G04 ================== begin FILE IDENTIFICATION RECORD ==================*
G04 Layout Name:  12432-1.brd*
G04 Film Name:    TSILK*
G04 File Format:  Gerber RS274X*
G04 File Origin:  Cadence Allegro 16.2-S037*
G04 Origin Date:  Wed Oct 17 10:59:50 2012*
G04 *
G04 Layer:  VIA CLASS/FILMMASKTOP*
G04 Layer:  REF DES/ASSEMBLY_TOP*
G04 Layer:  PACKAGE GEOMETRY/SILKSCREEN_TOP*
G04 Layer:  DRAWING FORMAT/LAYER_PCB_STORY*
G04 Layer:  DRAWING FORMAT/LAYER_SILK_T*
G04 Layer:  BOARD GEOMETRY/SILKSCREEN_TOP*
G04 *
G04 Offset:    (0.00 0.00)*
G04 Mirror:    No*
G04 Mode:      Positive*
G04 Rotation:  0*
G04 FullContactRelief:  No*
G04 UndefLineWidth:     6.00*
G04 ================== end FILE IDENTIFICATION RECORD ====================*
%FSLAX35Y35*MOIN*%
%IR0*IPPOS*OFA0.00000B0.00000*MIA0B0*SFA1.00000B1.00000*%
%ADD10C,.01*%
%ADD11C,.02*%
%ADD12C,.012*%
%ADD13C,.013*%
%ADD14C,.015*%
%ADD15C,.016*%
%ADD16C,.019*%
%ADD17C,.0005*%
%ADD18C,.002*%
%ADD19C,.006*%
%ADD20C,.008*%
G75*
%LPD*%
G75*
G36*
G01X23443Y369717D02*
Y374717D01*
X20943Y372217D01*
X23443Y369717D01*
G37*
G36*
G01X26143Y781614D02*
X28143Y783614D01*
Y779614D01*
X26143Y781614D01*
G37*
G36*
G01X23443Y1353969D02*
Y1358969D01*
X20943Y1356469D01*
X23443Y1353969D01*
G37*
G36*
G01X26143Y1765866D02*
X28143Y1767866D01*
Y1763866D01*
X26143Y1765866D01*
G37*
G36*
G01X30368Y1932862D02*
X34418D01*
X30368Y1936912D01*
Y1932862D01*
G37*
G36*
G01X91885Y166146D02*
X94385Y163646D01*
Y168646D01*
X91885Y166146D01*
G37*
G36*
G01Y571658D02*
X94385Y569158D01*
Y574158D01*
X91885Y571658D01*
G37*
G36*
G01Y977170D02*
X94385Y974670D01*
Y979670D01*
X91885Y977170D01*
G37*
G36*
G01X89399Y1137250D02*
X100599D01*
Y1119800D01*
X89399D01*
Y1137250D01*
G37*
G36*
G01X91885Y1382682D02*
X94385Y1380182D01*
Y1385182D01*
X91885Y1382682D01*
G37*
G36*
G01Y1788194D02*
X94385Y1785694D01*
Y1790694D01*
X91885Y1788194D01*
G37*
G36*
G01X116755Y1489071D02*
Y1497071D01*
X107655D01*
Y1489071D01*
X116755D01*
G37*
G36*
G01X144336Y203932D02*
X141836Y206432D01*
Y201432D01*
X144336Y203932D01*
G37*
G36*
G01Y609444D02*
X141836Y611944D01*
Y606944D01*
X144336Y609444D01*
G37*
G36*
G01Y1014956D02*
X141836Y1017456D01*
Y1012456D01*
X144336Y1014956D01*
G37*
G36*
G01X154099Y1214913D02*
X142899D01*
Y1232363D01*
X154099D01*
Y1214913D01*
G37*
G36*
G01X144336Y1420468D02*
X141836Y1422968D01*
Y1417968D01*
X144336Y1420468D01*
G37*
G36*
G01Y1825980D02*
X141836Y1828480D01*
Y1823480D01*
X144336Y1825980D01*
G37*
G36*
G01X172267Y537378D02*
Y545378D01*
X163167D01*
Y537378D01*
X172267D01*
G37*
G36*
G01X155299Y1292713D02*
Y1281513D01*
X172699D01*
Y1292713D01*
X155299D01*
G37*
G36*
G01X156299Y1715713D02*
Y1704513D01*
X173699D01*
Y1715713D01*
X156299D01*
G37*
G36*
G01X189599Y428850D02*
X178399D01*
Y446300D01*
X189599D01*
Y428850D01*
G37*
G36*
G01X172899Y1641813D02*
X184099D01*
Y1624363D01*
X172899D01*
Y1641813D01*
G37*
G36*
G01X196826Y86528D02*
Y82478D01*
X200876Y86528D01*
X196826D01*
G37*
G36*
G01X190299Y529713D02*
Y518513D01*
X207699D01*
Y529713D01*
X190299D01*
G37*
G36*
G01X214099Y827413D02*
X202899D01*
Y844863D01*
X214099D01*
Y827413D01*
G37*
G36*
G01X213799Y928213D02*
Y917013D01*
X231199D01*
Y928213D01*
X213799D01*
G37*
G36*
G01X231099Y1152250D02*
Y1141050D01*
X248499D01*
Y1152250D01*
X231099D01*
G37*
G36*
G01X269598Y311314D02*
X258398D01*
Y293914D01*
X269598D01*
Y311314D01*
G37*
G36*
G01X270099Y717750D02*
X258899D01*
Y700350D01*
X270099D01*
Y717750D01*
G37*
G36*
G01X268599Y1529250D02*
X257399D01*
Y1511850D01*
X268599D01*
Y1529250D01*
G37*
G36*
G01X271377Y1933391D02*
X260177D01*
Y1915991D01*
X271377D01*
Y1933391D01*
G37*
G36*
G01X284399Y367250D02*
X295599D01*
Y349800D01*
X284399D01*
Y367250D01*
G37*
G36*
G01X285399Y773750D02*
X296599D01*
Y756300D01*
X285399D01*
Y773750D01*
G37*
G36*
G01X284399Y1584750D02*
X295599D01*
Y1567300D01*
X284399D01*
Y1584750D01*
G37*
G36*
G01X284177Y1977391D02*
X295377D01*
Y1959941D01*
X284177D01*
Y1977391D01*
G37*
G36*
G01X344799Y102150D02*
Y90950D01*
X362199D01*
Y102150D01*
X344799D01*
G37*
G36*
G01X360899Y37750D02*
X372099D01*
Y20300D01*
X360899D01*
Y37750D01*
G37*
G36*
G01X415049Y1095050D02*
Y1130450D01*
X416049D01*
Y1096050D01*
X631549D01*
Y1095050D01*
X415049D01*
G37*
G36*
G01X428500Y1182500D02*
Y1177500D01*
X448500D01*
Y1182500D01*
X428500D01*
G37*
G36*
G01X793578Y340724D02*
X782378D01*
Y358174D01*
X793578D01*
Y340724D01*
G37*
G36*
G01X792296Y741182D02*
X781096D01*
Y758632D01*
X792296D01*
Y741182D01*
G37*
G36*
G01X792433Y1142692D02*
X781233D01*
Y1160142D01*
X792433D01*
Y1142692D01*
G37*
G36*
G01X794927Y1547596D02*
X783727D01*
Y1565046D01*
X794927D01*
Y1547596D01*
G37*
G36*
G01X792414Y1953513D02*
X781214D01*
Y1970963D01*
X792414D01*
Y1953513D01*
G37*
G36*
G01X807273Y291271D02*
X818473D01*
Y308671D01*
X807273D01*
Y291271D01*
G37*
G36*
G01X805231Y695653D02*
X816431D01*
Y713053D01*
X805231D01*
Y695653D01*
G37*
G36*
G01X805241Y1100016D02*
X816441D01*
Y1117416D01*
X805241D01*
Y1100016D01*
G37*
G36*
G01X806645Y1502522D02*
X817845D01*
Y1519922D01*
X806645D01*
Y1502522D01*
G37*
G36*
G01X805836Y1909165D02*
X817036D01*
Y1926565D01*
X805836D01*
Y1909165D01*
G37*
G36*
G01X833723Y181039D02*
Y189039D01*
X824623D01*
Y181039D01*
X833723D01*
G37*
G36*
G01Y1803087D02*
Y1811087D01*
X824623D01*
Y1803087D01*
X833723D01*
G37*
G36*
G01X872682Y203932D02*
X870182Y206432D01*
Y201432D01*
X872682Y203932D01*
G37*
G36*
G01Y609444D02*
X870182Y611944D01*
Y606944D01*
X872682Y609444D01*
G37*
G36*
G01Y1014956D02*
X870182Y1017456D01*
Y1012456D01*
X872682Y1014956D01*
G37*
G36*
G01Y1420468D02*
X870182Y1422968D01*
Y1417968D01*
X872682Y1420468D01*
G37*
G36*
G01X874750Y1711699D02*
X884750D01*
Y1706699D01*
X874750D01*
Y1711699D01*
G37*
G36*
G01X872682Y1825980D02*
X870182Y1828480D01*
Y1823480D01*
X872682Y1825980D01*
G37*
G36*
G01X914649Y99550D02*
Y95500D01*
X918699Y99550D01*
X914649D01*
G37*
G36*
G01X990391Y1621176D02*
X988391Y1619176D01*
Y1623176D01*
X990391Y1621176D01*
G37*
G54D10*
G01X1112204Y468621D02*
G03Y458149I0J-5236D01*
G01Y500117D02*
G03Y489644I0J-5236D01*
G01Y531612D02*
G03Y521139I0J-5236D01*
G01Y563107D02*
G03Y552634I0J-5236D01*
G01Y594602D02*
G03Y584129I0J-5237D01*
G01Y626097D02*
G03Y615625I0J-5236D01*
G54D20*
G01X16599Y1926550D02*
X17699D01*
G01X19299D02*
X20399D01*
G01X49199Y1969050D02*
X48099D01*
G01X51899D02*
X50799D01*
G01X105999Y1238050D02*
X101999D01*
G01X106499Y1270613D02*
X102499D01*
G01X104100Y1641500D02*
X100100D01*
G01X107499Y1676113D02*
X103499D01*
G01X107199Y1301113D02*
X106099D01*
G01X109899D02*
X108799D01*
G01X108699Y1705613D02*
X107599D01*
G01X111399D02*
X110299D01*
G01X136300Y457800D02*
X132300D01*
G01X141499Y491613D02*
X137499D01*
G01X142699Y520613D02*
X141599D01*
G01X145399D02*
X144299D01*
G01X134600Y1177400D02*
X138600D01*
G01X164999Y855613D02*
X160999D01*
G01X164499Y889113D02*
X160499D01*
G01X165699Y919113D02*
X164599D01*
G01X182999Y94250D02*
Y93150D01*
G01Y96950D02*
Y95850D01*
G01X168399Y919113D02*
X167299D01*
G01X222298Y284114D02*
X223398D01*
G01X219598D02*
X220698D01*
G01X216998Y315114D02*
X220998D01*
G01X211598Y348114D02*
X215598D01*
G01X222299Y690550D02*
X223399D01*
G01X219599D02*
X220699D01*
G01X216499Y722050D02*
X220499D01*
G01X212599Y755050D02*
X216599D01*
G01X218300Y1087000D02*
X219400D01*
G01X215600D02*
X216700D01*
G01X215600Y1125000D02*
X219600D01*
G01X221799Y1500550D02*
X222899D01*
G01X219099D02*
X220199D01*
G01X215999Y1532050D02*
X219999D01*
G01X228614Y1894113D02*
X229714D01*
G01X225914D02*
X227014D01*
G01X216814Y1923113D02*
X220814D01*
G01X211600Y1959600D02*
X215600D01*
G01X239499Y77350D02*
Y78450D01*
G01Y74650D02*
Y75750D01*
G01X255200Y1537700D02*
X251200D01*
G01X291099Y26113D02*
X287099D01*
G01X295999Y59113D02*
X291999D01*
G01X296699Y89613D02*
X295599D01*
G01X299399D02*
X298299D01*
G01X758049Y1799634D02*
Y1812134D01*
G01X772049Y1799634D02*
X758049D01*
G01X772049Y1812134D02*
X754549D01*
G01X772049D02*
Y1799634D01*
G01X765049Y1809634D02*
X767549Y1812134D01*
G01X765049Y1809634D02*
X762549Y1812134D01*
G01X781049Y1816634D02*
X785049D01*
G01X786049D02*
X790049D01*
G01X854778Y277924D02*
X855878D01*
G01X852078D02*
X853178D01*
G01X856999Y309050D02*
X860999D01*
G01X862900Y342100D02*
X866900D01*
G01X853496Y678882D02*
X854596D01*
G01X850796D02*
X851896D01*
G01X853696Y709382D02*
X857696D01*
G01X860896Y743582D02*
X864896D01*
G01X853133Y1084392D02*
X854233D01*
G01X850433D02*
X851533D01*
G01X853333Y1114892D02*
X857333D01*
G01X860933Y1146392D02*
X864933D01*
G01X855127Y1489296D02*
X856227D01*
G01X852427D02*
X853527D01*
G01X855827Y1519796D02*
X859827D01*
G01X863700Y1549600D02*
X867700D01*
G01X855614Y1895113D02*
X856714D01*
G01X852914D02*
X854014D01*
G01X855314Y1925613D02*
X859314D01*
G01X862500Y1959400D02*
X866500D01*
G01X881401Y1693050D02*
Y1691950D01*
G01Y1695750D02*
Y1694650D01*
G01X903499Y114250D02*
Y113150D01*
G01Y116950D02*
Y115850D01*
G01X896800Y1707000D02*
X892800D01*
G01X893400Y1715400D02*
Y1714300D01*
G01Y1718100D02*
Y1717000D01*
G01X955499Y90350D02*
Y91450D01*
G01Y87650D02*
Y88750D01*
G01X968200Y1658500D02*
Y1662500D01*
G01Y1663500D02*
Y1667500D01*
G54D11*
G01X-87137Y-139897D02*
Y-107897D01*
G01X-75137Y-123897D02*
G02I-12000J0D01*
G01X-80287D02*
G02I-6850J0D01*
G01X-71137D02*
X-103137D01*
G01X-71137Y-139897D02*
Y-219897D01*
G01D02*
X1129963D01*
G01X-71137Y-175397D02*
X1129963D01*
G01X-71137Y-139897D02*
X1129963D01*
G01X35499Y1972550D02*
X40499D01*
G01X59699Y768050D02*
X76299D01*
G01X51499Y782550D02*
X56499D01*
G01X54568Y1970262D02*
X59568D01*
G01X63198Y204231D02*
Y211831D01*
G01Y609743D02*
Y617343D01*
G01Y1015255D02*
Y1022855D01*
G01Y1420767D02*
Y1428367D01*
G01Y1826279D02*
Y1833879D01*
G01X81068Y1970262D02*
X86068D01*
G01X72068D02*
X77068D01*
G01X63268D02*
X68268D01*
G01X84999Y1878350D02*
Y1861750D01*
G01Y1898850D02*
Y1882250D01*
G01X90068Y1970262D02*
X95068D01*
G01X125221Y101577D02*
X141821D01*
G01X119205Y1497371D02*
Y1505071D01*
G01X118400Y1591800D02*
Y1575200D01*
G01X146221Y101577D02*
X162821D01*
G01X131899Y1600650D02*
Y1595650D01*
G01X173023Y165847D02*
Y158247D01*
G01X174717Y545678D02*
Y553378D01*
G01X173023Y571359D02*
Y563759D01*
G01Y976871D02*
Y969271D01*
G01Y1382383D02*
Y1374783D01*
G01Y1787894D02*
Y1780294D01*
G01X235999Y36050D02*
Y31050D01*
G01Y45050D02*
Y40050D01*
G01Y54050D02*
Y49050D01*
G01Y72050D02*
Y67050D01*
G01Y63050D02*
Y58050D01*
G01X243499Y86050D02*
X238499D01*
G01X342463Y-139897D02*
Y-219897D01*
G01X396999Y1300050D02*
X635999D01*
Y1230550D01*
X393499D01*
Y1300050D01*
X396999D01*
G01X479963Y-139897D02*
Y-219897D01*
G01X594963Y-139897D02*
Y-219897D01*
G01X670549Y1817834D02*
X662549D01*
G01X758049Y1812134D02*
X750049D01*
G01X762463Y-139897D02*
Y-219897D01*
G01X836173Y189339D02*
Y197039D01*
G01Y1811387D02*
Y1819087D01*
G01X853699Y108550D02*
X870299D01*
G01X874199D02*
X890799D01*
G01X872000Y1706899D02*
Y1699899D01*
G01X901369Y165847D02*
Y158247D01*
G01Y571359D02*
Y563759D01*
G01Y976871D02*
Y969271D01*
G01Y1382383D02*
Y1374783D01*
G01Y1787894D02*
Y1780294D01*
G01X932463Y-139897D02*
Y-219897D01*
G01X954999Y48550D02*
Y43550D01*
G01Y57550D02*
Y52550D01*
G01Y66550D02*
Y61550D01*
G01Y75550D02*
Y70550D01*
G01Y84550D02*
Y79550D01*
G01X952999Y104050D02*
Y99050D01*
G01X1129963Y-139897D02*
Y-219897D01*
G01X1157963Y-123897D02*
G02I-12000J0D01*
G01X1152813D02*
G02I-6850J0D01*
G01X1161963D02*
X1129963D01*
G01X1145963Y-139897D02*
Y-107897D01*
G54D12*
G01X0Y41772D02*
Y17214D01*
G01Y191667D02*
Y167110D01*
G01Y332003D02*
Y308383D01*
G01Y753542D02*
Y724169D01*
G01Y933234D02*
Y905988D01*
G01Y1129921D02*
Y1106301D01*
G01Y1309889D02*
Y1280567D01*
G01Y1738015D02*
Y1707948D01*
G01Y1912843D02*
Y1889223D01*
G01Y1986547D02*
Y1962927D01*
G01X66748Y12647D02*
G02Y21447I0J4400D01*
G01D02*
X71048D01*
G01D02*
G02Y12647I0J-4400D01*
G01D02*
X66748D01*
G01Y185875D02*
G02Y194675I0J4400D01*
G01D02*
X71048D01*
G01D02*
G02Y185875I0J-4400D01*
G01D02*
X66748D01*
G01Y418159D02*
G02Y426959I0J4400D01*
G01D02*
X71048D01*
G01D02*
G02Y418159I0J-4400D01*
G01D02*
X66748D01*
G01Y591387D02*
G02Y600187I0J4400D01*
G01D02*
X71048D01*
G01D02*
G02Y591387I0J-4400D01*
G01D02*
X66748D01*
G01Y823671D02*
G02Y832471I0J4400D01*
G01D02*
X71048D01*
G01D02*
G02Y823671I0J-4400D01*
G01D02*
X66748D01*
G01Y996899D02*
G02Y1005699I0J4400D01*
G01X71048D02*
G02Y996899I0J-4400D01*
G01D02*
X66748D01*
G01Y1005699D02*
X71048D01*
G01X66748Y1229183D02*
G02Y1237983I0J4400D01*
G01X71048D02*
G02Y1229183I0J-4400D01*
G01D02*
X66748D01*
G01Y1237983D02*
X71048D01*
G01X66748Y1402411D02*
G02Y1411211I0J4400D01*
G01X71048D02*
G02Y1402411I0J-4400D01*
G01D02*
X66748D01*
G01Y1411211D02*
X71048D01*
G01X66748Y1634695D02*
G02Y1643495I0J4400D01*
G01X71048D02*
G02Y1634695I0J-4400D01*
G01D02*
X66748D01*
G01Y1643495D02*
X71048D01*
G01X66748Y1807923D02*
G02Y1816723I0J4400D01*
G01X71048D02*
G02Y1807923I0J-4400D01*
G01D02*
X66748D01*
G01Y1816723D02*
X71048D01*
G01X169473Y175403D02*
X165173D01*
G01D02*
G02Y184203I0J4400D01*
G01D02*
X169473D01*
G01Y348631D02*
X165173D01*
G01D02*
G02Y357431I0J4400D01*
G01D02*
X169473D01*
G01Y580915D02*
X165173D01*
G01D02*
G02Y589715I0J4400D01*
G01D02*
X169473D01*
G01Y754143D02*
X165173D01*
G01D02*
G02Y762943I0J4400D01*
G01D02*
X169473D01*
G01Y986427D02*
X165173D01*
G01D02*
G02Y995227I0J4400D01*
G01D02*
X169473D01*
G01Y1159655D02*
X165173D01*
G01D02*
G02Y1168455I0J4400D01*
G01D02*
X169473D01*
G01Y1391939D02*
X165173D01*
G01D02*
G02Y1400739I0J4400D01*
G01D02*
X169473D01*
G01Y1565167D02*
X165173D01*
G01D02*
G02Y1573967I0J4400D01*
G01D02*
X169473D01*
G01Y1797451D02*
X165173D01*
G01D02*
G02Y1806251I0J4400D01*
G01D02*
X169473D01*
G01Y1970679D02*
X165173D01*
G01D02*
G02Y1979479I0J4400D01*
G01D02*
X169473D01*
G01Y184203D02*
G02Y175403I0J-4400D01*
G01Y357431D02*
G02Y348631I0J-4400D01*
G01Y589715D02*
G02Y580915I0J-4400D01*
G01Y762943D02*
G02Y754143I0J-4400D01*
G01Y995227D02*
G02Y986427I0J-4400D01*
G01Y1168455D02*
G02Y1159655I0J-4400D01*
G01Y1400739D02*
G02Y1391939I0J-4400D01*
G01Y1573967D02*
G02Y1565167I0J-4400D01*
G01Y1806251D02*
G02Y1797451I0J-4400D01*
G01Y1979479D02*
G02Y1970679I0J-4400D01*
G01X897819Y184203D02*
G02Y175403I0J-4400D01*
G01D02*
X893519D01*
G01D02*
G02Y184203I0J4400D01*
G01D02*
X897819D01*
G01Y357431D02*
G02Y348631I0J-4400D01*
G01D02*
X893519D01*
G01D02*
G02Y357431I0J4400D01*
G01D02*
X897819D01*
G01Y589715D02*
G02Y580915I0J-4400D01*
G01D02*
X893519D01*
G01D02*
G02Y589715I0J4400D01*
G01D02*
X897819D01*
G01Y762943D02*
G02Y754143I0J-4400D01*
G01D02*
X893519D01*
G01D02*
G02Y762943I0J4400D01*
G01D02*
X897819D01*
G01Y995227D02*
G02Y986427I0J-4400D01*
G01D02*
X893519D01*
G01D02*
G02Y995227I0J4400D01*
G01D02*
X897819D01*
G01Y1168455D02*
G02Y1159655I0J-4400D01*
G01D02*
X893519D01*
G01D02*
G02Y1168455I0J4400D01*
G01D02*
X897819D01*
G01Y1400739D02*
G02Y1391939I0J-4400D01*
G01D02*
X893519D01*
G01D02*
G02Y1400739I0J4400D01*
G01D02*
X897819D01*
G01Y1573967D02*
G02Y1565167I0J-4400D01*
G01D02*
X893519D01*
G01D02*
G02Y1573967I0J4400D01*
G01D02*
X897819D01*
G01Y1806251D02*
G02Y1797451I0J-4400D01*
G01D02*
X893519D01*
G01D02*
G02Y1806251I0J4400D01*
G01D02*
X897819D01*
G01Y1979479D02*
G02Y1970679I0J-4400D01*
G01D02*
X893519D01*
G01D02*
G02Y1979479I0J4400D01*
G01D02*
X897819D01*
G01X1033464Y48297D02*
Y24677D01*
G01X1033465Y240964D02*
Y217344D01*
G01Y468660D02*
Y445040D01*
G01Y721094D02*
Y697474D01*
G01Y721094D02*
Y697474D01*
G01Y1020472D02*
Y996852D01*
G01Y1367680D02*
Y1344060D01*
G01Y1763340D02*
Y1739720D01*
G01X1033464Y1982862D02*
Y1959242D01*
G54D13*
G01X17199Y1058550D02*
Y1062950D01*
X20699D01*
G01X38799Y210400D02*
Y214800D01*
X42299D01*
G01X20993Y373767D02*
Y370217D01*
G01X26193Y780840D02*
Y782340D01*
G01X20993Y1358019D02*
Y1354469D01*
G01X26193Y1765092D02*
Y1766592D01*
G01X56799Y1845100D02*
Y1849500D01*
X60299D01*
G01X77699Y649400D02*
Y645000D01*
X74199D01*
G01X91948Y164261D02*
Y168061D01*
G01Y569773D02*
Y573573D01*
G01Y975285D02*
Y979085D01*
G01Y1380797D02*
Y1384597D01*
G01Y1786309D02*
Y1790109D01*
G01X109399Y1075450D02*
X106549D01*
Y1078150D01*
G01X120099Y1093950D02*
Y1091100D01*
X117399D01*
G01X106899Y1206513D02*
X104049D01*
Y1209213D01*
G01X120099Y1315650D02*
X122949D01*
Y1312950D01*
G01X113399Y1720150D02*
Y1723000D01*
X116099D01*
G01X144273Y205817D02*
Y202017D01*
G01X145399Y423013D02*
X142549D01*
Y425713D01*
G01X144273Y611329D02*
Y607529D01*
G01Y1016841D02*
Y1013041D01*
G01X140899Y1349050D02*
Y1344650D01*
X137399D01*
G01X144273Y1422353D02*
Y1418553D01*
G01X132899Y1710950D02*
X130049D01*
Y1713650D01*
G01X144273Y1827865D02*
Y1824065D01*
G01X167399Y816513D02*
X164549D01*
Y819213D01*
G01X173149Y490953D02*
Y493803D01*
X175849D01*
G01X197199Y158700D02*
Y154300D01*
X193699D01*
G01X197199Y565900D02*
Y561500D01*
X193699D01*
G01X208599Y895650D02*
X211449D01*
Y892950D01*
G01X197199Y969600D02*
Y965200D01*
X193699D01*
G01X211699Y1374300D02*
Y1369900D01*
X208199D01*
G01X197699Y1780000D02*
Y1775600D01*
X194199D01*
G01X284099Y337650D02*
X286949D01*
Y334950D01*
G01X285099Y744150D02*
X287949D01*
Y741450D01*
G01X284099Y1555150D02*
X286949D01*
Y1552450D01*
G01X288749Y1946550D02*
X291599D01*
Y1943850D01*
G01X325598Y334014D02*
Y331164D01*
X322898D01*
G01X327099Y740950D02*
Y738100D01*
X324399D01*
G01X323599Y1554450D02*
Y1551600D01*
X320899D01*
G01X330821Y1944309D02*
Y1941459D01*
X328121D01*
G01X343899Y67150D02*
Y70000D01*
X346599D01*
G01X383899Y56150D02*
Y59000D01*
X386599D01*
G01X771578Y323824D02*
Y320974D01*
X768878D01*
G01X770796Y724782D02*
Y721932D01*
X768096D01*
G01X770933Y1126292D02*
Y1123442D01*
X768233D01*
G01X773927Y1531196D02*
Y1528346D01*
X771227D01*
G01X770414Y1937113D02*
Y1934263D01*
X767714D01*
G01X790599Y331650D02*
X793449D01*
Y328950D01*
G01X790099Y732650D02*
X792949D01*
Y729950D01*
G01X789599Y1135650D02*
X792449D01*
Y1132950D01*
G01X792853Y1539478D02*
X795703D01*
Y1536778D01*
G01X791099Y1946150D02*
X793949D01*
Y1943450D01*
G01X852799Y1365300D02*
Y1369700D01*
X856299D01*
G01X872619Y205817D02*
Y202017D01*
G01Y611329D02*
Y607529D01*
G01Y1016841D02*
Y1013041D01*
G01Y1422353D02*
Y1418553D01*
G01Y1827865D02*
Y1824065D01*
G01X925699Y564400D02*
Y560000D01*
X922199D01*
G01X925699Y968600D02*
Y964200D01*
X922199D01*
G01X925199Y1778500D02*
Y1774100D01*
X921699D01*
G01X943199Y165200D02*
Y160800D01*
X939699D01*
G01X990341Y1621876D02*
Y1620376D01*
G54D14*
G01X153649Y1273563D02*
Y1281313D01*
G01X154649Y1696563D02*
Y1704313D01*
G01X188649Y510563D02*
Y518313D01*
G01X212149Y909063D02*
Y916813D01*
G01X229449Y1133100D02*
Y1140850D01*
G01X250448Y312964D02*
X258198D01*
G01X250949Y719400D02*
X258699D01*
G01X249449Y1530900D02*
X257199D01*
G01X252227Y1935041D02*
X259977D01*
G01X343149Y83000D02*
Y90750D01*
G01X826423Y289621D02*
X818673D01*
G01X824381Y694003D02*
X816631D01*
G01X824391Y1098366D02*
X816641D01*
G01X825795Y1500872D02*
X818045D01*
G01X824986Y1907515D02*
X817236D01*
G54D15*
G01X108499Y1118250D02*
X100799D01*
G01X134999Y1233913D02*
X142699D01*
G01X170499Y447850D02*
X178199D01*
G01X191999Y1622813D02*
X184299D01*
G01X194999Y846413D02*
X202699D01*
G01X303499Y348250D02*
X295799D01*
G01X304499Y754750D02*
X296799D01*
G01X303499Y1565750D02*
X295799D01*
G01X303277Y1958391D02*
X295577D01*
G01X379999Y18750D02*
X372299D01*
G01X774478Y359724D02*
X782178D01*
G01X773196Y760182D02*
X780896D01*
G01X773333Y1161692D02*
X781033D01*
G01X775827Y1566596D02*
X783527D01*
G01X773314Y1972513D02*
X781014D01*
G54D16*
G01X115799Y1104200D02*
X112399D01*
G01X120999Y1221113D02*
X124399D01*
G01X138500Y548000D02*
Y551400D01*
G01X149700Y1322100D02*
X146300D01*
G01X155999Y440613D02*
X159399D01*
G01X179499Y839113D02*
X182899D01*
G01X178900Y934800D02*
Y938200D01*
G01X177699Y1655427D02*
X181099D01*
G01X169800Y1676100D02*
Y1679500D01*
G01X215800Y1885400D02*
X219200D01*
G01X239600Y272800D02*
Y276200D01*
G01X239000Y680200D02*
Y683600D01*
G01X244300Y1066560D02*
X240900D01*
G01X231300Y1480800D02*
X234700D01*
G01X313499Y350050D02*
Y353450D01*
G01X314499Y757050D02*
Y760450D01*
G01X313499Y1567550D02*
Y1570950D01*
G01X327100Y89900D02*
X323700D01*
G01X316640Y1956772D02*
Y1960172D01*
G01X396499Y34050D02*
X393099D01*
G01X758478Y344424D02*
X761878D01*
G01X756696Y744882D02*
X760096D01*
G01X758499Y1149050D02*
X761899D01*
G01X759327Y1551296D02*
X762727D01*
G01X756814Y1957213D02*
X760214D01*
G01X812400Y272500D02*
X815800D01*
G01X810900Y675100D02*
X814300D01*
G01X810600Y1077900D02*
X814000D01*
G01X812400Y1485600D02*
X815800D01*
G01X813000Y1890000D02*
X816400D01*
G54D17*
G01X17211Y1060002D02*
Y1059899D01*
G01X17136Y1060077D02*
Y1059824D01*
G01X17061Y1060152D02*
Y1059749D01*
G01X16986Y1060227D02*
Y1059674D01*
G01X16911Y1060302D02*
Y1059599D01*
G01X16836Y1060377D02*
Y1059524D01*
G01X16761Y1060452D02*
Y1059449D01*
G01X16686Y1060527D02*
Y1059374D01*
G01X16611Y1060602D02*
Y1059299D01*
G01X16536Y1060677D02*
Y1059224D01*
G01X16461Y1060752D02*
Y1059149D01*
G01X16386Y1060827D02*
Y1059074D01*
G01X16311Y1060902D02*
Y1058999D01*
G01X16236Y1060977D02*
Y1058924D01*
G01X16152Y1058881D02*
X16169Y1061034D01*
G01X16126Y1061087D02*
X17264Y1059950D01*
G01D02*
X16124Y1058811D01*
G01Y1058870D02*
Y1061030D01*
G01Y1061086D02*
Y1058811D01*
G01X16199Y1061014D02*
Y1058886D01*
G01X16274Y1060939D02*
Y1058961D01*
G01X16349Y1060864D02*
Y1059036D01*
G01X16424Y1060789D02*
Y1059111D01*
G01X16499Y1060714D02*
Y1059186D01*
G01X16574Y1060639D02*
Y1059261D01*
G01X16649Y1060564D02*
Y1059336D01*
G01X16724Y1060489D02*
Y1059411D01*
G01X16799Y1060414D02*
Y1059486D01*
G01X16874Y1060339D02*
Y1059561D01*
G01X16949Y1060264D02*
Y1059636D01*
G01X17024Y1060189D02*
Y1059711D01*
G01X17099Y1060114D02*
Y1059786D01*
G01X17174Y1060039D02*
Y1059861D01*
G01X17249Y1059964D02*
Y1059936D01*
G01X38811Y211852D02*
Y211749D01*
G01X38736Y211927D02*
Y211674D01*
G01X38661Y212002D02*
Y211599D01*
G01X38586Y212077D02*
Y211524D01*
G01X38511Y212152D02*
Y211449D01*
G01X38436Y212227D02*
Y211374D01*
G01X38361Y212302D02*
Y211299D01*
G01X38286Y212377D02*
Y211224D01*
G01X38211Y212452D02*
Y211149D01*
G01X38136Y212527D02*
Y211074D01*
G01X38061Y212602D02*
Y210999D01*
G01X37986Y212677D02*
Y210924D01*
G01X37911Y212752D02*
Y210849D01*
G01X37836Y212827D02*
Y210774D01*
G01X37752Y210731D02*
X37769Y212884D01*
G01X37726Y212937D02*
X38864Y211800D01*
G01D02*
X37724Y210661D01*
G01Y210720D02*
Y212880D01*
G01Y212936D02*
Y210661D01*
G01X37799Y212864D02*
Y210736D01*
G01X37874Y212789D02*
Y210811D01*
G01X37949Y212714D02*
Y210886D01*
G01X38024Y212639D02*
Y210961D01*
G01X38099Y212564D02*
Y211036D01*
G01X38174Y212489D02*
Y211111D01*
G01X38249Y212414D02*
Y211186D01*
G01X38324Y212339D02*
Y211261D01*
G01X38399Y212264D02*
Y211336D01*
G01X38474Y212189D02*
Y211411D01*
G01X38549Y212114D02*
Y211486D01*
G01X38624Y212039D02*
Y211561D01*
G01X38699Y211964D02*
Y211636D01*
G01X38774Y211889D02*
Y211711D01*
G01X38849Y211814D02*
Y211786D01*
G01X56811Y1846552D02*
Y1846449D01*
G01X56736Y1846627D02*
Y1846374D01*
G01X56661Y1846702D02*
Y1846299D01*
G01X56586Y1846777D02*
Y1846224D01*
G01X56511Y1846852D02*
Y1846149D01*
G01X56436Y1846927D02*
Y1846074D01*
G01X56361Y1847002D02*
Y1845999D01*
G01X56286Y1847077D02*
Y1845924D01*
G01X56211Y1847152D02*
Y1845849D01*
G01X56136Y1847227D02*
Y1845774D01*
G01X56061Y1847302D02*
Y1845699D01*
G01X55986Y1847377D02*
Y1845624D01*
G01X55911Y1847452D02*
Y1845549D01*
G01X55836Y1847527D02*
Y1845474D01*
G01X55752Y1845431D02*
X55769Y1847584D01*
G01X55726Y1847637D02*
X56864Y1846500D01*
G01D02*
X55724Y1845361D01*
G01Y1845420D02*
Y1847580D01*
G01Y1847636D02*
Y1845361D01*
G01X55799Y1847564D02*
Y1845436D01*
G01X55874Y1847489D02*
Y1845511D01*
G01X55949Y1847414D02*
Y1845586D01*
G01X56024Y1847339D02*
Y1845661D01*
G01X56099Y1847264D02*
Y1845736D01*
G01X56174Y1847189D02*
Y1845811D01*
G01X56249Y1847114D02*
Y1845886D01*
G01X56324Y1847039D02*
Y1845961D01*
G01X56399Y1846964D02*
Y1846036D01*
G01X56474Y1846889D02*
Y1846111D01*
G01X56549Y1846814D02*
Y1846186D01*
G01X56624Y1846739D02*
Y1846261D01*
G01X56699Y1846664D02*
Y1846336D01*
G01X56774Y1846589D02*
Y1846411D01*
G01X56849Y1846514D02*
Y1846486D01*
G01X77687Y647948D02*
Y648051D01*
G01X77762Y647873D02*
Y648126D01*
G01X77837Y647798D02*
Y648201D01*
G01X77912Y647723D02*
Y648276D01*
G01X77987Y647648D02*
Y648351D01*
G01X78062Y647573D02*
Y648426D01*
G01X78137Y647498D02*
Y648501D01*
G01X78212Y647423D02*
Y648576D01*
G01X78287Y647348D02*
Y648651D01*
G01X78362Y647273D02*
Y648726D01*
G01X78437Y647198D02*
Y648801D01*
G01X78512Y647123D02*
Y648876D01*
G01X78587Y647048D02*
Y648951D01*
G01X78662Y646973D02*
Y649026D01*
G01X78746Y649069D02*
X78729Y646916D01*
G01X78772Y646863D02*
X77634Y648000D01*
G01D02*
X78774Y649139D01*
G01Y649080D02*
Y646920D01*
G01Y646864D02*
Y649139D01*
G01X78699Y646936D02*
Y649064D01*
G01X78624Y647011D02*
Y648989D01*
G01X78549Y647086D02*
Y648914D01*
G01X78474Y647161D02*
Y648839D01*
G01X78399Y647236D02*
Y648764D01*
G01X78324Y647311D02*
Y648689D01*
G01X78249Y647386D02*
Y648614D01*
G01X78174Y647461D02*
Y648539D01*
G01X78099Y647536D02*
Y648464D01*
G01X78024Y647611D02*
Y648389D01*
G01X77949Y647686D02*
Y648314D01*
G01X77874Y647761D02*
Y648239D01*
G01X77799Y647836D02*
Y648164D01*
G01X77724Y647911D02*
Y648089D01*
G01X77649Y647986D02*
Y648014D01*
G01X140887Y1347598D02*
Y1347701D01*
G01X140962Y1347523D02*
Y1347776D01*
G01X141037Y1347448D02*
Y1347851D01*
G01X141112Y1347373D02*
Y1347926D01*
G01X141187Y1347298D02*
Y1348001D01*
G01X141262Y1347223D02*
Y1348076D01*
G01X141337Y1347148D02*
Y1348151D01*
G01X141412Y1347073D02*
Y1348226D01*
G01X141487Y1346998D02*
Y1348301D01*
G01X141562Y1346923D02*
Y1348376D01*
G01X141637Y1346848D02*
Y1348451D01*
G01X141712Y1346773D02*
Y1348526D01*
G01X141787Y1346698D02*
Y1348601D01*
G01X141862Y1346623D02*
Y1348676D01*
G01X141946Y1348719D02*
X141929Y1346566D01*
G01X141972Y1346513D02*
X140834Y1347650D01*
G01D02*
X141974Y1348789D01*
G01Y1348730D02*
Y1346570D01*
G01Y1346514D02*
Y1348789D01*
G01X141899Y1346586D02*
Y1348714D01*
G01X141824Y1346661D02*
Y1348639D01*
G01X141749Y1346736D02*
Y1348564D01*
G01X141674Y1346811D02*
Y1348489D01*
G01X141599Y1346886D02*
Y1348414D01*
G01X141524Y1346961D02*
Y1348339D01*
G01X141449Y1347036D02*
Y1348264D01*
G01X141374Y1347111D02*
Y1348189D01*
G01X141299Y1347186D02*
Y1348114D01*
G01X141224Y1347261D02*
Y1348039D01*
G01X141149Y1347336D02*
Y1347964D01*
G01X141074Y1347411D02*
Y1347889D01*
G01X140999Y1347486D02*
Y1347814D01*
G01X140924Y1347561D02*
Y1347739D01*
G01X140849Y1347636D02*
Y1347664D01*
G01X197187Y157248D02*
Y157351D01*
G01X197262Y157173D02*
Y157426D01*
G01X197337Y157098D02*
Y157501D01*
G01X197412Y157023D02*
Y157576D01*
G01X197487Y156948D02*
Y157651D01*
G01X197562Y156873D02*
Y157726D01*
G01X197637Y156798D02*
Y157801D01*
G01X197712Y156723D02*
Y157876D01*
G01X197787Y156648D02*
Y157951D01*
G01X197862Y156573D02*
Y158026D01*
G01X197937Y156498D02*
Y158101D01*
G01X198012Y156423D02*
Y158176D01*
G01X198087Y156348D02*
Y158251D01*
G01X198162Y156273D02*
Y158326D01*
G01X198246Y158369D02*
X198229Y156216D01*
G01X198272Y156163D02*
X197134Y157300D01*
G01D02*
X198274Y158439D01*
G01Y158380D02*
Y156220D01*
G01Y156164D02*
Y158439D01*
G01X198199Y156236D02*
Y158364D01*
G01X198124Y156311D02*
Y158289D01*
G01X198049Y156386D02*
Y158214D01*
G01X197974Y156461D02*
Y158139D01*
G01X197899Y156536D02*
Y158064D01*
G01X197824Y156611D02*
Y157989D01*
G01X197749Y156686D02*
Y157914D01*
G01X197674Y156761D02*
Y157839D01*
G01X197599Y156836D02*
Y157764D01*
G01X197524Y156911D02*
Y157689D01*
G01X197449Y156986D02*
Y157614D01*
G01X197374Y157061D02*
Y157539D01*
G01X197299Y157136D02*
Y157464D01*
G01X197224Y157211D02*
Y157389D01*
G01X197149Y157286D02*
Y157314D01*
G01X197187Y564448D02*
Y564551D01*
G01X197262Y564373D02*
Y564626D01*
G01X197337Y564298D02*
Y564701D01*
G01X197412Y564223D02*
Y564776D01*
G01X197487Y564148D02*
Y564851D01*
G01X197562Y564073D02*
Y564926D01*
G01X197637Y563998D02*
Y565001D01*
G01X197712Y563923D02*
Y565076D01*
G01X197787Y563848D02*
Y565151D01*
G01X197862Y563773D02*
Y565226D01*
G01X197937Y563698D02*
Y565301D01*
G01X198012Y563623D02*
Y565376D01*
G01X198087Y563548D02*
Y565451D01*
G01X198162Y563473D02*
Y565526D01*
G01X198246Y565569D02*
X198229Y563416D01*
G01X198272Y563363D02*
X197134Y564500D01*
G01D02*
X198274Y565639D01*
G01Y565580D02*
Y563420D01*
G01Y563364D02*
Y565639D01*
G01X198199Y563436D02*
Y565564D01*
G01X198124Y563511D02*
Y565489D01*
G01X198049Y563586D02*
Y565414D01*
G01X197974Y563661D02*
Y565339D01*
G01X197899Y563736D02*
Y565264D01*
G01X197824Y563811D02*
Y565189D01*
G01X197749Y563886D02*
Y565114D01*
G01X197674Y563961D02*
Y565039D01*
G01X197599Y564036D02*
Y564964D01*
G01X197524Y564111D02*
Y564889D01*
G01X197449Y564186D02*
Y564814D01*
G01X197374Y564261D02*
Y564739D01*
G01X197299Y564336D02*
Y564664D01*
G01X197224Y564411D02*
Y564589D01*
G01X197149Y564486D02*
Y564514D01*
G01X197187Y968148D02*
Y968251D01*
G01X197262Y968073D02*
Y968326D01*
G01X197337Y967998D02*
Y968401D01*
G01X197412Y967923D02*
Y968476D01*
G01X197487Y967848D02*
Y968551D01*
G01X197562Y967773D02*
Y968626D01*
G01X197637Y967698D02*
Y968701D01*
G01X197712Y967623D02*
Y968776D01*
G01X197787Y967548D02*
Y968851D01*
G01X197862Y967473D02*
Y968926D01*
G01X197937Y967398D02*
Y969001D01*
G01X198012Y967323D02*
Y969076D01*
G01X198087Y967248D02*
Y969151D01*
G01X198162Y967173D02*
Y969226D01*
G01X198246Y969269D02*
X198229Y967116D01*
G01X198272Y967063D02*
X197134Y968200D01*
G01D02*
X198274Y969339D01*
G01Y969280D02*
Y967120D01*
G01Y967064D02*
Y969339D01*
G01X198199Y967136D02*
Y969264D01*
G01X198124Y967211D02*
Y969189D01*
G01X198049Y967286D02*
Y969114D01*
G01X197974Y967361D02*
Y969039D01*
G01X197899Y967436D02*
Y968964D01*
G01X197824Y967511D02*
Y968889D01*
G01X197749Y967586D02*
Y968814D01*
G01X197674Y967661D02*
Y968739D01*
G01X197599Y967736D02*
Y968664D01*
G01X197524Y967811D02*
Y968589D01*
G01X197449Y967886D02*
Y968514D01*
G01X197374Y967961D02*
Y968439D01*
G01X197299Y968036D02*
Y968364D01*
G01X197224Y968111D02*
Y968289D01*
G01X197149Y968186D02*
Y968214D01*
G01X197687Y1778548D02*
Y1778651D01*
G01X197762Y1778473D02*
Y1778726D01*
G01X197837Y1778398D02*
Y1778801D01*
G01X197912Y1778323D02*
Y1778876D01*
G01X197987Y1778248D02*
Y1778951D01*
G01X198062Y1778173D02*
Y1779026D01*
G01X198137Y1778098D02*
Y1779101D01*
G01X198212Y1778023D02*
Y1779176D01*
G01X198287Y1777948D02*
Y1779251D01*
G01X198362Y1777873D02*
Y1779326D01*
G01X198437Y1777798D02*
Y1779401D01*
G01X198512Y1777723D02*
Y1779476D01*
G01X198587Y1777648D02*
Y1779551D01*
G01X198662Y1777573D02*
Y1779626D01*
G01X198746Y1779669D02*
X198729Y1777516D01*
G01X198772Y1777463D02*
X197634Y1778600D01*
G01D02*
X198774Y1779739D01*
G01Y1779680D02*
Y1777520D01*
G01Y1777464D02*
Y1779739D01*
G01X198699Y1777536D02*
Y1779664D01*
G01X198624Y1777611D02*
Y1779589D01*
G01X198549Y1777686D02*
Y1779514D01*
G01X198474Y1777761D02*
Y1779439D01*
G01X198399Y1777836D02*
Y1779364D01*
G01X198324Y1777911D02*
Y1779289D01*
G01X198249Y1777986D02*
Y1779214D01*
G01X198174Y1778061D02*
Y1779139D01*
G01X198099Y1778136D02*
Y1779064D01*
G01X198024Y1778211D02*
Y1778989D01*
G01X197949Y1778286D02*
Y1778914D01*
G01X197874Y1778361D02*
Y1778839D01*
G01X197799Y1778436D02*
Y1778764D01*
G01X197724Y1778511D02*
Y1778689D01*
G01X197649Y1778586D02*
Y1778614D01*
G01X211687Y1372848D02*
Y1372951D01*
G01X211762Y1372773D02*
Y1373026D01*
G01X211837Y1372698D02*
Y1373101D01*
G01X211912Y1372623D02*
Y1373176D01*
G01X211987Y1372548D02*
Y1373251D01*
G01X212062Y1372473D02*
Y1373326D01*
G01X212137Y1372398D02*
Y1373401D01*
G01X212212Y1372323D02*
Y1373476D01*
G01X212287Y1372248D02*
Y1373551D01*
G01X212362Y1372173D02*
Y1373626D01*
G01X212437Y1372098D02*
Y1373701D01*
G01X212512Y1372023D02*
Y1373776D01*
G01X212587Y1371948D02*
Y1373851D01*
G01X212662Y1371873D02*
Y1373926D01*
G01X212746Y1373969D02*
X212729Y1371816D01*
G01X212772Y1371763D02*
X211634Y1372900D01*
G01D02*
X212774Y1374039D01*
G01Y1373980D02*
Y1371820D01*
G01Y1371764D02*
Y1374039D01*
G01X212699Y1371836D02*
Y1373964D01*
G01X212624Y1371911D02*
Y1373889D01*
G01X212549Y1371986D02*
Y1373814D01*
G01X212474Y1372061D02*
Y1373739D01*
G01X212399Y1372136D02*
Y1373664D01*
G01X212324Y1372211D02*
Y1373589D01*
G01X212249Y1372286D02*
Y1373514D01*
G01X212174Y1372361D02*
Y1373439D01*
G01X212099Y1372436D02*
Y1373364D01*
G01X212024Y1372511D02*
Y1373289D01*
G01X211949Y1372586D02*
Y1373214D01*
G01X211874Y1372661D02*
Y1373139D01*
G01X211799Y1372736D02*
Y1373064D01*
G01X211724Y1372811D02*
Y1372989D01*
G01X211649Y1372886D02*
Y1372914D01*
G01X852811Y1366752D02*
Y1366649D01*
G01X852736Y1366827D02*
Y1366574D01*
G01X852661Y1366902D02*
Y1366499D01*
G01X852586Y1366977D02*
Y1366424D01*
G01X852511Y1367052D02*
Y1366349D01*
G01X852436Y1367127D02*
Y1366274D01*
G01X852361Y1367202D02*
Y1366199D01*
G01X852286Y1367277D02*
Y1366124D01*
G01X852211Y1367352D02*
Y1366049D01*
G01X852136Y1367427D02*
Y1365974D01*
G01X852061Y1367502D02*
Y1365899D01*
G01X851986Y1367577D02*
Y1365824D01*
G01X851911Y1367652D02*
Y1365749D01*
G01X851836Y1367727D02*
Y1365674D01*
G01X851752Y1365631D02*
X851769Y1367784D01*
G01X851726Y1367837D02*
X852864Y1366700D01*
G01D02*
X851724Y1365561D01*
G01Y1365620D02*
Y1367780D01*
G01Y1367836D02*
Y1365561D01*
G01X851799Y1367764D02*
Y1365636D01*
G01X851874Y1367689D02*
Y1365711D01*
G01X851949Y1367614D02*
Y1365786D01*
G01X852024Y1367539D02*
Y1365861D01*
G01X852099Y1367464D02*
Y1365936D01*
G01X852174Y1367389D02*
Y1366011D01*
G01X852249Y1367314D02*
Y1366086D01*
G01X852324Y1367239D02*
Y1366161D01*
G01X852399Y1367164D02*
Y1366236D01*
G01X852474Y1367089D02*
Y1366311D01*
G01X852549Y1367014D02*
Y1366386D01*
G01X852624Y1366939D02*
Y1366461D01*
G01X852699Y1366864D02*
Y1366536D01*
G01X852774Y1366789D02*
Y1366611D01*
G01X852849Y1366714D02*
Y1366686D01*
G01X925687Y562948D02*
Y563051D01*
G01X925762Y562873D02*
Y563126D01*
G01X925837Y562798D02*
Y563201D01*
G01X925912Y562723D02*
Y563276D01*
G01X925987Y562648D02*
Y563351D01*
G01X926062Y562573D02*
Y563426D01*
G01X926137Y562498D02*
Y563501D01*
G01X926212Y562423D02*
Y563576D01*
G01X926287Y562348D02*
Y563651D01*
G01X926362Y562273D02*
Y563726D01*
G01X926437Y562198D02*
Y563801D01*
G01X926512Y562123D02*
Y563876D01*
G01X926587Y562048D02*
Y563951D01*
G01X926662Y561973D02*
Y564026D01*
G01X926746Y564069D02*
X926729Y561916D01*
G01X926772Y561863D02*
X925634Y563000D01*
G01D02*
X926774Y564139D01*
G01Y564080D02*
Y561920D01*
G01Y561864D02*
Y564139D01*
G01X926699Y561936D02*
Y564064D01*
G01X926624Y562011D02*
Y563989D01*
G01X926549Y562086D02*
Y563914D01*
G01X926474Y562161D02*
Y563839D01*
G01X926399Y562236D02*
Y563764D01*
G01X926324Y562311D02*
Y563689D01*
G01X926249Y562386D02*
Y563614D01*
G01X926174Y562461D02*
Y563539D01*
G01X926099Y562536D02*
Y563464D01*
G01X926024Y562611D02*
Y563389D01*
G01X925949Y562686D02*
Y563314D01*
G01X925874Y562761D02*
Y563239D01*
G01X925799Y562836D02*
Y563164D01*
G01X925724Y562911D02*
Y563089D01*
G01X925649Y562986D02*
Y563014D01*
G01X925687Y967148D02*
Y967251D01*
G01X925762Y967073D02*
Y967326D01*
G01X925837Y966998D02*
Y967401D01*
G01X925912Y966923D02*
Y967476D01*
G01X925987Y966848D02*
Y967551D01*
G01X926062Y966773D02*
Y967626D01*
G01X926137Y966698D02*
Y967701D01*
G01X926212Y966623D02*
Y967776D01*
G01X926287Y966548D02*
Y967851D01*
G01X926362Y966473D02*
Y967926D01*
G01X926437Y966398D02*
Y968001D01*
G01X926512Y966323D02*
Y968076D01*
G01X926587Y966248D02*
Y968151D01*
G01X926662Y966173D02*
Y968226D01*
G01X926746Y968269D02*
X926729Y966116D01*
G01X926772Y966063D02*
X925634Y967200D01*
G01D02*
X926774Y968339D01*
G01Y968280D02*
Y966120D01*
G01Y966064D02*
Y968339D01*
G01X926699Y966136D02*
Y968264D01*
G01X926624Y966211D02*
Y968189D01*
G01X926549Y966286D02*
Y968114D01*
G01X926474Y966361D02*
Y968039D01*
G01X926399Y966436D02*
Y967964D01*
G01X926324Y966511D02*
Y967889D01*
G01X926249Y966586D02*
Y967814D01*
G01X926174Y966661D02*
Y967739D01*
G01X926099Y966736D02*
Y967664D01*
G01X926024Y966811D02*
Y967589D01*
G01X925949Y966886D02*
Y967514D01*
G01X925874Y966961D02*
Y967439D01*
G01X925799Y967036D02*
Y967364D01*
G01X925724Y967111D02*
Y967289D01*
G01X925649Y967186D02*
Y967214D01*
G01X925187Y1777048D02*
Y1777151D01*
G01X925262Y1776973D02*
Y1777226D01*
G01X925337Y1776898D02*
Y1777301D01*
G01X925412Y1776823D02*
Y1777376D01*
G01X925487Y1776748D02*
Y1777451D01*
G01X925562Y1776673D02*
Y1777526D01*
G01X925637Y1776598D02*
Y1777601D01*
G01X925712Y1776523D02*
Y1777676D01*
G01X925787Y1776448D02*
Y1777751D01*
G01X925862Y1776373D02*
Y1777826D01*
G01X925937Y1776298D02*
Y1777901D01*
G01X926012Y1776223D02*
Y1777976D01*
G01X926087Y1776148D02*
Y1778051D01*
G01X926162Y1776073D02*
Y1778126D01*
G01X926246Y1778169D02*
X926229Y1776016D01*
G01X926272Y1775963D02*
X925134Y1777100D01*
G01D02*
X926274Y1778239D01*
G01Y1778180D02*
Y1776020D01*
G01Y1775964D02*
Y1778239D01*
G01X926199Y1776036D02*
Y1778164D01*
G01X926124Y1776111D02*
Y1778089D01*
G01X926049Y1776186D02*
Y1778014D01*
G01X925974Y1776261D02*
Y1777939D01*
G01X925899Y1776336D02*
Y1777864D01*
G01X925824Y1776411D02*
Y1777789D01*
G01X925749Y1776486D02*
Y1777714D01*
G01X925674Y1776561D02*
Y1777639D01*
G01X925599Y1776636D02*
Y1777564D01*
G01X925524Y1776711D02*
Y1777489D01*
G01X925449Y1776786D02*
Y1777414D01*
G01X925374Y1776861D02*
Y1777339D01*
G01X925299Y1776936D02*
Y1777264D01*
G01X925224Y1777011D02*
Y1777189D01*
G01X925149Y1777086D02*
Y1777114D01*
G01X943187Y163748D02*
Y163851D01*
G01X943262Y163673D02*
Y163926D01*
G01X943337Y163598D02*
Y164001D01*
G01X943412Y163523D02*
Y164076D01*
G01X943487Y163448D02*
Y164151D01*
G01X943562Y163373D02*
Y164226D01*
G01X943637Y163298D02*
Y164301D01*
G01X943712Y163223D02*
Y164376D01*
G01X943787Y163148D02*
Y164451D01*
G01X943862Y163073D02*
Y164526D01*
G01X943937Y162998D02*
Y164601D01*
G01X944012Y162923D02*
Y164676D01*
G01X944087Y162848D02*
Y164751D01*
G01X944162Y162773D02*
Y164826D01*
G01X944246Y164869D02*
X944229Y162716D01*
G01X944272Y162663D02*
X943134Y163800D01*
G01D02*
X944274Y164939D01*
G01Y164880D02*
Y162720D01*
G01Y162664D02*
Y164939D01*
G01X944199Y162736D02*
Y164864D01*
G01X944124Y162811D02*
Y164789D01*
G01X944049Y162886D02*
Y164714D01*
G01X943974Y162961D02*
Y164639D01*
G01X943899Y163036D02*
Y164564D01*
G01X943824Y163111D02*
Y164489D01*
G01X943749Y163186D02*
Y164414D01*
G01X943674Y163261D02*
Y164339D01*
G01X943599Y163336D02*
Y164264D01*
G01X943524Y163411D02*
Y164189D01*
G01X943449Y163486D02*
Y164114D01*
G01X943374Y163561D02*
Y164039D01*
G01X943299Y163636D02*
Y163964D01*
G01X943224Y163711D02*
Y163889D01*
G01X943149Y163786D02*
Y163814D01*
G54D18*
G01X431670Y1187590D02*
X431010D01*
G01X431110Y1187680D02*
X431770D01*
G01X431860Y1187790D02*
X431210D01*
G01X431310Y1187880D02*
X431960D01*
G01X432060Y1187990D02*
X431400D01*
G01X431500Y1188090D02*
X432150D01*
G01X432250Y1188180D02*
X431600D01*
G01X431690Y1188290D02*
X432350D01*
G01X432440Y1188380D02*
X431790D01*
G01X431880Y1188490D02*
X432540D01*
G01X432640Y1188590D02*
X431980D01*
G01X432080Y1188680D02*
X432730D01*
G01X432830Y1188790D02*
X432185D01*
G01X432180D02*
X432230D01*
G01X432270Y1188880D02*
X432310D01*
G01X432270D02*
X432920D01*
G01X433020Y1188990D02*
X432370D01*
G01X432470Y1189090D02*
X433120D01*
G01X433220Y1189180D02*
X432560D01*
G01X432660Y1189290D02*
X433310D01*
G01X433410Y1189380D02*
X432750D01*
G01X432850Y1189490D02*
X433510D01*
G01X433600Y1189590D02*
X432950D01*
G01X433050Y1189680D02*
X433700D01*
G01X433790Y1189790D02*
X433140D01*
G01X433240Y1189880D02*
X433890D01*
G01X433990Y1189990D02*
X433330D01*
G01X433430Y1190090D02*
X434090D01*
G01X434180Y1190180D02*
X433530D01*
G01X433620Y1190290D02*
X434280D01*
G01X434470Y1190490D02*
X433820D01*
G01X434010Y1190680D02*
X434660D01*
G01X434680Y1198680D02*
X435120Y1193530D01*
G01X435130Y1193490D02*
X435600D01*
G01X435610Y1193290D02*
X435140D01*
G01X435160Y1193090D02*
X435630D01*
G01X435650Y1192880D02*
X435180D01*
G01X435200Y1192680D02*
X435670D01*
G01X435710Y1192590D02*
X435210D01*
G01X435220Y1191940D02*
X435120Y1191830D01*
G01X435250Y1192010D02*
X435220Y1191940D01*
G01X435070Y1191790D02*
X435760D01*
G01Y1191590D02*
X434880D01*
G01X434690Y1191380D02*
X435780D01*
G01X435140Y1191180D02*
X434490D01*
G01X434400Y1191090D02*
X435050D01*
G01X434950Y1190990D02*
X434300D01*
G01X434200Y1190880D02*
X434860D01*
G01X434760Y1190790D02*
X434110D01*
G01X433920Y1190590D02*
X434570D01*
G01X434370Y1190380D02*
X433720D01*
G01X435100Y1193790D02*
X435570D01*
G01X435550Y1193990D02*
X435090D01*
G01X435070Y1194180D02*
X435540D01*
G01X435530Y1194290D02*
X435060D01*
G01X435080Y1194090D02*
X435550D01*
G01X435560Y1193880D02*
X435090D01*
G01X435110Y1193680D02*
X435580D01*
G01X435590Y1193590D02*
X435120D01*
G01X435250Y1192070D02*
Y1192010D01*
G01X435120Y1193530D02*
X435250Y1192070D01*
G01X435240Y1191990D02*
X435920D01*
G01X435770Y1191810D02*
X435750Y1191740D01*
G01X435820Y1191890D02*
X435770Y1191810D01*
G01X435750Y1191680D02*
X434980D01*
G01X434790Y1191490D02*
X435770D01*
G01X435790Y1191180D02*
X435290D01*
G01X435260Y1191220D02*
X435160Y1191200D01*
G01X435530Y1188780D02*
X435640D01*
G01X435530Y1188790D02*
Y1188780D01*
G01X435330Y1191140D02*
X435530Y1188790D01*
G01X435260Y1191220D02*
X435330Y1191140D01*
G01X435630Y1188880D02*
X435520D01*
G01X435525D02*
X441120D01*
G01X441185Y1188790D02*
X435530D01*
G01X435770Y1187740D02*
X436660D01*
G01X435730Y1187780D02*
X435770Y1187740D01*
G01X435730Y1188460D02*
Y1187780D01*
G01X435700Y1188530D02*
X435730Y1188460D01*
G01X435550Y1188690D02*
X435700Y1188530D01*
G01X435540Y1188710D02*
X435550Y1188690D01*
G01X435530Y1188770D02*
X435540Y1188710D01*
G01X436700Y1187790D02*
X435730D01*
G01Y1187990D02*
X436700D01*
G01Y1188180D02*
X435730D01*
G01Y1188380D02*
X436700D01*
G01X435980Y1189090D02*
X435510D01*
G01X435490Y1189180D02*
X435960D01*
G01X435950Y1189380D02*
X435480D01*
G01X435460Y1189590D02*
X435930D01*
G01X435910Y1189790D02*
X435440D01*
G01X435430Y1189990D02*
X435900D01*
G01X435880Y1190180D02*
X435410D01*
G01X435390Y1190380D02*
X435860D01*
G01X435850Y1190590D02*
X435380D01*
G01X435360Y1190790D02*
X435830D01*
G01X435810Y1190990D02*
X435350D01*
G01X435240Y1192180D02*
X436110D01*
G01X436300Y1192380D02*
X435220D01*
G01X435190Y1192790D02*
X435660D01*
G01X435670Y1192640D02*
X435220Y1197930D01*
G01X435610Y1193380D02*
X435140D01*
G01X435150Y1193180D02*
X435620D01*
G01X435640Y1192990D02*
X435170D01*
G01X435740Y1192550D02*
X435840Y1192580D01*
G01X435670Y1192640D02*
X435740Y1192550D01*
G01X435650Y1188590D02*
X441430D01*
G01X435970Y1189160D02*
X435750Y1191740D01*
G01X435970Y1189090D02*
Y1189160D01*
G01X436070Y1189000D02*
X435970Y1189090D01*
G01X440170Y1189000D02*
X436070D01*
G01X435820Y1191880D02*
X435170D01*
G01X435250Y1192090D02*
X436010D01*
G01X435830Y1191890D02*
X435820D01*
G01X435830Y1191900D02*
Y1191890D01*
G01Y1191900D02*
X438420Y1194590D01*
G01X437390Y1194180D02*
X438040D01*
G01X437850Y1193990D02*
X437200D01*
G01X437010Y1193790D02*
X437650D01*
G01X437560Y1193680D02*
X436910D01*
G01X436960Y1193740D02*
X435840Y1192580D01*
G01X435850Y1192590D02*
X436490D01*
G01X436400Y1192490D02*
X435220D01*
G01X435230Y1192290D02*
X436210D01*
G01X435950Y1192680D02*
X436590D01*
G01X436690Y1192790D02*
X436050D01*
G01X436140Y1192880D02*
X436790D01*
G01X436880Y1192990D02*
X436240D01*
G01X436330Y1193090D02*
X436980D01*
G01X437070Y1193180D02*
X436430D01*
G01X436530Y1193290D02*
X437170D01*
G01X437270Y1193380D02*
X436620D01*
G01X436720Y1193490D02*
X437360D01*
G01X437460Y1193590D02*
X436810D01*
G01X435790Y1191290D02*
X434590D01*
G01X435330Y1191090D02*
X435800D01*
G01X435820Y1190880D02*
X435350D01*
G01X435370Y1190680D02*
X435840D01*
G01X435850Y1190490D02*
X435380D01*
G01X435400Y1190290D02*
X435870D01*
G01X435890Y1190090D02*
X435420D01*
G01X435440Y1189880D02*
X435900D01*
G01X435920Y1189680D02*
X435460D01*
G01X435470Y1189490D02*
X435940D01*
G01X435960Y1189290D02*
X435490D01*
G01X435720Y1188490D02*
X436770D01*
G01X436700Y1187780D02*
X436660Y1187740D01*
G01X436700Y1188420D02*
Y1187780D01*
G01X436800Y1188520D02*
X436700Y1188420D01*
G01Y1187880D02*
X435730D01*
G01Y1188090D02*
X436700D01*
G01Y1188290D02*
X435730D01*
G01X440270Y1189470D02*
Y1189480D01*
G01X440260Y1189400D02*
X440270Y1189470D01*
G01X440260Y1189140D02*
Y1189400D01*
G01X440270Y1189120D02*
X440260Y1189140D01*
G01X440170Y1189000D02*
X440270Y1189120D01*
G01Y1189490D02*
X441040D01*
G01X441000Y1189290D02*
X440260D01*
G01X440240Y1189090D02*
X441040D01*
G01X441580Y1192020D02*
X438880Y1194920D01*
G01X438120Y1194930D02*
X436960Y1193740D01*
G01X437110Y1193880D02*
X437750D01*
G01X437940Y1194090D02*
X437300D01*
G01X437490Y1194290D02*
X438140D01*
G01X438570Y1194590D02*
X440250Y1192770D01*
G01X440240Y1192790D02*
X440870D01*
G01X440680Y1192990D02*
X440050D01*
G01X439870Y1193180D02*
X440500D01*
G01X440310Y1193380D02*
X439680D01*
G01X439590Y1193490D02*
X440220D01*
G01X440120Y1193590D02*
X439490D01*
G01X439400Y1193680D02*
X440030D01*
G01X439940Y1193790D02*
X439310D01*
G01X439220Y1193880D02*
X439850D01*
G01X439750Y1193990D02*
X439120D01*
G01X439030Y1194090D02*
X439660D01*
G01X439570Y1194180D02*
X438940D01*
G01X438850Y1194290D02*
X439480D01*
G01X440400Y1193290D02*
X439770D01*
G01X439960Y1193090D02*
X440590D01*
G01X440770Y1192880D02*
X440140D01*
G01X440330Y1192680D02*
X440960D01*
G01X441050Y1192590D02*
X440420D01*
G01X440510Y1192490D02*
X441150D01*
G01X441240Y1192380D02*
X440610D01*
G01X440700Y1192290D02*
X441330D01*
G01X441520Y1192090D02*
X440890D01*
G01X441070Y1191880D02*
X442210D01*
G01X442200Y1191790D02*
X441170D01*
G01X440310Y1189660D02*
X440270Y1189480D01*
G01X440310Y1189670D02*
Y1189660D01*
G01X440420Y1189980D02*
X440310Y1189670D01*
G01X440430Y1189990D02*
X440420Y1189980D01*
G01X440640Y1190300D02*
X440430Y1189990D01*
G01X440650Y1190310D02*
X440640Y1190300D01*
G01X440890Y1190530D02*
X440650Y1190310D01*
G01X440900Y1190530D02*
X440890D01*
G01X441020Y1190610D02*
X440900Y1190530D01*
G01X441030Y1190620D02*
X441020Y1190610D01*
G01X441090Y1190650D02*
X441030Y1190620D01*
G01X441250Y1190720D02*
X441090Y1190650D01*
G01X440260Y1189380D02*
X441020D01*
G01X441060Y1188990D02*
X435510D01*
G01X441050Y1189010D02*
X441060Y1188990D01*
G01X441000Y1189270D02*
X441050Y1189010D01*
G01X441000Y1189280D02*
Y1189270D01*
G01Y1189300D02*
Y1189280D01*
G01X435550Y1188680D02*
X441290D01*
G01X441210Y1188750D02*
X441150Y1188840D01*
G01X441220Y1188740D02*
X441210Y1188750D01*
G01X441230Y1188730D02*
X441220Y1188740D01*
G01X441070Y1188980D02*
X441060Y1188990D01*
G01X441150Y1188850D02*
X441070Y1188980D01*
G01X441020Y1189180D02*
X440260D01*
G01X440290Y1189590D02*
X441060D01*
G01X441050Y1189560D02*
X441000Y1189300D01*
G01X441060Y1189580D02*
X441050Y1189560D01*
G01X441280Y1189310D02*
X441290Y1189330D01*
G01X441230Y1189840D02*
X441450Y1190000D01*
G01X441220Y1189830D02*
X441230Y1189840D01*
G01X441210Y1189810D02*
X441220Y1189830D01*
G01X441070Y1189600D02*
X441210Y1189810D01*
G01X441060Y1189580D02*
X441070Y1189600D01*
G01X441290Y1189880D02*
X440390D01*
G01X440350Y1189790D02*
X441190D01*
G01X441120Y1189680D02*
X440310D01*
G01X440490Y1190090D02*
X441750D01*
G01X441160Y1190680D02*
X442830D01*
G01X442920Y1190590D02*
X440980D01*
G01X440740Y1190380D02*
X443110D01*
G01X443290Y1190180D02*
X440570D01*
G01X441150Y1188790D02*
X441190D01*
G01X441230Y1188730D02*
X441450Y1188570D01*
G01X441020Y1187990D02*
X442570D01*
G01X442730Y1188090D02*
X440840D01*
G01X440400Y1188520D02*
X436800D01*
G01X440480Y1188490D02*
X440400Y1188520D01*
G01X440490Y1188480D02*
X440480Y1188490D01*
G01X440490Y1188470D02*
Y1188480D01*
G01X440530Y1188400D02*
X440490Y1188470D01*
G01X440540Y1188400D02*
X440530D01*
G01X440550Y1188390D02*
X440540Y1188400D01*
G01X440620Y1188290D02*
X440550Y1188390D01*
G01X440630Y1188280D02*
X440620Y1188290D01*
G01X440860Y1188060D02*
X440630Y1188280D01*
G01Y1188290D02*
X442970D01*
G01X440880Y1188050D02*
X440860Y1188060D01*
G01X441680Y1187750D02*
X442020Y1187760D01*
G01X441670Y1187750D02*
X441680D01*
G01X441660D02*
X441670D01*
G01X441500Y1187770D02*
X441660Y1187750D01*
G01X441480Y1187770D02*
X441500D01*
G01X440880Y1188050D02*
X441480Y1187770D01*
G01X442130Y1187790D02*
X441460D01*
G01Y1188560D02*
X441450Y1188570D01*
G01X441480Y1188560D02*
X441460D01*
G01X441650Y1188500D02*
X441480Y1188560D01*
G01X441670Y1188500D02*
X441740Y1188490D01*
G01X441650Y1188500D02*
X441670D01*
G01X441310Y1189120D02*
X441280Y1189310D01*
G01X441320Y1189090D02*
X441310Y1189120D01*
G01X441490Y1188870D02*
X441320Y1189090D01*
G01X441510Y1188860D02*
X441490Y1188870D01*
G01X441680Y1188780D02*
X441510Y1188860D01*
G01X441690Y1188780D02*
X441680D01*
G01X441730Y1188770D02*
X441690Y1188780D01*
G01X441730Y1189790D02*
X441750Y1189800D01*
G01X441420Y1189630D02*
X441730Y1189790D01*
G01X441400Y1189610D02*
X441420Y1189630D01*
G01X441290Y1189330D02*
X441400Y1189610D01*
G01X441460Y1190010D02*
X441450Y1190000D01*
G01X441480Y1190010D02*
X441460D01*
G01X441650Y1190070D02*
X441480Y1190010D01*
G01X441670Y1190070D02*
X441650D01*
G01X441740Y1190080D02*
X441670Y1190070D01*
G01X441760Y1190090D02*
X441740Y1190080D01*
G01X441430Y1189990D02*
X440430D01*
G01X441340Y1189470D02*
X442280D01*
G01X442300Y1189270D02*
X441290D01*
G01X441340Y1189070D02*
X442250D01*
G01X442070Y1188870D02*
X441500D01*
G01X442140Y1189660D02*
X441490D01*
G01X441340Y1190750D02*
X441250Y1190720D01*
G01X441350Y1190760D02*
X441340Y1190750D01*
G01X441490Y1190790D02*
X441350Y1190760D01*
G01X441570Y1190810D02*
X441490Y1190790D01*
G01X441350Y1191590D02*
X440250Y1192770D01*
G01X441610Y1191310D02*
X441350Y1191590D01*
G01X441640Y1191260D02*
X441610Y1191310D01*
G01X441670Y1191110D02*
X441640Y1191260D01*
G01X441680Y1191090D02*
X441670Y1191110D01*
G01X441680Y1191070D02*
Y1191090D01*
G01X441660Y1190900D02*
X441680Y1191070D01*
G01X441660Y1190890D02*
Y1190900D01*
G01X441570Y1190810D02*
X441660Y1190890D01*
G01X440790Y1192180D02*
X441430D01*
G01X441690Y1192000D02*
X441750Y1192080D01*
G01X441580Y1192020D02*
X441690Y1192000D01*
G01X442180Y1191590D02*
X441350D01*
G01X441540Y1191380D02*
X442180D01*
G01X442360Y1191180D02*
X441660D01*
G01X441670Y1190990D02*
X442550D01*
G01X442220Y1191990D02*
X440980D01*
G01X441260Y1191680D02*
X442190D01*
G01X442180Y1191490D02*
X441450D01*
G01X441620Y1191290D02*
X442260D01*
G01X442210Y1189570D02*
X441380D01*
G01X441300Y1189370D02*
X442290D01*
G01X441940Y1189770D02*
X441670D01*
G01X442200Y1188970D02*
X441420D01*
G01X441300Y1189160D02*
X442300D01*
G01X442450Y1191090D02*
X441680D01*
G01X441650Y1190880D02*
X442640D01*
G01X442730Y1190790D02*
X441460D01*
G01X440850Y1190490D02*
X443010D01*
G01X443200Y1190290D02*
X440630D01*
G01X440480Y1188490D02*
X443110D01*
G01X442880Y1188180D02*
X440730D01*
G01X440550Y1188380D02*
X443040D01*
G01X442400Y1187880D02*
X441240D01*
G01X429700Y1186220D02*
X435120Y1191830D01*
G01X429670Y1186190D02*
X429700Y1186220D01*
G01X429680Y1186170D02*
X429670Y1186190D01*
G01X429990Y1185900D02*
X429680Y1186170D01*
G01X430020Y1185890D02*
X429990Y1185900D01*
G01X430040D02*
X430020Y1185890D01*
G01X435160Y1191200D02*
X430040Y1185900D01*
G01X430120Y1185990D02*
X429890D01*
G01X429770Y1186090D02*
X430220D01*
G01X430320Y1186180D02*
X429670D01*
G01X429760Y1186290D02*
X430420D01*
G01X430510Y1186380D02*
X429860D01*
G01X429950Y1186490D02*
X430610D01*
G01X430700Y1186590D02*
X430050D01*
G01X430140Y1186680D02*
X430800D01*
G01X430900Y1186790D02*
X430240D01*
G01X430340Y1186880D02*
X430990D01*
G01X431090Y1186990D02*
X430440D01*
G01X430530Y1187090D02*
X431190D01*
G01X431280Y1187180D02*
X430630D01*
G01X430730Y1187290D02*
X431380D01*
G01X431480Y1187380D02*
X430820D01*
G01X430920Y1187490D02*
X431570D01*
G01X429370Y1205100D02*
X429400Y1205120D01*
G01X429370Y1204560D02*
Y1205100D01*
G01X429380Y1204540D02*
X429370Y1204560D01*
G01X429430Y1204430D02*
X429380Y1204540D01*
G01X429440Y1204420D02*
X429430Y1204430D01*
G01X434620Y1198830D02*
X429440Y1204420D01*
G01X429370Y1205090D02*
X429430D01*
G01X429370Y1204990D02*
X429520D01*
G01X429610Y1204880D02*
X429370D01*
G01Y1204790D02*
X429710D01*
G01X429800Y1204680D02*
X429370D01*
G01Y1204590D02*
X429890D01*
G01X429990Y1204490D02*
X429400D01*
G01X429470Y1204380D02*
X430080D01*
G01X430170Y1204290D02*
X429560D01*
G01X429650Y1204180D02*
X430260D01*
G01X430360Y1204090D02*
X429750D01*
G01X429840Y1203990D02*
X430450D01*
G01X430540Y1203880D02*
X429930D01*
G01X430020Y1203790D02*
X430640D01*
G01X430730Y1203680D02*
X430120D01*
G01X430210Y1203590D02*
X430820D01*
G01X430920Y1203490D02*
X430300D01*
G01X430400Y1203380D02*
X431010D01*
G01X431100Y1203290D02*
X430490D01*
G01X430580Y1203180D02*
X431200D01*
G01X431290Y1203090D02*
X430680D01*
G01X430770Y1202990D02*
X431380D01*
G01X431480Y1202880D02*
X430860D01*
G01X430950Y1202790D02*
X431570D01*
G01X431660Y1202680D02*
X431050D01*
G01X431140Y1202590D02*
X431750D01*
G01X431850Y1202490D02*
X431230D01*
G01X431330Y1202380D02*
X431940D01*
G01X432030Y1202290D02*
X431420D01*
G01X431510Y1202180D02*
X432120D01*
G01X432220Y1202090D02*
X431610D01*
G01X431700Y1201990D02*
X432310D01*
G01X432400Y1201880D02*
X431790D01*
G01X431880Y1201790D02*
X432500D01*
G01X432590Y1201680D02*
X431980D01*
G01X432070Y1201590D02*
X432680D01*
G01X432780Y1201490D02*
X432160D01*
G01X432250Y1201380D02*
X432870D01*
G01X432960Y1201290D02*
X432350D01*
G01X432440Y1201180D02*
X433060D01*
G01X433150Y1201090D02*
X432530D01*
G01X432620Y1200990D02*
X433240D01*
G01X433340Y1200880D02*
X432720D01*
G01X432810Y1200790D02*
X433430D01*
G01X433520Y1200680D02*
X432900D01*
G01X432990Y1200590D02*
X433620D01*
G01X433710Y1200490D02*
X433090D01*
G01X433180Y1200380D02*
X433800D01*
G01X433890Y1200290D02*
X433270D01*
G01X433370Y1200180D02*
X433990D01*
G01X434080Y1200090D02*
X433460D01*
G01X433550Y1199990D02*
X434170D01*
G01X434270Y1199880D02*
X433650D01*
G01X433830Y1199680D02*
X435070D01*
G01X435080Y1199490D02*
X434020D01*
G01X433770Y1201780D02*
X434280D01*
G01X433730Y1201740D02*
X433770Y1201780D01*
G01X433730Y1201280D02*
Y1201740D01*
G01X433770Y1201240D02*
X433730Y1201280D01*
G01Y1201680D02*
X443980D01*
G01X443910Y1201490D02*
X433730D01*
G01Y1201290D02*
X443750D01*
G01X436380Y1202590D02*
X434950D01*
G01X434370Y1201850D02*
X434280Y1201780D01*
G01X434390Y1201900D02*
X434370Y1201850D01*
G01X434390Y1201910D02*
Y1201900D01*
G01X434510Y1202160D02*
X434390Y1201910D01*
G01X434530Y1202170D02*
X434510Y1202160D01*
G01X434960Y1202590D02*
X434530Y1202170D01*
G01X434290Y1201790D02*
X435020D01*
G01X435130Y1202120D02*
X435240Y1202190D01*
G01X434960Y1201950D02*
X435130Y1202120D01*
G01X434940Y1201840D02*
X434960Y1201950D01*
G01X435030Y1201780D02*
X434940Y1201840D01*
G01X435100Y1202090D02*
X434480D01*
G01X434430Y1201990D02*
X435000D01*
G01X434950Y1201880D02*
X434380D01*
G01X434640Y1202290D02*
X436320D01*
G01Y1202490D02*
X434850D01*
G01X435200Y1198890D02*
X438430Y1195410D01*
G01X435190Y1198890D02*
X435200D01*
G01X435150Y1198940D02*
X435190Y1198890D01*
G01X435120Y1199000D02*
X435150Y1198940D01*
G01X434940Y1201130D02*
X435120Y1199000D01*
G01X435040Y1201240D02*
X434940Y1201130D01*
G01X435460Y1195090D02*
X434990D01*
G01X434980Y1195290D02*
X435440D01*
G01X435420Y1195490D02*
X434960D01*
G01X434940Y1195680D02*
X435410D01*
G01X435390Y1195880D02*
X434920D01*
G01X434900Y1196090D02*
X435370D01*
G01X435360Y1196290D02*
X434890D01*
G01X434870Y1196490D02*
X435340D01*
G01X435320Y1196680D02*
X434850D01*
G01X434840Y1196880D02*
X435310D01*
G01X435290Y1197090D02*
X434820D01*
G01X434800Y1197290D02*
X435270D01*
G01X435250Y1197490D02*
X434790D01*
G01X434770Y1197680D02*
X435240D01*
G01X435220Y1197880D02*
X434750D01*
G01X434740Y1197990D02*
X435250D01*
G01X435750Y1198290D02*
X434720D01*
G01X434700Y1198490D02*
X435570D01*
G01X434640Y1198800D02*
X434620Y1198830D01*
G01X434680Y1198700D02*
X434640Y1198800D01*
G01X434680Y1198690D02*
Y1198700D01*
G01Y1198680D02*
Y1198690D01*
G01X435380Y1198680D02*
X434680D01*
G01X434580Y1198880D02*
X435200D01*
G01X435130Y1198990D02*
X434480D01*
G01X434390Y1199090D02*
X435120D01*
G01X435110Y1199180D02*
X434300D01*
G01X434200Y1199290D02*
X435100D01*
G01X435090Y1199380D02*
X434110D01*
G01X433920Y1199590D02*
X435070D01*
G01X435060Y1199790D02*
X434580D01*
G01X434370Y1201240D02*
X433770D01*
G01X434470Y1201150D02*
X434370Y1201240D01*
G01X434590Y1199800D02*
X434470Y1201150D01*
G01X434430Y1201180D02*
X434990D01*
G01X434940Y1201090D02*
X434480D01*
G01X434490Y1200990D02*
X434960D01*
G01Y1200880D02*
X434490D01*
G01X434500Y1200790D02*
X434970D01*
G01X434980Y1200680D02*
X434510D01*
G01X434520Y1200590D02*
X434990D01*
G01X435000Y1200490D02*
X434530D01*
G01X434540Y1200380D02*
X435010D01*
G01Y1200290D02*
X434550D01*
G01Y1200180D02*
X435020D01*
G01X435030Y1200090D02*
X434570D01*
G01Y1199990D02*
X435040D01*
G01X435050Y1199880D02*
X434580D01*
G01X434420Y1199730D02*
X429400Y1205120D01*
G01X434530Y1199700D02*
X434420Y1199730D01*
G01X434590Y1199800D02*
X434530Y1199700D01*
G01X433740Y1199790D02*
X434360D01*
G01X435520Y1194380D02*
X435050D01*
G01X435030Y1194590D02*
X435500D01*
G01X435490Y1194790D02*
X435020D01*
G01X435010Y1194880D02*
X435480D01*
G01X435470Y1194990D02*
X435000D01*
G01X434980Y1195180D02*
X435450D01*
G01X435440Y1195380D02*
X434970D01*
G01X434950Y1195590D02*
X435420D01*
G01X435400Y1195790D02*
X434930D01*
G01X434920Y1195990D02*
X435380D01*
G01X435360Y1196180D02*
X434900D01*
G01X434880Y1196380D02*
X435350D01*
G01X435330Y1196590D02*
X434860D01*
G01X434850Y1196790D02*
X435310D01*
G01X435300Y1196990D02*
X434830D01*
G01X434810Y1197180D02*
X435280D01*
G01X435260Y1197380D02*
X434790D01*
G01X434780Y1197590D02*
X435240D01*
G01X435230Y1197790D02*
X434760D01*
G01X435390Y1198010D02*
X438120Y1195070D01*
G01X435270Y1198030D02*
X435390Y1198010D01*
G01X435220Y1197930D02*
X435270Y1198030D01*
G01X435490Y1194680D02*
X435030D01*
G01X435040Y1194490D02*
X435510D01*
G01X435410Y1197990D02*
X436030D01*
G01X436220Y1197790D02*
X435600D01*
G01X435780Y1197590D02*
X436400D01*
G01X435660Y1198380D02*
X434710D01*
G01X434690Y1198590D02*
X435480D01*
G01X435290Y1198790D02*
X434650D01*
G01X435350Y1202200D02*
X435240Y1202190D01*
G01X435400Y1202110D02*
X435350Y1202200D01*
G01X435400Y1201880D02*
Y1202110D01*
G01X435300Y1201780D02*
X435400Y1201880D01*
G01X435030Y1201780D02*
X435300D01*
G01X435230Y1202180D02*
X434540D01*
G01X435410Y1203170D02*
X435440Y1203190D01*
G01X435400Y1203140D02*
X435410Y1203170D01*
G01X435400Y1202940D02*
Y1203140D01*
G01X435390Y1202900D02*
X435400Y1202940D01*
G01X435370Y1202850D02*
X435390Y1202900D01*
G01X435320Y1202790D02*
X435370Y1202850D01*
G01X435230Y1202750D02*
X435320Y1202790D01*
G01X434960Y1202590D02*
X435230Y1202750D01*
G01X435440Y1203180D02*
X436270D01*
G01X435400Y1202990D02*
X438290D01*
G01X438280Y1202790D02*
X435300D01*
G01X435350Y1202180D02*
X436320D01*
G01Y1201990D02*
X435400D01*
G01X435310Y1201790D02*
X436420D01*
G01X438230Y1194380D02*
X437590D01*
G01X437640Y1195590D02*
X438270D01*
G01X438080Y1195790D02*
X437460D01*
G01X437270Y1195990D02*
X437890D01*
G01X437710Y1196180D02*
X437080D01*
G01X436990Y1196290D02*
X437610D01*
G01X437520Y1196380D02*
X436900D01*
G01X436810Y1196490D02*
X437430D01*
G01X437330Y1196590D02*
X436710D01*
G01X436620Y1196680D02*
X437240D01*
G01X437150Y1196790D02*
X436530D01*
G01X436430Y1196880D02*
X437060D01*
G01X436960Y1196990D02*
X436340D01*
G01X436250Y1197090D02*
X436870D01*
G01X436780Y1197180D02*
X436150D01*
G01X436060Y1197290D02*
X436680D01*
G01X436590Y1197380D02*
X435970D01*
G01X435880Y1197490D02*
X436500D01*
G01X436310Y1197680D02*
X435690D01*
G01X435500Y1197880D02*
X436120D01*
G01X435940Y1198090D02*
X434740D01*
G01X434730Y1198180D02*
X435850D01*
G01X437700Y1197460D02*
X437740Y1197420D01*
G01X436320Y1201880D02*
X435400D01*
G01X436420Y1201780D02*
X436320Y1201880D01*
G01X435400Y1202090D02*
X436320D01*
G01X437650Y1202790D02*
X437760Y1202680D01*
G01X437380Y1202760D02*
X437650Y1202790D01*
G01X437100Y1202730D02*
X437380Y1202760D01*
G01X436980Y1202720D02*
X437100Y1202730D01*
G01X436880Y1202700D02*
X436980Y1202720D01*
G01X436630Y1202660D02*
X436880Y1202700D01*
G01X436620Y1202660D02*
X436630D01*
G01X436530Y1202640D02*
X436620Y1202660D01*
G01X436520Y1202640D02*
X436530D01*
G01X436400Y1202620D02*
X436520Y1202640D01*
G01X436320Y1202520D02*
X436400Y1202620D01*
G01X436320Y1201880D02*
Y1202520D01*
G01X436260Y1203190D02*
X435440D01*
G01X436280Y1203180D02*
X436260Y1203190D01*
G01X436310Y1203170D02*
X436280Y1203180D01*
G01X436340Y1203150D02*
X436310Y1203170D01*
G01X436420Y1203130D02*
X436340Y1203150D01*
G01X436440Y1203140D02*
X436420Y1203130D01*
G01X436680Y1203180D02*
X436440Y1203140D01*
G01X437180Y1203250D02*
X436680Y1203180D01*
G01X437300Y1203260D02*
X437180Y1203250D01*
G01X437360Y1203260D02*
X437300D01*
G01X437520Y1203280D02*
X437360Y1203260D01*
G01X437660Y1203290D02*
X437520Y1203280D01*
G01X435120Y1202680D02*
X436770D01*
G01X436320Y1202380D02*
X434750D01*
G01X436420Y1201780D02*
X442260D01*
G01X440330Y1203290D02*
X437640D01*
G01X437660D02*
X437760Y1203390D01*
G01X438880Y1194920D02*
Y1195060D01*
G01X438900Y1195090D02*
X438110D01*
G01X438120Y1195070D02*
Y1194930D01*
G01X438330Y1194490D02*
X437680D01*
G01X438420Y1194590D02*
X438570D01*
G01X437780D02*
X438420D01*
G01X439380Y1194380D02*
X438750D01*
G01X438660Y1194490D02*
X439290D01*
G01X439200Y1194590D02*
X438550D01*
G01X438920Y1194880D02*
X438070D01*
G01X438120Y1194990D02*
X438880D01*
G01X439000Y1195180D02*
X438010D01*
G01X437920Y1195290D02*
X439100D01*
G01X439200Y1195380D02*
X437830D01*
G01X437740Y1195490D02*
X438360D01*
G01X438570Y1195410D02*
X440000Y1196880D01*
G01X438430Y1195410D02*
X438570D01*
G01X439900Y1196790D02*
X440540D01*
G01X440350Y1196590D02*
X439710D01*
G01X439620Y1196490D02*
X440250D01*
G01X440160Y1196380D02*
X439520D01*
G01X439420Y1196290D02*
X440060D01*
G01X439970Y1196180D02*
X439330D01*
G01X439230Y1196090D02*
X439870D01*
G01X439770Y1195990D02*
X439130D01*
G01X439040Y1195880D02*
X439680D01*
G01X439580Y1195790D02*
X438940D01*
G01X438850Y1195680D02*
X439480D01*
G01X439390Y1195590D02*
X438750D01*
G01X438650Y1195490D02*
X439290D01*
G01X439010Y1194790D02*
X437980D01*
G01X437880Y1194680D02*
X439100D01*
G01X438170Y1195680D02*
X437550D01*
G01X437360Y1195880D02*
X437990D01*
G01X437800Y1196090D02*
X437180D01*
G01X437790Y1197420D02*
X440280D01*
G01X437740D02*
X437790D01*
G01X440290Y1197180D02*
X440930D01*
G01X440740Y1196990D02*
X440100D01*
G01X441220Y1197490D02*
X437700D01*
G01X437740Y1198450D02*
X437790D01*
G01X437700Y1198410D02*
X437740Y1198450D01*
G01X437700Y1197460D02*
Y1198410D01*
G01Y1198290D02*
X440960D01*
G01X440990Y1198090D02*
X437700D01*
G01Y1197880D02*
X441610D01*
G01X441410Y1197680D02*
X437700D01*
G01X437760Y1202340D02*
Y1202680D01*
G01X437800Y1202290D02*
X437760Y1202340D01*
G01X437750Y1202680D02*
X440380D01*
G01X440250Y1202290D02*
X437800D01*
G01X440300Y1202340D02*
X440250Y1202290D01*
G01X440300Y1202620D02*
Y1202340D01*
G01X437760Y1202380D02*
X440300D01*
G01Y1202490D02*
X437760D01*
G01Y1202590D02*
X440300D01*
G01X439850Y1202900D02*
Y1202860D01*
G01X439750Y1203000D02*
X439850Y1202900D01*
G01X438310Y1203000D02*
X439750D01*
G01X438210Y1202900D02*
X438310Y1203000D01*
G01X438210Y1202860D02*
Y1202900D01*
G01X438310Y1202750D02*
X438210Y1202860D01*
G01X439750Y1202750D02*
X438310D01*
G01X439850Y1202860D02*
X439750Y1202750D01*
G01X439850Y1202880D02*
X441820D01*
G01X441530Y1202990D02*
X439760D01*
G01X437760Y1203420D02*
Y1203390D01*
G01X437800Y1203460D02*
X437760Y1203420D01*
G01X440250Y1203460D02*
X437800D01*
G01X440300Y1203420D02*
X440250Y1203460D01*
G01X440300Y1203320D02*
Y1203420D01*
G01X437750Y1203380D02*
X440300D01*
G01X438210Y1202880D02*
X435380D01*
G01X435400Y1203090D02*
X441160D01*
G01X440380Y1203220D02*
X440300Y1203320D01*
G01X440430Y1203220D02*
X440380D01*
G01X440990Y1203130D02*
X440430Y1203220D01*
G01X441170Y1203090D02*
X440990Y1203130D01*
G01X440610Y1203180D02*
X436740D01*
G01X440810Y1202650D02*
X441220Y1202560D01*
G01X440520Y1202700D02*
X440810Y1202650D01*
G01X440490Y1202700D02*
X440520D01*
G01X440410Y1202720D02*
X440490Y1202700D01*
G01X440300Y1202620D02*
X440410Y1202720D01*
G01X440600Y1202680D02*
X442190D01*
G01X440910Y1198450D02*
X437790D01*
G01X437700Y1198380D02*
X440960D01*
G01X440950Y1198410D02*
X440910Y1198450D01*
G01X441130Y1198060D02*
X441330Y1198260D01*
G01X441020Y1198030D02*
X441130Y1198060D01*
G01X440960Y1198130D02*
X441020Y1198030D01*
G01X440960Y1198310D02*
Y1198130D01*
G01Y1198320D02*
Y1198310D01*
G01X440950Y1198410D02*
X440960Y1198320D01*
G01X441160Y1198090D02*
X441800D01*
G01X440960Y1198180D02*
X437700D01*
G01X439810Y1196680D02*
X440450D01*
G01X440370Y1197360D02*
X440280Y1197420D01*
G01X440350Y1197250D02*
X440370Y1197360D01*
G01X440000Y1196880D02*
X440350Y1197250D01*
G01X440640Y1196880D02*
X440000D01*
G01X440330Y1197380D02*
X441120D01*
G01X441030Y1197290D02*
X440360D01*
G01X440200Y1197090D02*
X440830D01*
G01X441350Y1198290D02*
X441330Y1198260D01*
G01X441990Y1198290D02*
X441350D01*
G01D02*
X442160Y1199130D01*
G01X444000Y1198490D02*
X441550D01*
G01X441250Y1198180D02*
X441890D01*
G01X441700Y1197990D02*
X437700D01*
G01Y1197790D02*
X441510D01*
G01X441310Y1197590D02*
X437700D01*
G01X441500Y1202480D02*
X441220Y1202560D01*
G01X441510Y1202470D02*
X441500Y1202480D01*
G01X441620Y1202440D02*
X441510Y1202470D01*
G01X441620Y1202430D02*
Y1202440D01*
G01X441730Y1202390D02*
X441620Y1202430D01*
G01X441740Y1202380D02*
X441730Y1202390D01*
G01X441460Y1202490D02*
X442490D01*
G01X441290Y1203050D02*
X441170Y1203090D01*
G01X441400Y1203030D02*
X441290Y1203050D01*
G01X441640Y1202950D02*
X441400Y1203030D01*
G01X441750Y1202910D02*
X441640Y1202950D01*
G01X441100Y1202590D02*
X442350D01*
G01X442030Y1202790D02*
X439780D01*
G01X441740Y1202380D02*
X441930Y1202290D01*
G01X442090Y1198390D02*
X438880Y1195060D01*
G01X442090Y1198380D02*
X441450D01*
G01X442390Y1201240D02*
X435040D01*
G01X443840Y1201380D02*
X433730D01*
G01Y1201590D02*
X443940D01*
G01X441640Y1198590D02*
X444000D01*
G01X441870Y1188490D02*
X441890D01*
G01X441740D02*
X441870D01*
G01X441790Y1188770D02*
X441730D01*
G01X441810D02*
X441790D01*
G01X441840Y1189800D02*
X441850D01*
G01X441750D02*
X441840D01*
G01X441820Y1190090D02*
X441760D01*
G01X441850Y1190080D02*
X441820Y1190090D01*
G01X441810Y1188770D02*
X441940Y1188790D01*
G01X441890Y1190080D02*
X442090Y1190030D01*
G01X441850Y1190080D02*
X441890D01*
G01X441750Y1192080D02*
X442260Y1198310D01*
G01X441920Y1194090D02*
X442380D01*
G01X442370Y1193880D02*
X441900D01*
G01X441880Y1193680D02*
X442350D01*
G01X442340Y1193490D02*
X441870D01*
G01X441850Y1193290D02*
X442320D01*
G01X442310Y1193090D02*
X441840D01*
G01X441820Y1192880D02*
X442290D01*
G01X442270Y1192680D02*
X441810D01*
G01X441790Y1192490D02*
X442250D01*
G01X442240Y1192290D02*
X441770D01*
G01X441750Y1192090D02*
X442220D01*
G01X441940Y1194290D02*
X442400D01*
G01X442390Y1194180D02*
X441930D01*
G01X441910Y1193990D02*
X442380D01*
G01X442360Y1193790D02*
X441890D01*
G01X441880Y1193590D02*
X442350D01*
G01X442330Y1193380D02*
X441860D01*
G01X441850Y1193180D02*
X442310D01*
G01X442300Y1192990D02*
X441830D01*
G01X441810Y1192790D02*
X442280D01*
G01X442260Y1192590D02*
X441800D01*
G01X441780Y1192380D02*
X442250D01*
G01X442230Y1192180D02*
X441760D01*
G01X442200Y1191350D02*
X443160Y1190330D01*
G01X443480Y1189990D02*
X442150D01*
G01X442130Y1190010D02*
X442090Y1190030D01*
G01X442130Y1190010D02*
X442440Y1189750D01*
G01X442100Y1189700D02*
X441850Y1189800D01*
G01X442120Y1189690D02*
X442100Y1189700D01*
G01X442270Y1189490D02*
X442120Y1189690D01*
G01X442280Y1189460D02*
X442270Y1189490D01*
G01X441960Y1188790D02*
X441940D01*
G01X442180Y1188930D02*
X441960Y1188790D01*
G01X442190Y1188950D02*
X442180Y1188930D01*
G01X442300Y1189180D02*
X442190Y1188950D01*
G01X442310Y1189200D02*
X442300Y1189180D01*
G01X442280Y1189460D02*
X442310Y1189200D01*
G01X442150Y1188590D02*
X443170D01*
G01X442030Y1187760D02*
X442020D01*
G01X442320Y1187830D02*
X442030Y1187760D01*
G01X442330Y1187840D02*
X442320Y1187830D01*
G01X442840Y1188150D02*
X442330Y1187840D01*
G01X442090Y1188540D02*
X442130Y1188560D01*
G01X441890Y1188490D02*
X442090Y1188540D01*
G01X442190Y1191370D02*
X442170Y1191440D01*
G01X442200Y1191360D02*
X442190Y1191370D01*
G01X442200Y1191350D02*
Y1191360D01*
G01X442740Y1198370D02*
X442170Y1191440D01*
G01X442930Y1188240D02*
X442840Y1188150D01*
G01X442990Y1188310D02*
X442930Y1188240D01*
G01X443120Y1188500D02*
X442990Y1188310D01*
G01X443240Y1188750D02*
X443300Y1188920D01*
G01X443200Y1188650D02*
X443240Y1188750D01*
G01X443200Y1188640D02*
Y1188650D01*
G01X443130Y1188510D02*
X443200Y1188640D01*
G01X443120Y1188500D02*
X443130Y1188510D01*
G01X443290Y1188880D02*
X442475D01*
G01X442480D02*
X442540D01*
G01X442440Y1188820D02*
X442130Y1188560D01*
G01X442470Y1188870D02*
X442440Y1188820D01*
G01X442270Y1188680D02*
X443220D01*
G01X443250Y1188790D02*
X442460D01*
G01X443220D02*
X443250D01*
G01X442470Y1189700D02*
X442440Y1189750D01*
G01X442590Y1189310D02*
X442470Y1189700D01*
G01X442590Y1189250D02*
Y1189310D01*
G01X442470Y1188870D02*
X442590Y1189250D01*
G01X442400Y1189790D02*
X443660D01*
G01X443850Y1189590D02*
X442510D01*
G01X442570Y1189380D02*
X444030D01*
G01X443330Y1189180D02*
X442570D01*
G01X442510Y1188990D02*
X443310D01*
G01X443380Y1190090D02*
X441830D01*
G01X442270Y1189880D02*
X443570D01*
G01X443750Y1189680D02*
X442480D01*
G01X442530Y1189490D02*
X443940D01*
G01X444130Y1189290D02*
X443440D01*
G01X443300Y1188940D02*
Y1188920D01*
G01X443340Y1189210D02*
X443300Y1188940D01*
G01X443400Y1189290D02*
X443340Y1189210D01*
G01X443320Y1189090D02*
X442540D01*
G01X443400Y1189290D02*
X443510Y1189270D01*
G01X442590Y1189290D02*
X443400D01*
G01X443590Y1189180D02*
X444220D01*
G01X444310Y1189090D02*
X443680D01*
G01X443770Y1188990D02*
X444410D01*
G01X444460Y1188880D02*
X444500D01*
G01X444510D02*
X443870D01*
G01X443960Y1188790D02*
X444595D01*
G01X444590D02*
X444540D01*
G01X444695Y1188680D02*
X444050D01*
G01X444140Y1188590D02*
X444780D01*
G01X444870Y1188490D02*
X444235D01*
G01X444335Y1188380D02*
X444970D01*
G01X445060Y1188290D02*
X444420D01*
G01X444525Y1188180D02*
X445150D01*
G01X445250Y1188090D02*
X444610D01*
G01X444700Y1187990D02*
X445340D01*
G01X445430Y1187880D02*
X444790D01*
G01X444880Y1187790D02*
X445530D01*
G01X445710Y1187590D02*
X445070D01*
G01X444980Y1187680D02*
X445620D01*
G01X445800Y1187490D02*
X445160D01*
G01X445260Y1187380D02*
X445900D01*
G01X445990Y1187290D02*
X445350D01*
G01X445440Y1187180D02*
X446080D01*
G01X446180Y1187090D02*
X445530D01*
G01X445630Y1186990D02*
X446270D01*
G01X446360Y1186880D02*
X445720D01*
G01X445810Y1186790D02*
X446460D01*
G01X446550Y1186680D02*
X445910D01*
G01X446000Y1186590D02*
X446640D01*
G01X446830Y1186380D02*
X446190D01*
G01X446370Y1186180D02*
X446980D01*
G01X446970Y1186240D02*
X443160Y1190330D01*
G01X446640Y1185900D02*
X446660Y1185880D01*
G01X443510Y1189270D02*
X446640Y1185900D01*
G01X446560Y1185990D02*
X446780D01*
G01X446740Y1186490D02*
X446090D01*
G01X446280Y1186290D02*
X446920D01*
G01X446690Y1185900D02*
X446660Y1185880D01*
G01X446980Y1186190D02*
X446690Y1185900D01*
G01X446990Y1186210D02*
X446980Y1186190D01*
G01Y1186220D02*
X446990Y1186210D01*
G01X446970Y1186240D02*
X446980Y1186220D01*
G01X446460Y1186090D02*
X446880D01*
G01X441740Y1198680D02*
X444000D01*
G01X442600Y1202380D02*
X441740D01*
G01X441810Y1202890D02*
X441750Y1202910D01*
G01X442350Y1201830D02*
X442260Y1201780D01*
G01X442340Y1201930D02*
X442350Y1201830D01*
G01X442270Y1202040D02*
X442340Y1201930D01*
G01X442250Y1202060D02*
X442270Y1202040D01*
G01X441950Y1202280D02*
X442250Y1202060D01*
G01X441940Y1202290D02*
X441950Y1202280D01*
G01X441930Y1202290D02*
X441940D01*
G01X442270Y1201790D02*
X443990D01*
G01X443970Y1201990D02*
X442310D01*
G01X442080Y1202180D02*
X443890D01*
G01X444000Y1200180D02*
X442220D01*
G01X442190Y1199160D02*
X442160Y1199130D01*
G01X442220Y1199220D02*
X442190Y1199160D01*
G01X442220Y1200240D02*
Y1199220D01*
G01X442120Y1199090D02*
X442790D01*
G01X442960Y1199290D02*
X442220D01*
G01Y1199490D02*
X443150D01*
G01X443340Y1199680D02*
X442220D01*
G01Y1199790D02*
X444000D01*
G01Y1199990D02*
X442220D01*
G01X442330Y1200320D02*
X442430Y1200420D01*
G01X442260Y1200320D02*
X442330D01*
G01X442220Y1200280D02*
X442260Y1200320D01*
G01X442220Y1200240D02*
Y1200280D01*
G01X441930Y1198880D02*
X444000D01*
G01X442720Y1198180D02*
X442250D01*
G01X442200Y1198410D02*
X442090Y1198390D01*
G01X442260Y1198310D02*
X442200Y1198410D01*
G01X441980Y1194880D02*
X442450D01*
G01X442460Y1194990D02*
X441990D01*
G01X442010Y1195180D02*
X442480D01*
G01X442490Y1195380D02*
X442030D01*
G01X442040Y1195590D02*
X442510D01*
G01X442520Y1195790D02*
X442060D01*
G01X442070Y1195990D02*
X442540D01*
G01X442560Y1196180D02*
X442090D01*
G01X442110Y1196380D02*
X442570D01*
G01X442590Y1196590D02*
X442120D01*
G01X442140Y1196790D02*
X442610D01*
G01X442620Y1196990D02*
X442160D01*
G01X442170Y1197180D02*
X442640D01*
G01X442650Y1197380D02*
X442190D01*
G01X442200Y1197590D02*
X442670D01*
G01X442690Y1197790D02*
X442220D01*
G01X442240Y1197990D02*
X442700D01*
G01X441970Y1194680D02*
X442440D01*
G01X442420Y1194490D02*
X441950D01*
G01X441960Y1202830D02*
X441810Y1202890D01*
G01X441970Y1202820D02*
X441960Y1202830D01*
G01X443220Y1202540D02*
X443280Y1202550D01*
G01X443210Y1202540D02*
X443220D01*
G01X443100Y1202510D02*
X443210Y1202540D01*
G01X443090Y1202510D02*
X443100D01*
G01X442960Y1202460D02*
X443090Y1202510D01*
G01X442960Y1202450D02*
Y1202460D01*
G01X442900Y1202420D02*
X442960Y1202450D01*
G01X442880Y1202400D02*
X442900Y1202420D01*
G01X442820Y1202350D02*
X442880Y1202400D01*
G01X442800Y1202330D02*
X442820Y1202350D01*
G01X442660Y1202330D02*
X442800D01*
G01X442480Y1202500D02*
X442660Y1202330D01*
G01X442470Y1202510D02*
X442480Y1202500D01*
G01X441970Y1202820D02*
X442470Y1202510D01*
G01X443030Y1202490D02*
X443550D01*
G01X443600Y1201180D02*
X442440D01*
G01X442490Y1201130D02*
X442430Y1200420D01*
G01X442400Y1200380D02*
X442950D01*
G01X443240Y1201110D02*
X443270Y1201100D01*
G01X443160Y1201120D02*
X443240Y1201110D01*
G01X443090Y1201140D02*
X443160Y1201120D01*
G01X443080Y1201140D02*
X443090D01*
G01X442950Y1201050D02*
X443080Y1201140D01*
G01X442900Y1200440D02*
X442950Y1201050D01*
G01X443000Y1200330D02*
X442900Y1200440D01*
G01X443000Y1201090D02*
X442490D01*
G01Y1201130D02*
X442390Y1201240D01*
G01X442030Y1198990D02*
X442850D01*
G01X442820Y1199140D02*
X443370Y1199720D01*
G01X442790Y1199090D02*
X442820Y1199140D01*
G01X442790Y1199050D02*
Y1199090D01*
G01X442890Y1198940D02*
X442790Y1199050D01*
G01X443250Y1199590D02*
X442220D01*
G01Y1199380D02*
X443050D01*
G01X442860Y1199180D02*
X442200D01*
G01X442220Y1198380D02*
X442750D01*
G01X441940Y1194380D02*
X442410D01*
G01X442430Y1194590D02*
X441960D01*
G01X441980Y1194790D02*
X442440D01*
G01X442470Y1195090D02*
X442000D01*
G01X442010Y1195290D02*
X442480D01*
G01X442500Y1195490D02*
X442030D01*
G01X442050Y1195680D02*
X442510D01*
G01X442530Y1195880D02*
X442070D01*
G01X442080Y1196090D02*
X442550D01*
G01X442570Y1196290D02*
X442100D01*
G01X442110Y1196490D02*
X442580D01*
G01X442600Y1196680D02*
X442130D01*
G01X442150Y1196880D02*
X442610D01*
G01X442630Y1197090D02*
X442160D01*
G01X442180Y1197290D02*
X442640D01*
G01X442660Y1197490D02*
X442200D01*
G01X442210Y1197680D02*
X442680D01*
G01X442700Y1197880D02*
X442230D01*
G01X442240Y1198090D02*
X442710D01*
G01X442730Y1198290D02*
X442260D01*
G01X442740Y1198370D02*
X442830Y1198460D01*
G01X443160Y1200320D02*
X443280D01*
G01X443000Y1200330D02*
X443160Y1200320D01*
G01X442910Y1200490D02*
X442440D01*
G01X442450Y1200590D02*
X442920D01*
G01Y1200680D02*
X442460D01*
G01Y1200790D02*
X442930D01*
G01X442940Y1200880D02*
X442470D01*
G01X442480Y1200990D02*
X442950D01*
G01X443350Y1202550D02*
X443280D01*
G01X443360Y1202540D02*
X443350Y1202550D01*
G01X443620Y1202470D02*
X443360Y1202540D01*
G01X443630Y1202460D02*
X443620Y1202470D01*
G01X443830Y1202290D02*
X443630Y1202460D01*
G01X443840Y1202280D02*
X443830Y1202290D01*
G01X443960Y1202050D02*
X443840Y1202280D01*
G01X443970Y1202030D02*
X443960Y1202050D01*
G01X443990Y1201750D02*
X443970Y1202030D01*
G01X443990Y1201740D02*
Y1201750D01*
G01X443910Y1201480D02*
X443990Y1201740D01*
G01X443900Y1201470D02*
X443910Y1201480D01*
G01X443740Y1201270D02*
X443900Y1201470D01*
G01X443730Y1201250D02*
X443740Y1201270D01*
G01X443500Y1201130D02*
X443730Y1201250D01*
G01X443480Y1201130D02*
X443500D01*
G01X443360Y1201110D02*
X443480Y1201130D01*
G01X443350Y1201110D02*
X443360D01*
G01X443290Y1201100D02*
X443350Y1201110D01*
G01X443270Y1201100D02*
X443290D01*
G01X442860Y1202380D02*
X443720D01*
G01X443830Y1202290D02*
X441940D01*
G01X442220Y1202090D02*
X443940D01*
G01X443980Y1201880D02*
X442350D01*
G01X444250Y1201290D02*
X444880D01*
G01X444980Y1201380D02*
X444350D01*
G01X444440Y1201490D02*
X445080D01*
G01X445170Y1201590D02*
X444540D01*
G01X444640Y1201680D02*
X445270D01*
G01X445360Y1201790D02*
X444740D01*
G01X444830Y1201880D02*
X445460D01*
G01X445560Y1201990D02*
X444930D01*
G01X445030Y1202090D02*
X445660D01*
G01X445850Y1202290D02*
X445220D01*
G01X445410Y1202490D02*
X446040D01*
G01X444790Y1201180D02*
X444160D01*
G01X444060Y1201090D02*
X444690D01*
G01X444590Y1200990D02*
X443960D01*
G01X443860Y1200880D02*
X444500D01*
G01X444400Y1200790D02*
X443770D01*
G01X443670Y1200680D02*
X444310D01*
G01X444210Y1200590D02*
X443580D01*
G01X443480Y1200490D02*
X444110D01*
G01X443960Y1198460D02*
X442830D01*
G01X444000Y1198480D02*
X443960Y1198460D01*
G01X444000Y1198490D02*
Y1198480D01*
G01Y1200310D02*
Y1198490D01*
G01Y1200320D02*
Y1200310D01*
G01X444030Y1200400D02*
X444000Y1200320D01*
G01X443480Y1199740D02*
X443370Y1199720D01*
G01X443540Y1199640D02*
X443480Y1199740D01*
G01X443540Y1199040D02*
Y1199640D01*
G01X443440Y1198940D02*
X443540Y1199040D01*
G01X442890Y1198940D02*
X443440D01*
G01X443510Y1199680D02*
X444000D01*
G01Y1199590D02*
X443540D01*
G01Y1199490D02*
X444000D01*
G01Y1199380D02*
X443540D01*
G01Y1199290D02*
X444000D01*
G01Y1199180D02*
X443540D01*
G01Y1199090D02*
X444000D01*
G01Y1198990D02*
X443490D01*
G01X444000Y1198790D02*
X441830D01*
G01X444000Y1199880D02*
X442220D01*
G01Y1200090D02*
X444000D01*
G01Y1200290D02*
X442220D01*
G01X443280Y1200320D02*
X443350Y1200350D01*
G01X443380Y1200380D02*
X444020D01*
G01X443350Y1200350D02*
X447930Y1205090D01*
G01X447960Y1204480D02*
X444030Y1200400D01*
G01X445120Y1202180D02*
X445750D01*
G01X445940Y1202380D02*
X445310D01*
G01X445510Y1202590D02*
X446140D01*
G01X446240Y1202680D02*
X445610D01*
G01X445700Y1202790D02*
X446330D01*
G01X446430Y1202880D02*
X445800D01*
G01X445900Y1202990D02*
X446520D01*
G01X446620Y1203090D02*
X445990D01*
G01X446180Y1203290D02*
X446810D01*
G01X447010Y1203490D02*
X446380D01*
G01X446570Y1203680D02*
X447200D01*
G01X447100Y1203590D02*
X446480D01*
G01X446670Y1203790D02*
X447290D01*
G01X447390Y1203880D02*
X446760D01*
G01X446860Y1203990D02*
X447490D01*
G01X447590Y1204090D02*
X446960D01*
G01X447050Y1204180D02*
X447680D01*
G01X447780Y1204290D02*
X447150D01*
G01X447250Y1204380D02*
X447870D01*
G01X447980Y1204590D02*
X447440D01*
G01X447970Y1204510D02*
X447980Y1204590D01*
G01X447960Y1204480D02*
X447970Y1204510D01*
G01X447350Y1204490D02*
X447960D01*
G01X447980Y1205080D02*
X447930Y1205090D01*
G01X447980Y1204590D02*
Y1205080D01*
G01X447920Y1205090D02*
X447960D01*
G01X447980Y1204990D02*
X447830D01*
G01X447730Y1204880D02*
X447980D01*
G01Y1204790D02*
X447630D01*
G01X447540Y1204680D02*
X447980D01*
G01X446910Y1203380D02*
X446280D01*
G01X446090Y1203180D02*
X446720D01*
G54D19*
G01X-53190Y-209897D02*
Y-192397D01*
G01X-44894D02*
X-53190Y-203189D01*
G01X-43584Y-209897D02*
X-49479Y-198231D01*
G01X-35909Y-209897D02*
Y-192397D01*
X-25865Y-209897D01*
Y-192397D01*
G01X-13387Y-209897D02*
X-15134Y-209605D01*
X-16662Y-208439D01*
X-17972Y-206689D01*
X-18846Y-204647D01*
X-19282Y-202314D01*
Y-199980D01*
X-18846Y-197647D01*
X-17972Y-195605D01*
X-16662Y-193856D01*
X-15134Y-192689D01*
X-13387Y-192397D01*
X-11641Y-192689D01*
X-10112Y-193856D01*
X-8802Y-195605D01*
X-7928Y-197647D01*
X-7492Y-199980D01*
Y-202314D01*
X-7928Y-204647D01*
X-8802Y-206689D01*
X-10112Y-208439D01*
X-11641Y-209605D01*
X-13387Y-209897D01*
G01X-472D02*
X8698Y-192397D01*
G01X-472D02*
X8698Y-209897D01*
G01X34310D02*
Y-192397D01*
X38676D01*
X40423Y-193272D01*
X41733Y-194439D01*
X42825Y-196188D01*
X43698Y-198231D01*
X43916Y-201147D01*
X43698Y-204064D01*
X42825Y-206106D01*
X41733Y-207856D01*
X40423Y-209022D01*
X38676Y-209897D01*
X34310D01*
G01X52246D02*
Y-192397D01*
X57705D01*
X59451Y-193272D01*
X60543Y-194439D01*
X60980Y-196772D01*
X60543Y-199106D01*
X59233Y-200564D01*
X57705Y-201439D01*
X52246D01*
G01X57705D02*
X60980Y-209897D01*
G01X71493Y-192397D02*
X76733D01*
G01X74113D02*
Y-209897D01*
G01X71493D02*
X76733D01*
G01X86154Y-192397D02*
X91613Y-209897D01*
X97072Y-192397D01*
G01X113480Y-209897D02*
X104746D01*
Y-192397D01*
X113480D01*
G01X109986Y-200855D02*
X104746D01*
G01X139746Y-209897D02*
Y-192397D01*
X144986D01*
X146733Y-193272D01*
X148043Y-195314D01*
X148480Y-197647D01*
X148043Y-199980D01*
X146951Y-201730D01*
X144986Y-202606D01*
X139746D01*
G01X157246Y-192397D02*
Y-209897D01*
X165980D01*
G01X173654D02*
X179113Y-192397D01*
X184572Y-209897D01*
G01X182606Y-203772D02*
X175619D01*
G01X191591Y-209897D02*
Y-192397D01*
X201635Y-209897D01*
Y-192397D01*
G01X218480Y-209897D02*
X209746D01*
Y-192397D01*
X218480D01*
G01X214986Y-200855D02*
X209746D01*
G01X250859Y-200564D02*
X251733Y-199689D01*
X252388Y-198231D01*
X252825Y-196188D01*
X252388Y-194439D01*
X251515Y-193272D01*
X249986Y-192397D01*
X244091D01*
Y-209897D01*
X251296D01*
X252825Y-208731D01*
X253698Y-206980D01*
X254135Y-204939D01*
X253698Y-202897D01*
X252388Y-201147D01*
X250859Y-200564D01*
X244091D01*
G01X266613Y-209897D02*
X264866Y-209605D01*
X263338Y-208439D01*
X262028Y-206689D01*
X261154Y-204647D01*
X260718Y-202314D01*
Y-199980D01*
X261154Y-197647D01*
X262028Y-195605D01*
X263338Y-193856D01*
X264866Y-192689D01*
X266613Y-192397D01*
X268359Y-192689D01*
X269888Y-193856D01*
X271198Y-195605D01*
X272072Y-197647D01*
X272508Y-199980D01*
Y-202314D01*
X272072Y-204647D01*
X271198Y-206689D01*
X269888Y-208439D01*
X268359Y-209605D01*
X266613Y-209897D01*
G01X278654D02*
X284113Y-192397D01*
X289572Y-209897D01*
G01X287606Y-203772D02*
X280619D01*
G01X297246Y-209897D02*
Y-192397D01*
X302705D01*
X304451Y-193272D01*
X305543Y-194439D01*
X305980Y-196772D01*
X305543Y-199106D01*
X304233Y-200564D01*
X302705Y-201439D01*
X297246D01*
G01X302705D02*
X305980Y-209897D01*
G01X314310D02*
Y-192397D01*
X318676D01*
X320423Y-193272D01*
X321733Y-194439D01*
X322825Y-196188D01*
X323698Y-198231D01*
X323916Y-201147D01*
X323698Y-204064D01*
X322825Y-206106D01*
X321733Y-207856D01*
X320423Y-209022D01*
X318676Y-209897D01*
X314310D01*
G01X94686Y-164897D02*
Y-147397D01*
X100363Y-161980D01*
X106040Y-147397D01*
Y-164897D01*
G01X117863D02*
X116553Y-164605D01*
X115243Y-163439D01*
X114369Y-161397D01*
X113933Y-159064D01*
X114369Y-156730D01*
X115243Y-154689D01*
X116553Y-153522D01*
X117863Y-153231D01*
X119173Y-153522D01*
X120483Y-154689D01*
X121356Y-156730D01*
X121575Y-159064D01*
X121356Y-161397D01*
X120483Y-163439D01*
X119173Y-164605D01*
X117863Y-164897D01*
G01X139293Y-147397D02*
Y-164897D01*
G01Y-162273D02*
X138420Y-163731D01*
X137109Y-164605D01*
X135581Y-164897D01*
X133835Y-164314D01*
X132525Y-162856D01*
X131651Y-161106D01*
X131433Y-159064D01*
X131651Y-157022D01*
X132525Y-155272D01*
X133835Y-153814D01*
X135581Y-153231D01*
X137109Y-153522D01*
X138201Y-154106D01*
X139293Y-155272D01*
G01X149588Y-157022D02*
X156575D01*
X155920Y-154980D01*
X154828Y-153814D01*
X153300Y-153231D01*
X151771Y-153522D01*
X150461Y-154397D01*
X149588Y-156439D01*
X149151Y-158189D01*
Y-159939D01*
X149588Y-161689D01*
X150680Y-163439D01*
X151990Y-164605D01*
X153518Y-164897D01*
X155046Y-164314D01*
X156575Y-162564D01*
G01X170363Y-164897D02*
Y-147397D01*
G01X376163Y-209897D02*
Y-192397D01*
X373543Y-195897D01*
G01Y-209897D02*
X378783D01*
G01X389515Y-195314D02*
X390825Y-193564D01*
X392353Y-192689D01*
X394100Y-192397D01*
X396283Y-192980D01*
X397811Y-194439D01*
X398248Y-196188D01*
X398030Y-197939D01*
X397156Y-199397D01*
X392790Y-202314D01*
X390825Y-204355D01*
X389515Y-207273D01*
X389078Y-209897D01*
X398248D01*
G01X413783D02*
Y-192397D01*
X405704Y-204939D01*
X416622D01*
G01X423860Y-206397D02*
X425169Y-208439D01*
X426916Y-209605D01*
X428881Y-209897D01*
X430628Y-209605D01*
X432375Y-208147D01*
X433466Y-206397D01*
X433685Y-204647D01*
X433248Y-202606D01*
X431720Y-201147D01*
X430191Y-200564D01*
X428226D01*
G01X430191D02*
X431501Y-199689D01*
X432593Y-198231D01*
X433030Y-196481D01*
X432593Y-194730D01*
X431501Y-193272D01*
X429536Y-192397D01*
X427571Y-192689D01*
X425606Y-193856D01*
G01X442015Y-195314D02*
X443325Y-193564D01*
X444853Y-192689D01*
X446600Y-192397D01*
X448783Y-192980D01*
X450311Y-194439D01*
X450748Y-196188D01*
X450530Y-197939D01*
X449656Y-199397D01*
X445290Y-202314D01*
X443325Y-204355D01*
X442015Y-207273D01*
X441578Y-209897D01*
X450748D01*
G01X363046Y-164897D02*
Y-147397D01*
X368286D01*
X370033Y-148272D01*
X371343Y-150314D01*
X371780Y-152647D01*
X371343Y-154980D01*
X370251Y-156730D01*
X368286Y-157606D01*
X363046D01*
G01X389716Y-148856D02*
X388406Y-147980D01*
X386878Y-147397D01*
X385131D01*
X383166Y-148272D01*
X381638Y-149730D01*
X380546Y-151481D01*
X379673Y-154397D01*
X379454Y-157022D01*
X379891Y-159647D01*
X380546Y-161397D01*
X381856Y-163147D01*
X383385Y-164314D01*
X384913Y-164897D01*
X386441D01*
X387970Y-164314D01*
X389280Y-163439D01*
X390372Y-162273D01*
G01X404159Y-155564D02*
X405033Y-154689D01*
X405688Y-153231D01*
X406125Y-151188D01*
X405688Y-149439D01*
X404815Y-148272D01*
X403286Y-147397D01*
X397391D01*
Y-164897D01*
X404596D01*
X406125Y-163731D01*
X406998Y-161980D01*
X407435Y-159939D01*
X406998Y-157897D01*
X405688Y-156147D01*
X404159Y-155564D01*
X397391D01*
G01X413363Y-170730D02*
X426463D01*
G01X432391Y-164897D02*
Y-147397D01*
X442435Y-164897D01*
Y-147397D01*
G01X454913Y-164897D02*
X453166Y-164605D01*
X451638Y-163439D01*
X450328Y-161689D01*
X449454Y-159647D01*
X449018Y-157314D01*
Y-154980D01*
X449454Y-152647D01*
X450328Y-150605D01*
X451638Y-148856D01*
X453166Y-147689D01*
X454913Y-147397D01*
X456659Y-147689D01*
X458188Y-148856D01*
X459498Y-150605D01*
X460372Y-152647D01*
X460808Y-154980D01*
Y-157314D01*
X460372Y-159647D01*
X459498Y-161689D01*
X458188Y-163439D01*
X456659Y-164605D01*
X454913Y-164897D01*
G01X505754Y-147397D02*
X511213Y-164897D01*
X516672Y-147397D01*
G01X533080Y-164897D02*
X524346D01*
Y-147397D01*
X533080D01*
G01X529586Y-155855D02*
X524346D01*
G01X541846Y-164897D02*
Y-147397D01*
X547305D01*
X549051Y-148272D01*
X550143Y-149439D01*
X550580Y-151772D01*
X550143Y-154106D01*
X548833Y-155564D01*
X547305Y-156439D01*
X541846D01*
G01X547305D02*
X550580Y-164897D01*
G01X563713Y-165480D02*
X563276Y-165189D01*
Y-164605D01*
X563713Y-164314D01*
X564150Y-164605D01*
Y-165189D01*
X563713Y-165480D01*
G01X537463Y-209897D02*
Y-192397D01*
X534843Y-195897D01*
G01Y-209897D02*
X540083D01*
G01X630546Y-147397D02*
Y-164897D01*
X639280D01*
G01X656343D02*
Y-153231D01*
G01Y-155272D02*
X655470Y-154106D01*
X654159Y-153522D01*
X652631Y-153231D01*
X651103Y-153814D01*
X649793Y-154980D01*
X648919Y-156730D01*
X648483Y-159064D01*
X648919Y-161397D01*
X649793Y-163147D01*
X651103Y-164314D01*
X652631Y-164897D01*
X654159Y-164605D01*
X655470Y-163731D01*
X656343Y-162564D01*
G01X665328Y-170147D02*
X666638Y-170730D01*
X668385Y-170147D01*
X669476Y-168981D01*
X670350Y-167522D01*
X671659Y-162856D01*
X674498Y-153231D01*
G01X667511D02*
X671659Y-162856D01*
G01X684138Y-157022D02*
X691125D01*
X690470Y-154980D01*
X689378Y-153814D01*
X687850Y-153231D01*
X686321Y-153522D01*
X685011Y-154397D01*
X684138Y-156439D01*
X683701Y-158189D01*
Y-159939D01*
X684138Y-161689D01*
X685230Y-163439D01*
X686540Y-164605D01*
X688068Y-164897D01*
X689596Y-164314D01*
X691125Y-162564D01*
G01X701856Y-164897D02*
Y-153231D01*
G01Y-155564D02*
X702948Y-154397D01*
X704040Y-153522D01*
X705568Y-153231D01*
X706659Y-153522D01*
X707970Y-154397D01*
G01X719138Y-162856D02*
X720230Y-164022D01*
X721758Y-164897D01*
X723068D01*
X724378Y-164314D01*
X725251Y-163439D01*
X725688Y-162273D01*
X725470Y-160522D01*
X724596Y-159647D01*
X720666Y-157897D01*
X719793Y-155855D01*
X720230Y-154397D01*
X721103Y-153522D01*
X722413Y-153231D01*
X723723Y-153522D01*
X725033Y-154397D01*
G01X643663Y-192397D02*
Y-209897D01*
G01X638641Y-192397D02*
X648685D01*
G01X656578Y-207564D02*
X658325Y-209022D01*
X660290Y-209897D01*
X662036D01*
X663783Y-209022D01*
X665093Y-207564D01*
X665748Y-205522D01*
X665311Y-203481D01*
X664220Y-201730D01*
X662255Y-200564D01*
X659635Y-199980D01*
X658106Y-198814D01*
X657451Y-196772D01*
X657888Y-194730D01*
X658980Y-193272D01*
X660508Y-192397D01*
X662036D01*
X663565Y-192980D01*
X664875Y-194439D01*
G01X676043Y-192397D02*
X681283D01*
G01X678663D02*
Y-209897D01*
G01X676043D02*
X681283D01*
G01X691796Y-192397D02*
Y-209897D01*
X700530D01*
G01X708860D02*
Y-192397D01*
G01X717156D02*
X708860Y-203189D01*
G01X718466Y-209897D02*
X712571Y-198231D01*
G01X781410Y-164897D02*
Y-147397D01*
X785776D01*
X787523Y-148272D01*
X788833Y-149439D01*
X789925Y-151188D01*
X790798Y-153231D01*
X791016Y-156147D01*
X790798Y-159064D01*
X789925Y-161106D01*
X788833Y-162856D01*
X787523Y-164022D01*
X785776Y-164897D01*
X781410D01*
G01X800438Y-157022D02*
X807425D01*
X806770Y-154980D01*
X805678Y-153814D01*
X804150Y-153231D01*
X802621Y-153522D01*
X801311Y-154397D01*
X800438Y-156439D01*
X800001Y-158189D01*
Y-159939D01*
X800438Y-161689D01*
X801530Y-163439D01*
X802840Y-164605D01*
X804368Y-164897D01*
X805896Y-164314D01*
X807425Y-162564D01*
G01X817938Y-162856D02*
X819030Y-164022D01*
X820558Y-164897D01*
X821868D01*
X823178Y-164314D01*
X824051Y-163439D01*
X824488Y-162273D01*
X824270Y-160522D01*
X823396Y-159647D01*
X819466Y-157897D01*
X818593Y-155855D01*
X819030Y-154397D01*
X819903Y-153522D01*
X821213Y-153231D01*
X822523Y-153522D01*
X823833Y-154397D01*
G01X838713Y-153231D02*
Y-164897D01*
G01Y-148564D02*
X838276Y-148272D01*
Y-147689D01*
X838713Y-147397D01*
X839150Y-147689D01*
Y-148272D01*
X838713Y-148564D01*
G01X853156Y-169272D02*
X854685Y-170439D01*
X856431Y-170730D01*
X857959Y-170439D01*
X859270Y-168981D01*
X860143Y-166939D01*
Y-153231D01*
G01Y-155564D02*
X859270Y-154397D01*
X857959Y-153522D01*
X856431Y-153231D01*
X854685Y-153814D01*
X853593Y-154980D01*
X852719Y-157022D01*
X852283Y-159064D01*
X852501Y-160814D01*
X853375Y-162856D01*
X854685Y-164314D01*
X856431Y-164897D01*
X857741Y-164605D01*
X859270Y-163439D01*
X860143Y-162273D01*
G01X870001Y-164897D02*
Y-153231D01*
G01Y-156147D02*
X870875Y-154689D01*
X872185Y-153522D01*
X873931Y-153231D01*
X875459Y-153522D01*
X876770Y-154689D01*
X877425Y-156730D01*
Y-164897D01*
G01X887938Y-157022D02*
X894925D01*
X894270Y-154980D01*
X893178Y-153814D01*
X891650Y-153231D01*
X890121Y-153522D01*
X888811Y-154397D01*
X887938Y-156439D01*
X887501Y-158189D01*
Y-159939D01*
X887938Y-161689D01*
X889030Y-163439D01*
X890340Y-164605D01*
X891868Y-164897D01*
X893396Y-164314D01*
X894925Y-162564D01*
G01X905656Y-164897D02*
Y-153231D01*
G01Y-155564D02*
X906748Y-154397D01*
X907840Y-153522D01*
X909368Y-153231D01*
X910459Y-153522D01*
X911770Y-154397D01*
G01X825596Y-209897D02*
Y-192397D01*
X831055D01*
X832801Y-193272D01*
X833893Y-194439D01*
X834330Y-196772D01*
X833893Y-199106D01*
X832583Y-200564D01*
X831055Y-201439D01*
X825596D01*
G01X831055D02*
X834330Y-209897D01*
G01X847463D02*
X846153Y-209605D01*
X844843Y-208439D01*
X843969Y-206397D01*
X843533Y-204064D01*
X843969Y-201730D01*
X844843Y-199689D01*
X846153Y-198522D01*
X847463Y-198231D01*
X848773Y-198522D01*
X850083Y-199689D01*
X850956Y-201730D01*
X851175Y-204064D01*
X850956Y-206397D01*
X850083Y-208439D01*
X848773Y-209605D01*
X847463Y-209897D01*
G01X861033D02*
Y-192397D01*
G01Y-201147D02*
X862125Y-199397D01*
X863435Y-198522D01*
X864745Y-198231D01*
X866709Y-198814D01*
X868020Y-199980D01*
X868893Y-202022D01*
Y-204355D01*
X868456Y-206689D01*
X867583Y-208439D01*
X866055Y-209605D01*
X864745Y-209897D01*
X863435Y-209605D01*
X862125Y-208731D01*
X861033Y-207273D01*
G01X952413Y-209897D02*
Y-192397D01*
X949793Y-195897D01*
G01Y-209897D02*
X955033D01*
G01X969913Y-192397D02*
X968166Y-192980D01*
X966856Y-194439D01*
X965983Y-196188D01*
X965328Y-198522D01*
X965110Y-201147D01*
X965328Y-203772D01*
X965983Y-206106D01*
X966856Y-207856D01*
X968166Y-209314D01*
X969913Y-209897D01*
X971659Y-209314D01*
X972970Y-207856D01*
X973843Y-206106D01*
X974498Y-203772D01*
X974716Y-201147D01*
X974498Y-198522D01*
X973843Y-196188D01*
X972970Y-194439D01*
X971659Y-192980D01*
X969913Y-192397D01*
G01X983483Y-210480D02*
X991343Y-192397D01*
G01X1004913Y-209897D02*
Y-192397D01*
X1002293Y-195897D01*
G01Y-209897D02*
X1007533D01*
G01X1018265Y-202606D02*
X1019793Y-200564D01*
X1021103Y-199397D01*
X1022850Y-198814D01*
X1024378Y-199397D01*
X1025470Y-200564D01*
X1026343Y-202314D01*
X1026561Y-204355D01*
X1026343Y-206106D01*
X1025470Y-207856D01*
X1024159Y-209314D01*
X1022631Y-209897D01*
X1020885Y-209314D01*
X1019356Y-207564D01*
X1018483Y-204939D01*
X1018265Y-202022D01*
X1018701Y-198231D01*
X1019356Y-196188D01*
X1020448Y-194147D01*
X1021976Y-192689D01*
X1023505Y-192397D01*
X1025033Y-192980D01*
X1026125Y-194439D01*
G01X1035983Y-210480D02*
X1043843Y-192397D01*
G01X1053265Y-195314D02*
X1054575Y-193564D01*
X1056103Y-192689D01*
X1057850Y-192397D01*
X1060033Y-192980D01*
X1061561Y-194439D01*
X1061998Y-196188D01*
X1061780Y-197939D01*
X1060906Y-199397D01*
X1056540Y-202314D01*
X1054575Y-204355D01*
X1053265Y-207273D01*
X1052828Y-209897D01*
X1061998D01*
G01X1074913Y-192397D02*
X1073166Y-192980D01*
X1071856Y-194439D01*
X1070983Y-196188D01*
X1070328Y-198522D01*
X1070110Y-201147D01*
X1070328Y-203772D01*
X1070983Y-206106D01*
X1071856Y-207856D01*
X1073166Y-209314D01*
X1074913Y-209897D01*
X1076659Y-209314D01*
X1077970Y-207856D01*
X1078843Y-206106D01*
X1079498Y-203772D01*
X1079716Y-201147D01*
X1079498Y-198522D01*
X1078843Y-196188D01*
X1077970Y-194439D01*
X1076659Y-192980D01*
X1074913Y-192397D01*
G01X1092413Y-209897D02*
Y-192397D01*
X1089793Y-195897D01*
G01Y-209897D02*
X1095033D01*
G01X1105765Y-195314D02*
X1107075Y-193564D01*
X1108603Y-192689D01*
X1110350Y-192397D01*
X1112533Y-192980D01*
X1114061Y-194439D01*
X1114498Y-196188D01*
X1114280Y-197939D01*
X1113406Y-199397D01*
X1109040Y-202314D01*
X1107075Y-204355D01*
X1105765Y-207273D01*
X1105328Y-209897D01*
X1114498D01*
G01X1000110Y-164897D02*
Y-147397D01*
X1004476D01*
X1006223Y-148272D01*
X1007533Y-149439D01*
X1008625Y-151188D01*
X1009498Y-153231D01*
X1009716Y-156147D01*
X1009498Y-159064D01*
X1008625Y-161106D01*
X1007533Y-162856D01*
X1006223Y-164022D01*
X1004476Y-164897D01*
X1000110D01*
G01X1026343D02*
Y-153231D01*
G01Y-155272D02*
X1025470Y-154106D01*
X1024159Y-153522D01*
X1022631Y-153231D01*
X1021103Y-153814D01*
X1019793Y-154980D01*
X1018919Y-156730D01*
X1018483Y-159064D01*
X1018919Y-161397D01*
X1019793Y-163147D01*
X1021103Y-164314D01*
X1022631Y-164897D01*
X1024159Y-164605D01*
X1025470Y-163731D01*
X1026343Y-162564D01*
G01X1039913Y-147397D02*
Y-164897D01*
G01X1036856Y-153231D02*
X1042970D01*
G01X1054138Y-157022D02*
X1061125D01*
X1060470Y-154980D01*
X1059378Y-153814D01*
X1057850Y-153231D01*
X1056321Y-153522D01*
X1055011Y-154397D01*
X1054138Y-156439D01*
X1053701Y-158189D01*
Y-159939D01*
X1054138Y-161689D01*
X1055230Y-163439D01*
X1056540Y-164605D01*
X1058068Y-164897D01*
X1059596Y-164314D01*
X1061125Y-162564D01*
G01X-11324Y516942D02*
X-11532Y516609D01*
X-11657Y516234D01*
Y515900D01*
X-11532Y515567D01*
X-11324Y515317D01*
X-11032Y515192D01*
X-10740Y515275D01*
X-10490Y515484D01*
X-10324Y515859D01*
X-10240Y516359D01*
X-10074Y516650D01*
X-9782Y516775D01*
X-9490Y516692D01*
X-9282Y516484D01*
X-9157Y516192D01*
Y515900D01*
X-9240Y515609D01*
X-9449Y515359D01*
G01X-11657Y512967D02*
X-9157D01*
G01X-9990Y509867D02*
X-11657D01*
G01X-9324D02*
X-9282Y509950D01*
X-9199D01*
X-9157Y509867D01*
X-9199Y509784D01*
X-9282D01*
X-9324Y509867D01*
G01X-9157Y506767D02*
X-11657D01*
G01X-9990Y507350D02*
Y506184D01*
G01X-11658Y818815D02*
X-11866Y818482D01*
X-11991Y818107D01*
Y817773D01*
X-11866Y817440D01*
X-11658Y817190D01*
X-11366Y817065D01*
X-11074Y817148D01*
X-10824Y817357D01*
X-10658Y817732D01*
X-10574Y818232D01*
X-10408Y818523D01*
X-10116Y818648D01*
X-9824Y818565D01*
X-9616Y818357D01*
X-9491Y818065D01*
Y817773D01*
X-9574Y817482D01*
X-9783Y817232D01*
G01X-11991Y814840D02*
X-9491D01*
G01X-10324Y811740D02*
X-11991D01*
G01X-9658D02*
X-9616Y811823D01*
X-9533D01*
X-9491Y811740D01*
X-9533Y811657D01*
X-9616D01*
X-9658Y811740D01*
G01X-9491Y808640D02*
X-11991D01*
G01X-10324Y809223D02*
Y808057D01*
G01X-11324Y1501194D02*
X-11532Y1500861D01*
X-11657Y1500486D01*
Y1500152D01*
X-11532Y1499819D01*
X-11324Y1499569D01*
X-11032Y1499444D01*
X-10740Y1499527D01*
X-10490Y1499736D01*
X-10324Y1500111D01*
X-10240Y1500611D01*
X-10074Y1500902D01*
X-9782Y1501027D01*
X-9490Y1500944D01*
X-9282Y1500736D01*
X-9157Y1500444D01*
Y1500152D01*
X-9240Y1499861D01*
X-9449Y1499611D01*
G01X-11657Y1497219D02*
X-9157D01*
G01X-9990Y1494119D02*
X-11657D01*
G01X-9324D02*
X-9282Y1494202D01*
X-9199D01*
X-9157Y1494119D01*
X-9199Y1494036D01*
X-9282D01*
X-9324Y1494119D01*
G01X-9157Y1491019D02*
X-11657D01*
G01X-9990Y1491602D02*
Y1490436D01*
G01X-11658Y1803067D02*
X-11866Y1802734D01*
X-11991Y1802359D01*
Y1802025D01*
X-11866Y1801692D01*
X-11658Y1801442D01*
X-11366Y1801317D01*
X-11074Y1801400D01*
X-10824Y1801609D01*
X-10658Y1801984D01*
X-10574Y1802484D01*
X-10408Y1802775D01*
X-10116Y1802900D01*
X-9824Y1802817D01*
X-9616Y1802609D01*
X-9491Y1802317D01*
Y1802025D01*
X-9574Y1801734D01*
X-9783Y1801484D01*
G01X-11991Y1799092D02*
X-9491D01*
G01X-10324Y1795992D02*
X-11991D01*
G01X-9658D02*
X-9616Y1796075D01*
X-9533D01*
X-9491Y1795992D01*
X-9533Y1795909D01*
X-9616D01*
X-9658Y1795992D01*
G01X-9491Y1792892D02*
X-11991D01*
G01X-10324Y1793475D02*
Y1792309D01*
G01X14999Y238550D02*
Y248550D01*
G01X21999D02*
Y238550D01*
G01Y243550D02*
X14999D01*
G01X25432Y238550D02*
Y248550D01*
X28766D01*
X30099Y248050D01*
X31099Y247383D01*
X31932Y246383D01*
X32599Y245216D01*
X32766Y243550D01*
X32599Y241883D01*
X31932Y240717D01*
X31099Y239716D01*
X30099Y239050D01*
X28766Y238550D01*
X25432D01*
G01X36032D02*
Y248550D01*
X39366D01*
X40699Y248050D01*
X41699Y247383D01*
X42532Y246383D01*
X43199Y245216D01*
X43366Y243550D01*
X43199Y241883D01*
X42532Y240717D01*
X41699Y239716D01*
X40699Y239050D01*
X39366Y238550D01*
X36032D01*
G01X50299D02*
Y248550D01*
X48299Y246550D01*
G01Y238550D02*
X52299D01*
G01X62899D02*
Y248550D01*
X56732Y241383D01*
X65066D01*
G01X66499Y235217D02*
X76499D01*
G01X78766Y248550D02*
Y238550D01*
X85432D01*
G01X96032D02*
X89366D01*
Y248550D01*
X96032D01*
G01X93366Y243717D02*
X89366D01*
G01X99632Y238550D02*
Y248550D01*
X102966D01*
X104299Y248050D01*
X105299Y247383D01*
X106132Y246383D01*
X106799Y245216D01*
X106966Y243550D01*
X106799Y241883D01*
X106132Y240717D01*
X105299Y239716D01*
X104299Y239050D01*
X102966Y238550D01*
X99632D01*
G01X0Y339917D02*
X25843D01*
Y367517D01*
X20643D01*
Y703317D01*
X25843D01*
Y730917D01*
X0D01*
Y423026D01*
X1969Y421057D01*
X19883D01*
G02Y413577I0J-3740D01*
G01X1969D01*
X0Y411608D01*
Y339917D01*
G01X19842Y823050D02*
X1970D01*
X1Y821081D01*
Y752381D01*
X1970Y750412D01*
X25843D01*
Y887420D01*
X1970D01*
X1Y885451D01*
Y832499D01*
X1970Y830530D01*
X19883D01*
G02Y823050I0J-3740D01*
G01X19842D01*
G01X14765Y977250D02*
X24765Y970250D01*
G01Y977250D02*
X14765Y970250D01*
G01Y963150D02*
X24765D01*
X22765Y965150D01*
G01X14765D02*
Y961150D01*
G01Y955883D02*
X24765D01*
Y951883D01*
X24265Y950550D01*
X23098Y949550D01*
X21765Y949217D01*
X20432Y949550D01*
X19432Y950383D01*
X18931Y951883D01*
Y955883D01*
G01X23932Y938283D02*
X24432Y939283D01*
X24765Y940450D01*
Y941783D01*
X24265Y943284D01*
X23432Y944450D01*
X22432Y945283D01*
X20765Y945950D01*
X19265Y946117D01*
X17765Y945783D01*
X16765Y945283D01*
X15765Y944283D01*
X15098Y943117D01*
X14765Y941950D01*
Y940783D01*
X15098Y939617D01*
X15598Y938617D01*
X16265Y937783D01*
G01X24765Y933350D02*
Y929350D01*
G01Y931350D02*
X14765D01*
G01Y933350D02*
Y929350D01*
G01Y917417D02*
Y924083D01*
X24765D01*
Y917417D01*
G01X19932Y920083D02*
Y924083D01*
G01X11432Y915150D02*
Y905150D01*
G01X20098Y898217D02*
X20598Y897550D01*
X21431Y897050D01*
X22598Y896717D01*
X23598Y897050D01*
X24265Y897717D01*
X24765Y898883D01*
Y903383D01*
X14765D01*
Y897883D01*
X15432Y896717D01*
X16432Y896050D01*
X17598Y895717D01*
X18765Y896050D01*
X19765Y897050D01*
X20098Y898217D01*
Y903383D01*
G01X8661Y1068425D02*
Y1070925D01*
X9702D01*
X10036Y1070800D01*
X10244Y1070633D01*
X10327Y1070300D01*
X10244Y1069967D01*
X9994Y1069758D01*
X9702Y1069633D01*
X8661D01*
G01X9702D02*
X10327Y1068425D01*
G01X11677Y1068800D02*
X11927Y1068592D01*
X12219Y1068467D01*
X12594Y1068425D01*
X12969Y1068508D01*
X13261Y1068675D01*
X13469Y1068967D01*
X13511Y1069300D01*
X13427Y1069633D01*
X13219Y1069842D01*
X12927Y1070008D01*
X12636Y1070050D01*
X12344Y1070008D01*
X11969Y1069842D01*
X12094Y1070925D01*
X13219D01*
G01X15694D02*
X15361Y1070842D01*
X15111Y1070633D01*
X14944Y1070383D01*
X14819Y1070050D01*
X14777Y1069675D01*
X14819Y1069300D01*
X14944Y1068967D01*
X15111Y1068717D01*
X15361Y1068508D01*
X15694Y1068425D01*
X16027Y1068508D01*
X16277Y1068717D01*
X16444Y1068967D01*
X16569Y1069300D01*
X16611Y1069675D01*
X16569Y1070050D01*
X16444Y1070383D01*
X16277Y1070633D01*
X16027Y1070842D01*
X15694Y1070925D01*
G01X18002Y1070508D02*
X18252Y1070758D01*
X18544Y1070883D01*
X18877Y1070925D01*
X19294Y1070842D01*
X19586Y1070633D01*
X19669Y1070383D01*
X19627Y1070133D01*
X19461Y1069925D01*
X18627Y1069508D01*
X18252Y1069217D01*
X18002Y1068800D01*
X17919Y1068425D01*
X19669D01*
G01X17399Y1067050D02*
Y1063050D01*
X24799D01*
G01X31599Y1062550D02*
X17599D01*
G01Y1049550D02*
X31599D01*
G01X17599Y1062550D02*
Y1049550D01*
G01X13416Y1168050D02*
Y1173050D01*
X16582D01*
G01X15416Y1170633D02*
X13416D01*
G01X20599Y1168050D02*
Y1173050D01*
X19599Y1172050D01*
G01Y1168050D02*
X21599D01*
G01X24616Y1170133D02*
X25199Y1170717D01*
X25699Y1171050D01*
X26366Y1171217D01*
X26949Y1171050D01*
X27366Y1170717D01*
X27699Y1170217D01*
X27782Y1169633D01*
X27699Y1169133D01*
X27366Y1168633D01*
X26866Y1168217D01*
X26282Y1168050D01*
X25616Y1168217D01*
X25032Y1168717D01*
X24699Y1169467D01*
X24616Y1170300D01*
X24782Y1171383D01*
X25032Y1171967D01*
X25449Y1172550D01*
X26032Y1172967D01*
X26616Y1173050D01*
X27199Y1172883D01*
X27616Y1172467D01*
G01X31799Y1167883D02*
X31632Y1167967D01*
Y1168133D01*
X31799Y1168217D01*
X31966Y1168133D01*
Y1167967D01*
X31799Y1167883D01*
G01Y1170133D02*
X31632Y1170217D01*
Y1170383D01*
X31799Y1170467D01*
X31966Y1170383D01*
Y1170217D01*
X31799Y1170133D01*
G01X35566Y1169050D02*
X36066Y1168467D01*
X36732Y1168133D01*
X37482Y1168050D01*
X38149Y1168133D01*
X38816Y1168550D01*
X39232Y1169050D01*
X39316Y1169550D01*
X39149Y1170133D01*
X38566Y1170550D01*
X37982Y1170717D01*
X37232D01*
G01X37982D02*
X38482Y1170967D01*
X38899Y1171383D01*
X39066Y1171883D01*
X38899Y1172383D01*
X38482Y1172800D01*
X37732Y1173050D01*
X36982Y1172967D01*
X36232Y1172633D01*
G01X40916Y1168050D02*
X42999Y1173050D01*
X45082Y1168050D01*
G01X44332Y1169800D02*
X41666D01*
G01X47099Y1167883D02*
X50099Y1173050D01*
G01X54199Y1168050D02*
Y1173050D01*
X53199Y1172050D01*
G01Y1168050D02*
X55199D01*
G01X57966Y1168800D02*
X58466Y1168383D01*
X59049Y1168133D01*
X59799Y1168050D01*
X60549Y1168217D01*
X61132Y1168550D01*
X61549Y1169133D01*
X61632Y1169800D01*
X61466Y1170467D01*
X61049Y1170883D01*
X60466Y1171217D01*
X59882Y1171300D01*
X59299Y1171217D01*
X58549Y1170883D01*
X58799Y1173050D01*
X61049D01*
G01X63316D02*
X65399Y1168050D01*
X67482Y1173050D01*
G01X15899Y1309050D02*
Y1306550D01*
G01X14941Y1309050D02*
X16857D01*
G01X18166Y1306550D02*
Y1309050D01*
X19166D01*
X19499Y1308925D01*
X19749Y1308633D01*
X19832Y1308300D01*
X19749Y1307967D01*
X19541Y1307717D01*
X19166Y1307592D01*
X18166D01*
G01X21182Y1306925D02*
X21432Y1306717D01*
X21724Y1306592D01*
X22099Y1306550D01*
X22474Y1306633D01*
X22766Y1306800D01*
X22974Y1307092D01*
X23016Y1307425D01*
X22932Y1307758D01*
X22724Y1307967D01*
X22432Y1308133D01*
X22141Y1308175D01*
X21849Y1308133D01*
X21474Y1307967D01*
X21599Y1309050D01*
X22724D01*
G01X0Y1324169D02*
X25843D01*
Y1351769D01*
X20643D01*
Y1687569D01*
X25843D01*
Y1715169D01*
X0D01*
Y1407278D01*
X1969Y1405309D01*
X19883D01*
G02Y1397829I0J-3740D01*
G01X1969D01*
X0Y1395860D01*
Y1324169D01*
G01X19842Y1807302D02*
X1970D01*
X1Y1805333D01*
Y1736633D01*
X1970Y1734664D01*
X25843D01*
Y1871672D01*
X1970D01*
X1Y1869703D01*
Y1816751D01*
X1970Y1814782D01*
X19883D01*
G02Y1807302I0J-3740D01*
G01X19842D01*
G01X3425Y1934650D02*
Y1937150D01*
X4425D01*
X4758Y1937025D01*
X5008Y1936733D01*
X5091Y1936400D01*
X5008Y1936067D01*
X4800Y1935817D01*
X4425Y1935692D01*
X3425D01*
G01X6525Y1934650D02*
Y1937150D01*
X7566D01*
X7900Y1937025D01*
X8108Y1936858D01*
X8191Y1936525D01*
X8108Y1936192D01*
X7858Y1935983D01*
X7566Y1935858D01*
X6525D01*
G01X7566D02*
X8191Y1934650D01*
G01X9541Y1935150D02*
X9791Y1934858D01*
X10125Y1934692D01*
X10500Y1934650D01*
X10833Y1934692D01*
X11166Y1934900D01*
X11375Y1935150D01*
X11416Y1935400D01*
X11333Y1935692D01*
X11041Y1935900D01*
X10750Y1935983D01*
X10375D01*
G01X10750D02*
X11000Y1936108D01*
X11208Y1936317D01*
X11291Y1936567D01*
X11208Y1936817D01*
X11000Y1937025D01*
X10625Y1937150D01*
X10250Y1937108D01*
X9875Y1936942D01*
G01X12850Y1934942D02*
X13141Y1934733D01*
X13475Y1934650D01*
X13808Y1934733D01*
X14100Y1934983D01*
X14308Y1935358D01*
X14391Y1935733D01*
Y1936192D01*
X14308Y1936567D01*
X14100Y1936900D01*
X13850Y1937067D01*
X13558Y1937150D01*
X13225Y1937067D01*
X12975Y1936900D01*
X12808Y1936650D01*
X12725Y1936317D01*
X12808Y1936025D01*
X13016Y1935733D01*
X13266Y1935567D01*
X13558Y1935525D01*
X13891Y1935608D01*
X14141Y1935817D01*
X14391Y1936192D01*
G01X16299Y1938050D02*
Y1934050D01*
X23699D01*
G01X14500Y1921517D02*
X12000D01*
Y1922517D01*
X12125Y1922850D01*
X12417Y1923100D01*
X12750Y1923183D01*
X13083Y1923100D01*
X13333Y1922892D01*
X13458Y1922517D01*
Y1921517D01*
G01X14500Y1924617D02*
X12000D01*
Y1925658D01*
X12125Y1925992D01*
X12292Y1926200D01*
X12625Y1926283D01*
X12958Y1926200D01*
X13167Y1925950D01*
X13292Y1925658D01*
Y1924617D01*
G01Y1925658D02*
X14500Y1926283D01*
G01Y1929050D02*
X12000D01*
X13792Y1927508D01*
Y1929592D01*
G01X14500Y1931567D02*
X13958Y1931650D01*
X13500Y1931775D01*
X13083Y1931942D01*
X12625Y1932150D01*
X12000Y1932483D01*
Y1930817D01*
G01X10203Y1921345D02*
X7703D01*
Y1922345D01*
X7828Y1922678D01*
X8120Y1922928D01*
X8453Y1923011D01*
X8786Y1922928D01*
X9036Y1922720D01*
X9161Y1922345D01*
Y1921345D01*
G01X10203Y1924445D02*
X7703D01*
Y1925486D01*
X7828Y1925820D01*
X7995Y1926028D01*
X8328Y1926111D01*
X8661Y1926028D01*
X8870Y1925778D01*
X8995Y1925486D01*
Y1924445D01*
G01Y1925486D02*
X10203Y1926111D01*
G01Y1928878D02*
X7703D01*
X9495Y1927336D01*
Y1929420D01*
G01X10203Y1931478D02*
X10161Y1931770D01*
X10036Y1932103D01*
X9828Y1932311D01*
X9536Y1932395D01*
X9245Y1932311D01*
X8995Y1932061D01*
X8870Y1931686D01*
Y1931270D01*
X8786Y1931020D01*
X8578Y1930811D01*
X8286Y1930728D01*
X7995Y1930853D01*
X7786Y1931145D01*
X7703Y1931478D01*
X7786Y1931811D01*
X7995Y1932103D01*
X8286Y1932228D01*
X8578Y1932145D01*
X8786Y1931936D01*
X8870Y1931686D01*
Y1931270D01*
X8995Y1930895D01*
X9245Y1930645D01*
X9536Y1930561D01*
X9828Y1930645D01*
X10036Y1930853D01*
X10161Y1931186D01*
X10203Y1931478D01*
G01X5672Y1920957D02*
X3172D01*
Y1921998D01*
X3297Y1922332D01*
X3464Y1922540D01*
X3797Y1922623D01*
X4130Y1922540D01*
X4339Y1922290D01*
X4464Y1921998D01*
Y1920957D01*
G01Y1921998D02*
X5672Y1922623D01*
G01Y1925390D02*
X3172D01*
X4964Y1923848D01*
Y1925932D01*
G01X5672Y1927990D02*
X5630Y1928282D01*
X5505Y1928615D01*
X5297Y1928823D01*
X5005Y1928907D01*
X4714Y1928823D01*
X4464Y1928573D01*
X4339Y1928198D01*
Y1927782D01*
X4255Y1927532D01*
X4047Y1927323D01*
X3755Y1927240D01*
X3464Y1927365D01*
X3255Y1927657D01*
X3172Y1927990D01*
X3255Y1928323D01*
X3464Y1928615D01*
X3755Y1928740D01*
X4047Y1928657D01*
X4255Y1928448D01*
X4339Y1928198D01*
Y1927782D01*
X4464Y1927407D01*
X4714Y1927157D01*
X5005Y1927073D01*
X5297Y1927157D01*
X5505Y1927365D01*
X5630Y1927698D01*
X5672Y1927990D01*
G01X4630Y1930298D02*
X4339Y1930590D01*
X4172Y1930840D01*
X4089Y1931173D01*
X4172Y1931465D01*
X4339Y1931673D01*
X4589Y1931840D01*
X4880Y1931882D01*
X5130Y1931840D01*
X5380Y1931673D01*
X5589Y1931423D01*
X5672Y1931132D01*
X5589Y1930798D01*
X5339Y1930507D01*
X4964Y1930340D01*
X4547Y1930298D01*
X4005Y1930382D01*
X3714Y1930507D01*
X3422Y1930715D01*
X3214Y1931007D01*
X3172Y1931298D01*
X3255Y1931590D01*
X3464Y1931798D01*
G01X3425Y1954650D02*
Y1957150D01*
X4425D01*
X4758Y1957025D01*
X5008Y1956733D01*
X5091Y1956400D01*
X5008Y1956067D01*
X4800Y1955817D01*
X4425Y1955692D01*
X3425D01*
G01X8275Y1956942D02*
X8025Y1957067D01*
X7733Y1957150D01*
X7400D01*
X7025Y1957025D01*
X6733Y1956817D01*
X6525Y1956567D01*
X6358Y1956150D01*
X6316Y1955775D01*
X6400Y1955400D01*
X6525Y1955150D01*
X6775Y1954900D01*
X7066Y1954733D01*
X7358Y1954650D01*
X7650D01*
X7941Y1954733D01*
X8191Y1954858D01*
X8400Y1955025D01*
G01X9541Y1955150D02*
X9791Y1954858D01*
X10125Y1954692D01*
X10500Y1954650D01*
X10833Y1954692D01*
X11166Y1954900D01*
X11375Y1955150D01*
X11416Y1955400D01*
X11333Y1955692D01*
X11041Y1955900D01*
X10750Y1955983D01*
X10375D01*
G01X10750D02*
X11000Y1956108D01*
X11208Y1956317D01*
X11291Y1956567D01*
X11208Y1956817D01*
X11000Y1957025D01*
X10625Y1957150D01*
X10250Y1957108D01*
X9875Y1956942D01*
G01X12766Y1956733D02*
X13016Y1956983D01*
X13308Y1957108D01*
X13641Y1957150D01*
X14058Y1957067D01*
X14350Y1956858D01*
X14433Y1956608D01*
X14391Y1956358D01*
X14225Y1956150D01*
X13391Y1955733D01*
X13016Y1955442D01*
X12766Y1955025D01*
X12683Y1954650D01*
X14433D01*
G01X3425Y1942650D02*
Y1945150D01*
X4425D01*
X4758Y1945025D01*
X5008Y1944733D01*
X5091Y1944400D01*
X5008Y1944067D01*
X4800Y1943817D01*
X4425Y1943692D01*
X3425D01*
G01X6525Y1942650D02*
Y1945150D01*
X7566D01*
X7900Y1945025D01*
X8108Y1944858D01*
X8191Y1944525D01*
X8108Y1944192D01*
X7858Y1943983D01*
X7566Y1943858D01*
X6525D01*
G01X7566D02*
X8191Y1942650D01*
G01X10958D02*
Y1945150D01*
X9416Y1943358D01*
X11500D01*
G01X13558Y1942650D02*
Y1945150D01*
X13058Y1944650D01*
G01Y1942650D02*
X14058D01*
G01X16299Y1946050D02*
Y1942050D01*
X23699D01*
G01X3425Y1946650D02*
Y1949150D01*
X4425D01*
X4758Y1949025D01*
X5008Y1948733D01*
X5091Y1948400D01*
X5008Y1948067D01*
X4800Y1947817D01*
X4425Y1947692D01*
X3425D01*
G01X6525Y1946650D02*
Y1949150D01*
X7566D01*
X7900Y1949025D01*
X8108Y1948858D01*
X8191Y1948525D01*
X8108Y1948192D01*
X7858Y1947983D01*
X7566Y1947858D01*
X6525D01*
G01X7566D02*
X8191Y1946650D01*
G01X10958D02*
Y1949150D01*
X9416Y1947358D01*
X11500D01*
G01X12641Y1947150D02*
X12891Y1946858D01*
X13225Y1946692D01*
X13600Y1946650D01*
X13933Y1946692D01*
X14266Y1946900D01*
X14475Y1947150D01*
X14516Y1947400D01*
X14433Y1947692D01*
X14141Y1947900D01*
X13850Y1947983D01*
X13475D01*
G01X13850D02*
X14100Y1948108D01*
X14308Y1948317D01*
X14391Y1948567D01*
X14308Y1948817D01*
X14100Y1949025D01*
X13725Y1949150D01*
X13350Y1949108D01*
X12975Y1948942D01*
G01X23699Y1946050D02*
Y1950050D01*
X16299D01*
G01X3425Y1950650D02*
Y1953150D01*
X4425D01*
X4758Y1953025D01*
X5008Y1952733D01*
X5091Y1952400D01*
X5008Y1952067D01*
X4800Y1951817D01*
X4425Y1951692D01*
X3425D01*
G01X6525Y1950650D02*
Y1953150D01*
X7566D01*
X7900Y1953025D01*
X8108Y1952858D01*
X8191Y1952525D01*
X8108Y1952192D01*
X7858Y1951983D01*
X7566Y1951858D01*
X6525D01*
G01X7566D02*
X8191Y1950650D01*
G01X10958D02*
Y1953150D01*
X9416Y1951358D01*
X11500D01*
G01X12641Y1951025D02*
X12891Y1950817D01*
X13183Y1950692D01*
X13558Y1950650D01*
X13933Y1950733D01*
X14225Y1950900D01*
X14433Y1951192D01*
X14475Y1951525D01*
X14391Y1951858D01*
X14183Y1952067D01*
X13891Y1952233D01*
X13600Y1952275D01*
X13308Y1952233D01*
X12933Y1952067D01*
X13058Y1953150D01*
X14183D01*
G01X23699Y1950050D02*
Y1954050D01*
X16299D01*
G01X3425Y1938650D02*
Y1941150D01*
X4466D01*
X4800Y1941025D01*
X5008Y1940858D01*
X5091Y1940525D01*
X5008Y1940192D01*
X4758Y1939983D01*
X4466Y1939858D01*
X3425D01*
G01X4466D02*
X5091Y1938650D01*
G01X7858D02*
Y1941150D01*
X6316Y1939358D01*
X8400D01*
G01X10458Y1938650D02*
X10750Y1938692D01*
X11083Y1938817D01*
X11291Y1939025D01*
X11375Y1939317D01*
X11291Y1939608D01*
X11041Y1939858D01*
X10666Y1939983D01*
X10250D01*
X10000Y1940067D01*
X9791Y1940275D01*
X9708Y1940567D01*
X9833Y1940858D01*
X10125Y1941067D01*
X10458Y1941150D01*
X10791Y1941067D01*
X11083Y1940858D01*
X11208Y1940567D01*
X11125Y1940275D01*
X10916Y1940067D01*
X10666Y1939983D01*
X10250D01*
X9875Y1939858D01*
X9625Y1939608D01*
X9541Y1939317D01*
X9625Y1939025D01*
X9833Y1938817D01*
X10166Y1938692D01*
X10458Y1938650D01*
G01X13475D02*
X13558Y1939192D01*
X13683Y1939650D01*
X13850Y1940067D01*
X14058Y1940525D01*
X14391Y1941150D01*
X12725D01*
G01X23699Y1938050D02*
Y1942050D01*
X16299D01*
G01X7754Y1958716D02*
X5254D01*
Y1959716D01*
X5379Y1960049D01*
X5671Y1960299D01*
X6004Y1960382D01*
X6337Y1960299D01*
X6587Y1960091D01*
X6712Y1959716D01*
Y1958716D01*
G01X7754Y1961816D02*
X5254D01*
Y1962857D01*
X5379Y1963191D01*
X5546Y1963399D01*
X5879Y1963482D01*
X6212Y1963399D01*
X6421Y1963149D01*
X6546Y1962857D01*
Y1961816D01*
G01Y1962857D02*
X7754Y1963482D01*
G01X7254Y1964832D02*
X7546Y1965082D01*
X7712Y1965416D01*
X7754Y1965791D01*
X7712Y1966124D01*
X7504Y1966457D01*
X7254Y1966666D01*
X7004Y1966707D01*
X6712Y1966624D01*
X6504Y1966332D01*
X6421Y1966041D01*
Y1965666D01*
G01Y1966041D02*
X6296Y1966291D01*
X6087Y1966499D01*
X5837Y1966582D01*
X5587Y1966499D01*
X5379Y1966291D01*
X5254Y1965916D01*
X5296Y1965541D01*
X5462Y1965166D01*
G01X7754Y1969349D02*
X5254D01*
X7046Y1967807D01*
Y1969891D01*
G01X3754Y1958716D02*
X1254D01*
Y1959716D01*
X1379Y1960049D01*
X1671Y1960299D01*
X2004Y1960382D01*
X2337Y1960299D01*
X2587Y1960091D01*
X2712Y1959716D01*
Y1958716D01*
G01X3754Y1961816D02*
X1254D01*
Y1962857D01*
X1379Y1963191D01*
X1546Y1963399D01*
X1879Y1963482D01*
X2212Y1963399D01*
X2421Y1963149D01*
X2546Y1962857D01*
Y1961816D01*
G01Y1962857D02*
X3754Y1963482D01*
G01X3254Y1964832D02*
X3546Y1965082D01*
X3712Y1965416D01*
X3754Y1965791D01*
X3712Y1966124D01*
X3504Y1966457D01*
X3254Y1966666D01*
X3004Y1966707D01*
X2712Y1966624D01*
X2504Y1966332D01*
X2421Y1966041D01*
Y1965666D01*
G01Y1966041D02*
X2296Y1966291D01*
X2087Y1966499D01*
X1837Y1966582D01*
X1587Y1966499D01*
X1379Y1966291D01*
X1254Y1965916D01*
X1296Y1965541D01*
X1462Y1965166D01*
G01X3754Y1968849D02*
X3712Y1969141D01*
X3587Y1969474D01*
X3379Y1969682D01*
X3087Y1969766D01*
X2796Y1969682D01*
X2546Y1969432D01*
X2421Y1969057D01*
Y1968641D01*
X2337Y1968391D01*
X2129Y1968182D01*
X1837Y1968099D01*
X1546Y1968224D01*
X1337Y1968516D01*
X1254Y1968849D01*
X1337Y1969182D01*
X1546Y1969474D01*
X1837Y1969599D01*
X2129Y1969516D01*
X2337Y1969307D01*
X2421Y1969057D01*
Y1968641D01*
X2546Y1968266D01*
X2796Y1968016D01*
X3087Y1967932D01*
X3379Y1968016D01*
X3587Y1968224D01*
X3712Y1968557D01*
X3754Y1968849D01*
G01X21999Y1970250D02*
X17999D01*
Y1962850D01*
G01X15754Y1958716D02*
X13254D01*
Y1959716D01*
X13379Y1960049D01*
X13671Y1960299D01*
X14004Y1960382D01*
X14337Y1960299D01*
X14587Y1960091D01*
X14712Y1959716D01*
Y1958716D01*
G01X15754Y1961816D02*
X13254D01*
Y1962857D01*
X13379Y1963191D01*
X13546Y1963399D01*
X13879Y1963482D01*
X14212Y1963399D01*
X14421Y1963149D01*
X14546Y1962857D01*
Y1961816D01*
G01Y1962857D02*
X15754Y1963482D01*
G01Y1966249D02*
X13254D01*
X15046Y1964707D01*
Y1966791D01*
G01X15754Y1969349D02*
X13254D01*
X15046Y1967807D01*
Y1969891D01*
G01X11754Y1958716D02*
X9254D01*
Y1959716D01*
X9379Y1960049D01*
X9671Y1960299D01*
X10004Y1960382D01*
X10337Y1960299D01*
X10587Y1960091D01*
X10712Y1959716D01*
Y1958716D01*
G01X11754Y1961816D02*
X9254D01*
Y1962857D01*
X9379Y1963191D01*
X9546Y1963399D01*
X9879Y1963482D01*
X10212Y1963399D01*
X10421Y1963149D01*
X10546Y1962857D01*
Y1961816D01*
G01Y1962857D02*
X11754Y1963482D01*
G01Y1966249D02*
X9254D01*
X11046Y1964707D01*
Y1966791D01*
G01X10712Y1968057D02*
X10421Y1968349D01*
X10254Y1968599D01*
X10171Y1968932D01*
X10254Y1969224D01*
X10421Y1969432D01*
X10671Y1969599D01*
X10962Y1969641D01*
X11212Y1969599D01*
X11462Y1969432D01*
X11671Y1969182D01*
X11754Y1968891D01*
X11671Y1968557D01*
X11421Y1968266D01*
X11046Y1968099D01*
X10629Y1968057D01*
X10087Y1968141D01*
X9796Y1968266D01*
X9504Y1968474D01*
X9296Y1968766D01*
X9254Y1969057D01*
X9337Y1969349D01*
X9546Y1969557D01*
G01X20000Y1980567D02*
X17500D01*
Y1981567D01*
X17625Y1981900D01*
X17917Y1982150D01*
X18250Y1982233D01*
X18583Y1982150D01*
X18833Y1981942D01*
X18958Y1981567D01*
Y1980567D01*
G01X18750Y1984750D02*
Y1985583D01*
X19500D01*
X19750Y1985333D01*
X19917Y1985042D01*
X20000Y1984625D01*
X19917Y1984208D01*
X19750Y1983917D01*
X19500Y1983667D01*
X19208Y1983500D01*
X18875Y1983417D01*
X18583D01*
X18333Y1983500D01*
X18042Y1983667D01*
X17792Y1983917D01*
X17625Y1984167D01*
X17500Y1984500D01*
Y1984792D01*
X17583Y1985125D01*
X17750Y1985375D01*
G01X19500Y1986683D02*
X19792Y1986933D01*
X19958Y1987267D01*
X20000Y1987642D01*
X19958Y1987975D01*
X19750Y1988308D01*
X19500Y1988517D01*
X19250Y1988558D01*
X18958Y1988475D01*
X18750Y1988183D01*
X18667Y1987892D01*
Y1987517D01*
G01Y1987892D02*
X18542Y1988142D01*
X18333Y1988350D01*
X18083Y1988433D01*
X17833Y1988350D01*
X17625Y1988142D01*
X17500Y1987767D01*
X17542Y1987392D01*
X17708Y1987017D01*
G01X91598Y184261D02*
Y23061D01*
X77998D01*
Y10111D01*
X59798D01*
Y23061D01*
X30898D01*
Y33411D01*
X37598D01*
Y173911D01*
X30898D01*
Y184261D01*
X59798D01*
Y197211D01*
X77998D01*
Y184261D01*
X91598D01*
G01X30167Y108988D02*
X30375Y109321D01*
X30500Y109696D01*
Y110030D01*
X30375Y110363D01*
X30167Y110613D01*
X29875Y110738D01*
X29583Y110655D01*
X29333Y110446D01*
X29167Y110071D01*
X29083Y109571D01*
X28917Y109280D01*
X28625Y109155D01*
X28333Y109238D01*
X28125Y109446D01*
X28000Y109738D01*
Y110030D01*
X28083Y110321D01*
X28292Y110571D01*
G01X30500Y112046D02*
X28000D01*
G01Y113630D02*
X29542Y112046D01*
G01X30500Y113880D02*
X28833Y112755D01*
G01X28000Y116063D02*
X30500D01*
G01X28000Y115105D02*
Y117021D01*
G01X30500Y119163D02*
X28000D01*
X28500Y118663D01*
G01X30500D02*
Y119663D01*
G01X30125Y121346D02*
X30333Y121596D01*
X30458Y121888D01*
X30500Y122263D01*
X30417Y122638D01*
X30250Y122930D01*
X29958Y123138D01*
X29625Y123180D01*
X29292Y123096D01*
X29083Y122888D01*
X28917Y122596D01*
X28875Y122305D01*
X28917Y122013D01*
X29083Y121638D01*
X28000Y121763D01*
Y122888D01*
G01X35999Y205450D02*
X35957Y205117D01*
X35791Y204825D01*
X35541Y204575D01*
X35249Y204408D01*
X34916Y204325D01*
X34582D01*
X34249Y204408D01*
X33957Y204575D01*
X33707Y204825D01*
X33541Y205117D01*
X33499Y205450D01*
X33541Y205783D01*
X33707Y206075D01*
X33957Y206325D01*
X34249Y206492D01*
X34582Y206575D01*
X34916D01*
X35249Y206492D01*
X35541Y206325D01*
X35791Y206075D01*
X35957Y205783D01*
X35999Y205450D01*
G01X35332Y205783D02*
X35999Y206283D01*
G01Y209050D02*
X33499D01*
X35291Y207508D01*
Y209592D01*
G01X35999Y211650D02*
X35957Y211942D01*
X35832Y212275D01*
X35624Y212483D01*
X35332Y212567D01*
X35041Y212483D01*
X34791Y212233D01*
X34666Y211858D01*
Y211442D01*
X34582Y211192D01*
X34374Y210983D01*
X34082Y210900D01*
X33791Y211025D01*
X33582Y211317D01*
X33499Y211650D01*
X33582Y211983D01*
X33791Y212275D01*
X34082Y212400D01*
X34374Y212317D01*
X34582Y212108D01*
X34666Y211858D01*
Y211442D01*
X34791Y211067D01*
X35041Y210817D01*
X35332Y210733D01*
X35624Y210817D01*
X35832Y211025D01*
X35957Y211358D01*
X35999Y211650D01*
G01X53199Y214400D02*
X39199D01*
G01Y201400D02*
X53199D01*
G01X39199Y214400D02*
Y201400D01*
G01X32771Y223738D02*
Y226238D01*
X33812D01*
X34146Y226113D01*
X34354Y225946D01*
X34437Y225613D01*
X34354Y225280D01*
X34104Y225071D01*
X33812Y224946D01*
X32771D01*
G01X33812D02*
X34437Y223738D01*
G01X35787Y224113D02*
X36037Y223905D01*
X36329Y223780D01*
X36704Y223738D01*
X37079Y223821D01*
X37371Y223988D01*
X37579Y224280D01*
X37621Y224613D01*
X37537Y224946D01*
X37329Y225155D01*
X37037Y225321D01*
X36746Y225363D01*
X36454Y225321D01*
X36079Y225155D01*
X36204Y226238D01*
X37329D01*
G01X39804D02*
X39471Y226155D01*
X39221Y225946D01*
X39054Y225696D01*
X38929Y225363D01*
X38887Y224988D01*
X38929Y224613D01*
X39054Y224280D01*
X39221Y224030D01*
X39471Y223821D01*
X39804Y223738D01*
X40137Y223821D01*
X40387Y224030D01*
X40554Y224280D01*
X40679Y224613D01*
X40721Y224988D01*
X40679Y225363D01*
X40554Y225696D01*
X40387Y225946D01*
X40137Y226155D01*
X39804Y226238D01*
G01X43404Y223738D02*
Y226238D01*
X41862Y224446D01*
X43946D01*
G01X27101Y331554D02*
Y334054D01*
G01X28851D02*
Y331554D01*
G01Y332804D02*
X27101D01*
G01X30284Y332596D02*
X30576Y332887D01*
X30826Y333054D01*
X31159Y333137D01*
X31451Y333054D01*
X31659Y332887D01*
X31826Y332637D01*
X31868Y332346D01*
X31826Y332096D01*
X31659Y331846D01*
X31409Y331637D01*
X31118Y331554D01*
X30784Y331637D01*
X30493Y331887D01*
X30326Y332262D01*
X30284Y332679D01*
X30368Y333221D01*
X30493Y333512D01*
X30701Y333804D01*
X30993Y334012D01*
X31284Y334054D01*
X31576Y333971D01*
X31784Y333762D01*
G01X35899Y379326D02*
Y376826D01*
G01X34941Y379326D02*
X36857D01*
G01X38166Y376826D02*
Y379326D01*
X39166D01*
X39499Y379201D01*
X39749Y378909D01*
X39832Y378576D01*
X39749Y378243D01*
X39541Y377993D01*
X39166Y377868D01*
X38166D01*
G01X41307D02*
X41599Y378159D01*
X41849Y378326D01*
X42182Y378409D01*
X42474Y378326D01*
X42682Y378159D01*
X42849Y377909D01*
X42891Y377618D01*
X42849Y377368D01*
X42682Y377118D01*
X42432Y376909D01*
X42141Y376826D01*
X41807Y376909D01*
X41516Y377159D01*
X41349Y377534D01*
X41307Y377951D01*
X41391Y378493D01*
X41516Y378784D01*
X41724Y379076D01*
X42016Y379284D01*
X42307Y379326D01*
X42599Y379243D01*
X42807Y379034D01*
G01X27708Y414880D02*
X27583Y414630D01*
X27500Y414338D01*
Y414005D01*
X27625Y413630D01*
X27833Y413338D01*
X28083Y413130D01*
X28500Y412963D01*
X28875Y412921D01*
X29250Y413005D01*
X29500Y413130D01*
X29750Y413380D01*
X29917Y413671D01*
X30000Y413963D01*
Y414255D01*
X29917Y414546D01*
X29792Y414796D01*
X29625Y415005D01*
G01X30000Y416105D02*
X27500D01*
X30000Y418021D01*
X27500D01*
G01X27917Y419371D02*
X27667Y419621D01*
X27542Y419913D01*
X27500Y420246D01*
X27583Y420663D01*
X27792Y420955D01*
X28042Y421038D01*
X28292Y420996D01*
X28500Y420830D01*
X28917Y419996D01*
X29208Y419621D01*
X29625Y419371D01*
X30000Y419288D01*
Y421038D01*
G01X91598Y589773D02*
Y428573D01*
X77998D01*
Y415623D01*
X59798D01*
Y428573D01*
X30898D01*
Y438923D01*
X37598D01*
Y579423D01*
X30898D01*
Y589773D01*
X59798D01*
Y602723D01*
X77998D01*
Y589773D01*
X91598D01*
G01X32667Y509488D02*
X32875Y509821D01*
X33000Y510196D01*
Y510530D01*
X32875Y510863D01*
X32667Y511113D01*
X32375Y511238D01*
X32083Y511155D01*
X31833Y510946D01*
X31667Y510571D01*
X31583Y510071D01*
X31417Y509780D01*
X31125Y509655D01*
X30833Y509738D01*
X30625Y509946D01*
X30500Y510238D01*
Y510530D01*
X30583Y510821D01*
X30792Y511071D01*
G01X33000Y512546D02*
X30500D01*
G01Y514130D02*
X32042Y512546D01*
G01X33000Y514380D02*
X31333Y513255D01*
G01X30500Y516563D02*
X33000D01*
G01X30500Y515605D02*
Y517521D01*
G01X33000Y519663D02*
X30500D01*
X31000Y519163D01*
G01X33000D02*
Y520163D01*
G01Y523263D02*
X30500D01*
X32292Y521721D01*
Y523805D01*
G01X33400Y605200D02*
Y601200D01*
X40800D01*
G01X30100Y599400D02*
Y595400D01*
X37500D01*
G01X30100Y595300D02*
Y591300D01*
X37500D01*
G01X37700Y599400D02*
Y595400D01*
X45100D01*
G01X36699Y609550D02*
Y613550D01*
X29299D01*
G01Y618050D02*
Y614050D01*
X36699D01*
G01X33400Y609326D02*
Y605326D01*
X40800D01*
G01X26017Y643000D02*
Y645500D01*
X27058D01*
X27392Y645375D01*
X27600Y645208D01*
X27683Y644875D01*
X27600Y644542D01*
X27350Y644333D01*
X27058Y644208D01*
X26017D01*
G01X27058D02*
X27683Y643000D01*
G01X29033Y643500D02*
X29283Y643208D01*
X29617Y643042D01*
X29992Y643000D01*
X30325Y643042D01*
X30658Y643250D01*
X30867Y643500D01*
X30908Y643750D01*
X30825Y644042D01*
X30533Y644250D01*
X30242Y644333D01*
X29867D01*
G01X30242D02*
X30492Y644458D01*
X30700Y644667D01*
X30783Y644917D01*
X30700Y645167D01*
X30492Y645375D01*
X30117Y645500D01*
X29742Y645458D01*
X29367Y645292D01*
G01X32133Y643375D02*
X32383Y643167D01*
X32675Y643042D01*
X33050Y643000D01*
X33425Y643083D01*
X33717Y643250D01*
X33925Y643542D01*
X33967Y643875D01*
X33883Y644208D01*
X33675Y644417D01*
X33383Y644583D01*
X33092Y644625D01*
X32800Y644583D01*
X32425Y644417D01*
X32550Y645500D01*
X33675D01*
G01X35358Y644042D02*
X35650Y644333D01*
X35900Y644500D01*
X36233Y644583D01*
X36525Y644500D01*
X36733Y644333D01*
X36900Y644083D01*
X36942Y643792D01*
X36900Y643542D01*
X36733Y643292D01*
X36483Y643083D01*
X36192Y643000D01*
X35858Y643083D01*
X35567Y643333D01*
X35400Y643708D01*
X35358Y644125D01*
X35442Y644667D01*
X35567Y644958D01*
X35775Y645250D01*
X36067Y645458D01*
X36358Y645500D01*
X36650Y645417D01*
X36858Y645208D01*
G01X26017Y639000D02*
Y641500D01*
X27058D01*
X27392Y641375D01*
X27600Y641208D01*
X27683Y640875D01*
X27600Y640542D01*
X27350Y640333D01*
X27058Y640208D01*
X26017D01*
G01X27058D02*
X27683Y639000D01*
G01X29033Y639375D02*
X29283Y639167D01*
X29575Y639042D01*
X29950Y639000D01*
X30325Y639083D01*
X30617Y639250D01*
X30825Y639542D01*
X30867Y639875D01*
X30783Y640208D01*
X30575Y640417D01*
X30283Y640583D01*
X29992Y640625D01*
X29700Y640583D01*
X29325Y640417D01*
X29450Y641500D01*
X30575D01*
G01X33550Y639000D02*
Y641500D01*
X32008Y639708D01*
X34092D01*
G01X35442Y639292D02*
X35733Y639083D01*
X36067Y639000D01*
X36400Y639083D01*
X36692Y639333D01*
X36900Y639708D01*
X36983Y640083D01*
Y640542D01*
X36900Y640917D01*
X36692Y641250D01*
X36442Y641417D01*
X36150Y641500D01*
X35817Y641417D01*
X35567Y641250D01*
X35400Y641000D01*
X35317Y640667D01*
X35400Y640375D01*
X35608Y640083D01*
X35858Y639917D01*
X36150Y639875D01*
X36483Y639958D01*
X36733Y640167D01*
X36983Y640542D01*
G01X26017Y635000D02*
Y637500D01*
X27058D01*
X27392Y637375D01*
X27600Y637208D01*
X27683Y636875D01*
X27600Y636542D01*
X27350Y636333D01*
X27058Y636208D01*
X26017D01*
G01X27058D02*
X27683Y635000D01*
G01X29033Y635375D02*
X29283Y635167D01*
X29575Y635042D01*
X29950Y635000D01*
X30325Y635083D01*
X30617Y635250D01*
X30825Y635542D01*
X30867Y635875D01*
X30783Y636208D01*
X30575Y636417D01*
X30283Y636583D01*
X29992Y636625D01*
X29700Y636583D01*
X29325Y636417D01*
X29450Y637500D01*
X30575D01*
G01X33550Y635000D02*
Y637500D01*
X32008Y635708D01*
X34092D01*
G01X36150Y635000D02*
X36442Y635042D01*
X36775Y635167D01*
X36983Y635375D01*
X37067Y635667D01*
X36983Y635958D01*
X36733Y636208D01*
X36358Y636333D01*
X35942D01*
X35692Y636417D01*
X35483Y636625D01*
X35400Y636917D01*
X35525Y637208D01*
X35817Y637417D01*
X36150Y637500D01*
X36483Y637417D01*
X36775Y637208D01*
X36900Y636917D01*
X36817Y636625D01*
X36608Y636417D01*
X36358Y636333D01*
X35942D01*
X35567Y636208D01*
X35317Y635958D01*
X35233Y635667D01*
X35317Y635375D01*
X35525Y635167D01*
X35858Y635042D01*
X36150Y635000D01*
G01X26017Y631000D02*
Y633500D01*
X27058D01*
X27392Y633375D01*
X27600Y633208D01*
X27683Y632875D01*
X27600Y632542D01*
X27350Y632333D01*
X27058Y632208D01*
X26017D01*
G01X27058D02*
X27683Y631000D01*
G01X29033Y631375D02*
X29283Y631167D01*
X29575Y631042D01*
X29950Y631000D01*
X30325Y631083D01*
X30617Y631250D01*
X30825Y631542D01*
X30867Y631875D01*
X30783Y632208D01*
X30575Y632417D01*
X30283Y632583D01*
X29992Y632625D01*
X29700Y632583D01*
X29325Y632417D01*
X29450Y633500D01*
X30575D01*
G01X33550Y631000D02*
Y633500D01*
X32008Y631708D01*
X34092D01*
G01X36067Y631000D02*
X36150Y631542D01*
X36275Y632000D01*
X36442Y632417D01*
X36650Y632875D01*
X36983Y633500D01*
X35317D01*
G01X26017Y627000D02*
Y629500D01*
X27058D01*
X27392Y629375D01*
X27600Y629208D01*
X27683Y628875D01*
X27600Y628542D01*
X27350Y628333D01*
X27058Y628208D01*
X26017D01*
G01X27058D02*
X27683Y627000D01*
G01X29033Y627375D02*
X29283Y627167D01*
X29575Y627042D01*
X29950Y627000D01*
X30325Y627083D01*
X30617Y627250D01*
X30825Y627542D01*
X30867Y627875D01*
X30783Y628208D01*
X30575Y628417D01*
X30283Y628583D01*
X29992Y628625D01*
X29700Y628583D01*
X29325Y628417D01*
X29450Y629500D01*
X30575D01*
G01X33550Y627000D02*
Y629500D01*
X32008Y627708D01*
X34092D01*
G01X35358Y628042D02*
X35650Y628333D01*
X35900Y628500D01*
X36233Y628583D01*
X36525Y628500D01*
X36733Y628333D01*
X36900Y628083D01*
X36942Y627792D01*
X36900Y627542D01*
X36733Y627292D01*
X36483Y627083D01*
X36192Y627000D01*
X35858Y627083D01*
X35567Y627333D01*
X35400Y627708D01*
X35358Y628125D01*
X35442Y628667D01*
X35567Y628958D01*
X35775Y629250D01*
X36067Y629458D01*
X36358Y629500D01*
X36650Y629417D01*
X36858Y629208D01*
G01X26017Y647000D02*
Y649500D01*
X27058D01*
X27392Y649375D01*
X27600Y649208D01*
X27683Y648875D01*
X27600Y648542D01*
X27350Y648333D01*
X27058Y648208D01*
X26017D01*
G01X27058D02*
X27683Y647000D01*
G01X29033Y647500D02*
X29283Y647208D01*
X29617Y647042D01*
X29992Y647000D01*
X30325Y647042D01*
X30658Y647250D01*
X30867Y647500D01*
X30908Y647750D01*
X30825Y648042D01*
X30533Y648250D01*
X30242Y648333D01*
X29867D01*
G01X30242D02*
X30492Y648458D01*
X30700Y648667D01*
X30783Y648917D01*
X30700Y649167D01*
X30492Y649375D01*
X30117Y649500D01*
X29742Y649458D01*
X29367Y649292D01*
G01X32133Y647375D02*
X32383Y647167D01*
X32675Y647042D01*
X33050Y647000D01*
X33425Y647083D01*
X33717Y647250D01*
X33925Y647542D01*
X33967Y647875D01*
X33883Y648208D01*
X33675Y648417D01*
X33383Y648583D01*
X33092Y648625D01*
X32800Y648583D01*
X32425Y648417D01*
X32550Y649500D01*
X33675D01*
G01X35442Y647292D02*
X35733Y647083D01*
X36067Y647000D01*
X36400Y647083D01*
X36692Y647333D01*
X36900Y647708D01*
X36983Y648083D01*
Y648542D01*
X36900Y648917D01*
X36692Y649250D01*
X36442Y649417D01*
X36150Y649500D01*
X35817Y649417D01*
X35567Y649250D01*
X35400Y649000D01*
X35317Y648667D01*
X35400Y648375D01*
X35608Y648083D01*
X35858Y647917D01*
X36150Y647875D01*
X36483Y647958D01*
X36733Y648167D01*
X36983Y648542D01*
G01X30708Y807380D02*
X30583Y807130D01*
X30500Y806838D01*
Y806505D01*
X30625Y806130D01*
X30833Y805838D01*
X31083Y805630D01*
X31500Y805463D01*
X31875Y805421D01*
X32250Y805505D01*
X32500Y805630D01*
X32750Y805880D01*
X32917Y806171D01*
X33000Y806463D01*
Y806755D01*
X32917Y807046D01*
X32792Y807296D01*
X32625Y807505D01*
G01X33000Y808605D02*
X30500D01*
X33000Y810521D01*
X30500D01*
G01X31958Y811871D02*
X31667Y812163D01*
X31500Y812413D01*
X31417Y812746D01*
X31500Y813038D01*
X31667Y813246D01*
X31917Y813413D01*
X32208Y813455D01*
X32458Y813413D01*
X32708Y813246D01*
X32917Y812996D01*
X33000Y812705D01*
X32917Y812371D01*
X32667Y812080D01*
X32292Y811913D01*
X31875Y811871D01*
X31333Y811955D01*
X31042Y812080D01*
X30750Y812288D01*
X30542Y812580D01*
X30500Y812871D01*
X30583Y813163D01*
X30792Y813371D01*
G01X91598Y995285D02*
Y834085D01*
X77998D01*
Y821135D01*
X59798D01*
Y834085D01*
X30898D01*
Y844435D01*
X37598D01*
Y984935D01*
X30898D01*
Y995285D01*
X59798D01*
Y1008235D01*
X77998D01*
Y995285D01*
X91598D01*
G01X28499Y854400D02*
X30999D01*
G01X28499Y853442D02*
Y855358D01*
G01X30999Y856667D02*
X28499D01*
Y857667D01*
X28624Y858000D01*
X28916Y858250D01*
X29249Y858333D01*
X29582Y858250D01*
X29832Y858042D01*
X29957Y857667D01*
Y856667D01*
G01X30999Y860600D02*
X28499D01*
X28999Y860100D01*
G01X30999D02*
Y861100D01*
G01Y863617D02*
X30457Y863700D01*
X29999Y863825D01*
X29582Y863992D01*
X29124Y864200D01*
X28499Y864533D01*
Y862867D01*
G01X33167Y914488D02*
X33375Y914821D01*
X33500Y915196D01*
Y915530D01*
X33375Y915863D01*
X33167Y916113D01*
X32875Y916238D01*
X32583Y916155D01*
X32333Y915946D01*
X32167Y915571D01*
X32083Y915071D01*
X31917Y914780D01*
X31625Y914655D01*
X31333Y914738D01*
X31125Y914946D01*
X31000Y915238D01*
Y915530D01*
X31083Y915821D01*
X31292Y916071D01*
G01X33500Y917546D02*
X31000D01*
G01Y919130D02*
X32542Y917546D01*
G01X33500Y919380D02*
X31833Y918255D01*
G01X31000Y921563D02*
X33500D01*
G01X31000Y920605D02*
Y922521D01*
G01X33500Y924663D02*
X31000D01*
X31500Y924163D01*
G01X33500D02*
Y925163D01*
G01X33000Y926846D02*
X33292Y927096D01*
X33458Y927430D01*
X33500Y927805D01*
X33458Y928138D01*
X33250Y928471D01*
X33000Y928680D01*
X32750Y928721D01*
X32458Y928638D01*
X32250Y928346D01*
X32167Y928055D01*
Y927680D01*
G01Y928055D02*
X32042Y928305D01*
X31833Y928513D01*
X31583Y928596D01*
X31333Y928513D01*
X31125Y928305D01*
X31000Y927930D01*
X31042Y927555D01*
X31208Y927180D01*
G01X29900Y1065000D02*
X29567Y1065042D01*
X29275Y1065208D01*
X29025Y1065458D01*
X28858Y1065750D01*
X28775Y1066083D01*
Y1066417D01*
X28858Y1066750D01*
X29025Y1067042D01*
X29275Y1067292D01*
X29567Y1067458D01*
X29900Y1067500D01*
X30233Y1067458D01*
X30525Y1067292D01*
X30775Y1067042D01*
X30942Y1066750D01*
X31025Y1066417D01*
Y1066083D01*
X30942Y1065750D01*
X30775Y1065458D01*
X30525Y1065208D01*
X30233Y1065042D01*
X29900Y1065000D01*
G01X30233Y1065667D02*
X30733Y1065000D01*
G01X33500D02*
Y1067500D01*
X31958Y1065708D01*
X34042D01*
G01X35308Y1066042D02*
X35600Y1066333D01*
X35850Y1066500D01*
X36183Y1066583D01*
X36475Y1066500D01*
X36683Y1066333D01*
X36850Y1066083D01*
X36892Y1065792D01*
X36850Y1065542D01*
X36683Y1065292D01*
X36433Y1065083D01*
X36142Y1065000D01*
X35808Y1065083D01*
X35517Y1065333D01*
X35350Y1065708D01*
X35308Y1066125D01*
X35392Y1066667D01*
X35517Y1066958D01*
X35725Y1067250D01*
X36017Y1067458D01*
X36308Y1067500D01*
X36600Y1067417D01*
X36808Y1067208D01*
G01X31599Y1049550D02*
Y1062550D01*
G01X91598Y1400797D02*
Y1239597D01*
X77998D01*
Y1226647D01*
X59798D01*
Y1239597D01*
X30898D01*
Y1249947D01*
X37598D01*
Y1390447D01*
X30898D01*
Y1400797D01*
X59798D01*
Y1413747D01*
X77998D01*
Y1400797D01*
X91598D01*
G01X34167Y1309488D02*
X34375Y1309821D01*
X34500Y1310196D01*
Y1310530D01*
X34375Y1310863D01*
X34167Y1311113D01*
X33875Y1311238D01*
X33583Y1311155D01*
X33333Y1310946D01*
X33167Y1310571D01*
X33083Y1310071D01*
X32917Y1309780D01*
X32625Y1309655D01*
X32333Y1309738D01*
X32125Y1309946D01*
X32000Y1310238D01*
Y1310530D01*
X32083Y1310821D01*
X32292Y1311071D01*
G01X34500Y1312546D02*
X32000D01*
G01Y1314130D02*
X33542Y1312546D01*
G01X34500Y1314380D02*
X32833Y1313255D01*
G01X32000Y1316563D02*
X34500D01*
G01X32000Y1315605D02*
Y1317521D01*
G01X34500Y1319663D02*
X32000D01*
X32500Y1319163D01*
G01X34500D02*
Y1320163D01*
G01X32417Y1321971D02*
X32167Y1322221D01*
X32042Y1322513D01*
X32000Y1322846D01*
X32083Y1323263D01*
X32292Y1323555D01*
X32542Y1323638D01*
X32792Y1323596D01*
X33000Y1323430D01*
X33417Y1322596D01*
X33708Y1322221D01*
X34125Y1321971D01*
X34500Y1321888D01*
Y1323638D01*
G01X43265Y1499750D02*
X53265D01*
G01Y1492750D02*
X43265D01*
G01X48265D02*
Y1499750D01*
G01X43265Y1489317D02*
X53265D01*
Y1485983D01*
X52765Y1484650D01*
X52098Y1483650D01*
X51098Y1482817D01*
X49931Y1482150D01*
X48265Y1481983D01*
X46598Y1482150D01*
X45432Y1482817D01*
X44431Y1483650D01*
X43765Y1484650D01*
X43265Y1485983D01*
Y1489317D01*
G01Y1478717D02*
X53265D01*
Y1475383D01*
X52765Y1474050D01*
X52098Y1473050D01*
X51098Y1472217D01*
X49931Y1471550D01*
X48265Y1471383D01*
X46598Y1471550D01*
X45432Y1472217D01*
X44431Y1473050D01*
X43765Y1474050D01*
X43265Y1475383D01*
Y1478717D01*
G01Y1464450D02*
X53265D01*
X51265Y1466450D01*
G01X43265D02*
Y1462450D01*
G01Y1453850D02*
X53265D01*
X51265Y1455850D01*
G01X43265D02*
Y1451850D01*
G01X39932Y1448250D02*
Y1438250D01*
G01X53265Y1435983D02*
X43265D01*
Y1429317D01*
G01Y1418717D02*
Y1425383D01*
X53265D01*
Y1418717D01*
G01X48432Y1421383D02*
Y1425383D01*
G01X43265Y1415117D02*
X53265D01*
Y1411783D01*
X52765Y1410450D01*
X52098Y1409450D01*
X51098Y1408617D01*
X49931Y1407950D01*
X48265Y1407783D01*
X46598Y1407950D01*
X45432Y1408617D01*
X44431Y1409450D01*
X43765Y1410450D01*
X43265Y1411783D01*
Y1415117D01*
G01X24208Y1449380D02*
X24083Y1449130D01*
X24000Y1448838D01*
Y1448505D01*
X24125Y1448130D01*
X24333Y1447838D01*
X24583Y1447630D01*
X25000Y1447463D01*
X25375Y1447421D01*
X25750Y1447505D01*
X26000Y1447630D01*
X26250Y1447880D01*
X26417Y1448171D01*
X26500Y1448463D01*
Y1448755D01*
X26417Y1449046D01*
X26292Y1449296D01*
X26125Y1449505D01*
G01X26500Y1450605D02*
X24000D01*
X26500Y1452521D01*
X24000D01*
G01X26500Y1454663D02*
X24000D01*
X24500Y1454163D01*
G01X26500D02*
Y1455163D01*
G01X28500Y1557350D02*
X31000D01*
G01X28500Y1556392D02*
Y1558308D01*
G01X31000Y1559617D02*
X28500D01*
Y1560617D01*
X28625Y1560950D01*
X28917Y1561200D01*
X29250Y1561283D01*
X29583Y1561200D01*
X29833Y1560992D01*
X29958Y1560617D01*
Y1559617D01*
G01X31000Y1563550D02*
X28500D01*
X29000Y1563050D01*
G01X31000D02*
Y1564050D01*
G01X30625Y1565733D02*
X30833Y1565983D01*
X30958Y1566275D01*
X31000Y1566650D01*
X30917Y1567025D01*
X30750Y1567317D01*
X30458Y1567525D01*
X30125Y1567567D01*
X29792Y1567483D01*
X29583Y1567275D01*
X29417Y1566983D01*
X29375Y1566692D01*
X29417Y1566400D01*
X29583Y1566025D01*
X28500Y1566150D01*
Y1567275D01*
G01X35500Y1596017D02*
X33000D01*
Y1597058D01*
X33125Y1597392D01*
X33292Y1597600D01*
X33625Y1597683D01*
X33958Y1597600D01*
X34167Y1597350D01*
X34292Y1597058D01*
Y1596017D01*
G01Y1597058D02*
X35500Y1597683D01*
G01X35000Y1599033D02*
X35292Y1599283D01*
X35458Y1599617D01*
X35500Y1599992D01*
X35458Y1600325D01*
X35250Y1600658D01*
X35000Y1600867D01*
X34750Y1600908D01*
X34458Y1600825D01*
X34250Y1600533D01*
X34167Y1600242D01*
Y1599867D01*
G01Y1600242D02*
X34042Y1600492D01*
X33833Y1600700D01*
X33583Y1600783D01*
X33333Y1600700D01*
X33125Y1600492D01*
X33000Y1600117D01*
X33042Y1599742D01*
X33208Y1599367D01*
G01X35125Y1602133D02*
X35333Y1602383D01*
X35458Y1602675D01*
X35500Y1603050D01*
X35417Y1603425D01*
X35250Y1603717D01*
X34958Y1603925D01*
X34625Y1603967D01*
X34292Y1603883D01*
X34083Y1603675D01*
X33917Y1603383D01*
X33875Y1603092D01*
X33917Y1602800D01*
X34083Y1602425D01*
X33000Y1602550D01*
Y1603675D01*
G01X35125Y1605233D02*
X35333Y1605483D01*
X35458Y1605775D01*
X35500Y1606150D01*
X35417Y1606525D01*
X35250Y1606817D01*
X34958Y1607025D01*
X34625Y1607067D01*
X34292Y1606983D01*
X34083Y1606775D01*
X33917Y1606483D01*
X33875Y1606192D01*
X33917Y1605900D01*
X34083Y1605525D01*
X33000Y1605650D01*
Y1606775D01*
G01X36599Y1594050D02*
X32599D01*
Y1586650D01*
G01X31500Y1596017D02*
X29000D01*
Y1597058D01*
X29125Y1597392D01*
X29292Y1597600D01*
X29625Y1597683D01*
X29958Y1597600D01*
X30167Y1597350D01*
X30292Y1597058D01*
Y1596017D01*
G01Y1597058D02*
X31500Y1597683D01*
G01X31000Y1599033D02*
X31292Y1599283D01*
X31458Y1599617D01*
X31500Y1599992D01*
X31458Y1600325D01*
X31250Y1600658D01*
X31000Y1600867D01*
X30750Y1600908D01*
X30458Y1600825D01*
X30250Y1600533D01*
X30167Y1600242D01*
Y1599867D01*
G01Y1600242D02*
X30042Y1600492D01*
X29833Y1600700D01*
X29583Y1600783D01*
X29333Y1600700D01*
X29125Y1600492D01*
X29000Y1600117D01*
X29042Y1599742D01*
X29208Y1599367D01*
G01X31125Y1602133D02*
X31333Y1602383D01*
X31458Y1602675D01*
X31500Y1603050D01*
X31417Y1603425D01*
X31250Y1603717D01*
X30958Y1603925D01*
X30625Y1603967D01*
X30292Y1603883D01*
X30083Y1603675D01*
X29917Y1603383D01*
X29875Y1603092D01*
X29917Y1602800D01*
X30083Y1602425D01*
X29000Y1602550D01*
Y1603675D01*
G01X31500Y1606150D02*
X31458Y1606442D01*
X31333Y1606775D01*
X31125Y1606983D01*
X30833Y1607067D01*
X30542Y1606983D01*
X30292Y1606733D01*
X30167Y1606358D01*
Y1605942D01*
X30083Y1605692D01*
X29875Y1605483D01*
X29583Y1605400D01*
X29292Y1605525D01*
X29083Y1605817D01*
X29000Y1606150D01*
X29083Y1606483D01*
X29292Y1606775D01*
X29583Y1606900D01*
X29875Y1606817D01*
X30083Y1606608D01*
X30167Y1606358D01*
Y1605942D01*
X30292Y1605567D01*
X30542Y1605317D01*
X30833Y1605233D01*
X31125Y1605317D01*
X31333Y1605525D01*
X31458Y1605858D01*
X31500Y1606150D01*
G01X28499Y1586660D02*
X32499D01*
Y1594060D01*
G01X91598Y1806309D02*
Y1645109D01*
X77998D01*
Y1632159D01*
X59798D01*
Y1645109D01*
X30898D01*
Y1655459D01*
X37598D01*
Y1795959D01*
X30898D01*
Y1806309D01*
X59798D01*
Y1819259D01*
X77998D01*
Y1806309D01*
X91598D01*
G01X33667Y1732488D02*
X33875Y1732821D01*
X34000Y1733196D01*
Y1733530D01*
X33875Y1733863D01*
X33667Y1734113D01*
X33375Y1734238D01*
X33083Y1734155D01*
X32833Y1733946D01*
X32667Y1733571D01*
X32583Y1733071D01*
X32417Y1732780D01*
X32125Y1732655D01*
X31833Y1732738D01*
X31625Y1732946D01*
X31500Y1733238D01*
Y1733530D01*
X31583Y1733821D01*
X31792Y1734071D01*
G01X34000Y1735546D02*
X31500D01*
G01Y1737130D02*
X33042Y1735546D01*
G01X34000Y1737380D02*
X32333Y1736255D01*
G01X31500Y1739563D02*
X34000D01*
G01X31500Y1738605D02*
Y1740521D01*
G01X34000Y1742663D02*
X31500D01*
X32000Y1742163D01*
G01X34000D02*
Y1743163D01*
G01Y1745763D02*
X31500D01*
X32000Y1745263D01*
G01X34000D02*
Y1746263D01*
G01X28750Y1828700D02*
Y1826200D01*
G01X27792Y1828700D02*
X29708D01*
G01X31017Y1826200D02*
Y1828700D01*
X32017D01*
X32350Y1828575D01*
X32600Y1828283D01*
X32683Y1827950D01*
X32600Y1827617D01*
X32392Y1827367D01*
X32017Y1827242D01*
X31017D01*
G01X34950Y1826200D02*
Y1828700D01*
X34450Y1828200D01*
G01Y1826200D02*
X35450D01*
G01X38050D02*
X38342Y1826242D01*
X38675Y1826367D01*
X38883Y1826575D01*
X38967Y1826867D01*
X38883Y1827158D01*
X38633Y1827408D01*
X38258Y1827533D01*
X37842D01*
X37592Y1827617D01*
X37383Y1827825D01*
X37300Y1828117D01*
X37425Y1828408D01*
X37717Y1828617D01*
X38050Y1828700D01*
X38383Y1828617D01*
X38675Y1828408D01*
X38800Y1828117D01*
X38717Y1827825D01*
X38508Y1827617D01*
X38258Y1827533D01*
X37842D01*
X37467Y1827408D01*
X37217Y1827158D01*
X37133Y1826867D01*
X37217Y1826575D01*
X37425Y1826367D01*
X37758Y1826242D01*
X38050Y1826200D01*
G01X29708Y1814317D02*
X29583Y1814067D01*
X29500Y1813775D01*
Y1813442D01*
X29625Y1813067D01*
X29833Y1812775D01*
X30083Y1812567D01*
X30500Y1812400D01*
X30875Y1812358D01*
X31250Y1812442D01*
X31500Y1812567D01*
X31750Y1812817D01*
X31917Y1813108D01*
X32000Y1813400D01*
Y1813692D01*
X31917Y1813983D01*
X31792Y1814233D01*
X31625Y1814442D01*
G01X32000Y1815542D02*
X29500D01*
X32000Y1817458D01*
X29500D01*
G01X31625Y1818683D02*
X31833Y1818933D01*
X31958Y1819225D01*
X32000Y1819600D01*
X31917Y1819975D01*
X31750Y1820267D01*
X31458Y1820475D01*
X31125Y1820517D01*
X30792Y1820433D01*
X30583Y1820225D01*
X30417Y1819933D01*
X30375Y1819642D01*
X30417Y1819350D01*
X30583Y1818975D01*
X29500Y1819100D01*
Y1820225D01*
G01X28517Y1848000D02*
Y1850500D01*
X29558D01*
X29892Y1850375D01*
X30100Y1850208D01*
X30183Y1849875D01*
X30100Y1849542D01*
X29850Y1849333D01*
X29558Y1849208D01*
X28517D01*
G01X29558D02*
X30183Y1848000D01*
G01X31533Y1848500D02*
X31783Y1848208D01*
X32117Y1848042D01*
X32492Y1848000D01*
X32825Y1848042D01*
X33158Y1848250D01*
X33367Y1848500D01*
X33408Y1848750D01*
X33325Y1849042D01*
X33033Y1849250D01*
X32742Y1849333D01*
X32367D01*
G01X32742D02*
X32992Y1849458D01*
X33200Y1849667D01*
X33283Y1849917D01*
X33200Y1850167D01*
X32992Y1850375D01*
X32617Y1850500D01*
X32242Y1850458D01*
X31867Y1850292D01*
G01X34842Y1848292D02*
X35133Y1848083D01*
X35467Y1848000D01*
X35800Y1848083D01*
X36092Y1848333D01*
X36300Y1848708D01*
X36383Y1849083D01*
Y1849542D01*
X36300Y1849917D01*
X36092Y1850250D01*
X35842Y1850417D01*
X35550Y1850500D01*
X35217Y1850417D01*
X34967Y1850250D01*
X34800Y1850000D01*
X34717Y1849667D01*
X34800Y1849375D01*
X35008Y1849083D01*
X35258Y1848917D01*
X35550Y1848875D01*
X35883Y1848958D01*
X36133Y1849167D01*
X36383Y1849542D01*
G01X38650Y1848000D02*
Y1850500D01*
X38150Y1850000D01*
G01Y1848000D02*
X39150D01*
G01X36299Y1840050D02*
Y1836050D01*
X43699D01*
G01X36299Y1844050D02*
Y1840050D01*
X43699D01*
G01X28516Y1852617D02*
Y1855117D01*
X29557D01*
X29891Y1854992D01*
X30099Y1854825D01*
X30182Y1854492D01*
X30099Y1854159D01*
X29849Y1853950D01*
X29557Y1853825D01*
X28516D01*
G01X29557D02*
X30182Y1852617D01*
G01X31532Y1853117D02*
X31782Y1852825D01*
X32116Y1852659D01*
X32491Y1852617D01*
X32824Y1852659D01*
X33157Y1852867D01*
X33366Y1853117D01*
X33407Y1853367D01*
X33324Y1853659D01*
X33032Y1853867D01*
X32741Y1853950D01*
X32366D01*
G01X32741D02*
X32991Y1854075D01*
X33199Y1854284D01*
X33282Y1854534D01*
X33199Y1854784D01*
X32991Y1854992D01*
X32616Y1855117D01*
X32241Y1855075D01*
X31866Y1854909D01*
G01X34841Y1852909D02*
X35132Y1852700D01*
X35466Y1852617D01*
X35799Y1852700D01*
X36091Y1852950D01*
X36299Y1853325D01*
X36382Y1853700D01*
Y1854159D01*
X36299Y1854534D01*
X36091Y1854867D01*
X35841Y1855034D01*
X35549Y1855117D01*
X35216Y1855034D01*
X34966Y1854867D01*
X34799Y1854617D01*
X34716Y1854284D01*
X34799Y1853992D01*
X35007Y1853700D01*
X35257Y1853534D01*
X35549Y1853492D01*
X35882Y1853575D01*
X36132Y1853784D01*
X36382Y1854159D01*
G01X37857Y1854700D02*
X38107Y1854950D01*
X38399Y1855075D01*
X38732Y1855117D01*
X39149Y1855034D01*
X39441Y1854825D01*
X39524Y1854575D01*
X39482Y1854325D01*
X39316Y1854117D01*
X38482Y1853700D01*
X38107Y1853409D01*
X37857Y1852992D01*
X37774Y1852617D01*
X39524D01*
G01X26174Y1880217D02*
Y1882717D01*
G01X27924D02*
Y1880217D01*
G01Y1881467D02*
X26174D01*
G01X29357Y1882300D02*
X29607Y1882550D01*
X29899Y1882675D01*
X30232Y1882717D01*
X30649Y1882634D01*
X30941Y1882425D01*
X31024Y1882175D01*
X30982Y1881925D01*
X30816Y1881717D01*
X29982Y1881300D01*
X29607Y1881009D01*
X29357Y1880592D01*
X29274Y1880217D01*
X31024D01*
G01X29999Y1916850D02*
X33999D01*
Y1924250D01*
G01X29030Y1930638D02*
X25030D01*
Y1923238D01*
G01Y1930638D02*
X21030D01*
Y1923238D01*
G01X35368Y1960562D02*
X30368D01*
Y1955562D01*
G01X21999Y1962850D02*
X25999D01*
Y1970250D01*
G01X33999Y1977750D02*
X29999D01*
Y1970350D01*
G01X33999Y1970250D02*
X29999D01*
Y1962850D01*
G01X25999D02*
X29999D01*
Y1970250D01*
G01X38462Y1959555D02*
Y1962555D01*
G01X28500Y1979017D02*
X26000D01*
Y1980017D01*
X26125Y1980350D01*
X26417Y1980600D01*
X26750Y1980683D01*
X27083Y1980600D01*
X27333Y1980392D01*
X27458Y1980017D01*
Y1979017D01*
G01X28500Y1982117D02*
X26000D01*
Y1983158D01*
X26125Y1983492D01*
X26292Y1983700D01*
X26625Y1983783D01*
X26958Y1983700D01*
X27167Y1983450D01*
X27292Y1983158D01*
Y1982117D01*
G01Y1983158D02*
X28500Y1983783D01*
G01Y1986550D02*
X26000D01*
X27792Y1985008D01*
Y1987092D01*
G01X26417Y1988358D02*
X26167Y1988608D01*
X26042Y1988900D01*
X26000Y1989233D01*
X26083Y1989650D01*
X26292Y1989942D01*
X26542Y1990025D01*
X26792Y1989983D01*
X27000Y1989817D01*
X27417Y1988983D01*
X27708Y1988608D01*
X28125Y1988358D01*
X28500Y1988275D01*
Y1990025D01*
G01X33500Y1979517D02*
X31000D01*
Y1980517D01*
X31125Y1980850D01*
X31417Y1981100D01*
X31750Y1981183D01*
X32083Y1981100D01*
X32333Y1980892D01*
X32458Y1980517D01*
Y1979517D01*
G01X31208Y1984367D02*
X31083Y1984117D01*
X31000Y1983825D01*
Y1983492D01*
X31125Y1983117D01*
X31333Y1982825D01*
X31583Y1982617D01*
X32000Y1982450D01*
X32375Y1982408D01*
X32750Y1982492D01*
X33000Y1982617D01*
X33250Y1982867D01*
X33417Y1983158D01*
X33500Y1983450D01*
Y1983742D01*
X33417Y1984033D01*
X33292Y1984283D01*
X33125Y1984492D01*
G01X33000Y1985633D02*
X33292Y1985883D01*
X33458Y1986217D01*
X33500Y1986592D01*
X33458Y1986925D01*
X33250Y1987258D01*
X33000Y1987467D01*
X32750Y1987508D01*
X32458Y1987425D01*
X32250Y1987133D01*
X32167Y1986842D01*
Y1986467D01*
G01Y1986842D02*
X32042Y1987092D01*
X31833Y1987300D01*
X31583Y1987383D01*
X31333Y1987300D01*
X31125Y1987092D01*
X31000Y1986717D01*
X31042Y1986342D01*
X31208Y1985967D01*
G01X32458Y1988858D02*
X32167Y1989150D01*
X32000Y1989400D01*
X31917Y1989733D01*
X32000Y1990025D01*
X32167Y1990233D01*
X32417Y1990400D01*
X32708Y1990442D01*
X32958Y1990400D01*
X33208Y1990233D01*
X33417Y1989983D01*
X33500Y1989692D01*
X33417Y1989358D01*
X33167Y1989067D01*
X32792Y1988900D01*
X32375Y1988858D01*
X31833Y1988942D01*
X31542Y1989067D01*
X31250Y1989275D01*
X31042Y1989567D01*
X31000Y1989858D01*
X31083Y1990150D01*
X31292Y1990358D01*
G01X55911Y220292D02*
Y222792D01*
X56952D01*
X57286Y222667D01*
X57494Y222500D01*
X57577Y222167D01*
X57494Y221834D01*
X57244Y221625D01*
X56952Y221500D01*
X55911D01*
G01X56952D02*
X57577Y220292D01*
G01X59052Y222375D02*
X59302Y222625D01*
X59594Y222750D01*
X59927Y222792D01*
X60344Y222709D01*
X60636Y222500D01*
X60719Y222250D01*
X60677Y222000D01*
X60511Y221792D01*
X59677Y221375D01*
X59302Y221084D01*
X59052Y220667D01*
X58969Y220292D01*
X60719D01*
G01X62236Y220584D02*
X62527Y220375D01*
X62861Y220292D01*
X63194Y220375D01*
X63486Y220625D01*
X63694Y221000D01*
X63777Y221375D01*
Y221834D01*
X63694Y222209D01*
X63486Y222542D01*
X63236Y222709D01*
X62944Y222792D01*
X62611Y222709D01*
X62361Y222542D01*
X62194Y222292D01*
X62111Y221959D01*
X62194Y221667D01*
X62402Y221375D01*
X62652Y221209D01*
X62944Y221167D01*
X63277Y221250D01*
X63527Y221459D01*
X63777Y221834D01*
G01X65252Y221334D02*
X65544Y221625D01*
X65794Y221792D01*
X66127Y221875D01*
X66419Y221792D01*
X66627Y221625D01*
X66794Y221375D01*
X66836Y221084D01*
X66794Y220834D01*
X66627Y220584D01*
X66377Y220375D01*
X66086Y220292D01*
X65752Y220375D01*
X65461Y220625D01*
X65294Y221000D01*
X65252Y221417D01*
X65336Y221959D01*
X65461Y222250D01*
X65669Y222542D01*
X65961Y222750D01*
X66252Y222792D01*
X66544Y222709D01*
X66752Y222500D01*
G01X61199Y201550D02*
Y205550D01*
X53799D01*
G01X61199D02*
Y209550D01*
X53799D01*
G01X61199D02*
Y213550D01*
X53799D01*
G01X46399Y219100D02*
Y215100D01*
X53799D01*
G01X53199Y201400D02*
Y214400D01*
G01X55911Y224292D02*
Y226792D01*
X56952D01*
X57286Y226667D01*
X57494Y226500D01*
X57577Y226167D01*
X57494Y225834D01*
X57244Y225625D01*
X56952Y225500D01*
X55911D01*
G01X56952D02*
X57577Y224292D01*
G01X59052Y226375D02*
X59302Y226625D01*
X59594Y226750D01*
X59927Y226792D01*
X60344Y226709D01*
X60636Y226500D01*
X60719Y226250D01*
X60677Y226000D01*
X60511Y225792D01*
X59677Y225375D01*
X59302Y225084D01*
X59052Y224667D01*
X58969Y224292D01*
X60719D01*
G01X62236Y224584D02*
X62527Y224375D01*
X62861Y224292D01*
X63194Y224375D01*
X63486Y224625D01*
X63694Y225000D01*
X63777Y225375D01*
Y225834D01*
X63694Y226209D01*
X63486Y226542D01*
X63236Y226709D01*
X62944Y226792D01*
X62611Y226709D01*
X62361Y226542D01*
X62194Y226292D01*
X62111Y225959D01*
X62194Y225667D01*
X62402Y225375D01*
X62652Y225209D01*
X62944Y225167D01*
X63277Y225250D01*
X63527Y225459D01*
X63777Y225834D01*
G01X66044Y224292D02*
X66336Y224334D01*
X66669Y224459D01*
X66877Y224667D01*
X66961Y224959D01*
X66877Y225250D01*
X66627Y225500D01*
X66252Y225625D01*
X65836D01*
X65586Y225709D01*
X65377Y225917D01*
X65294Y226209D01*
X65419Y226500D01*
X65711Y226709D01*
X66044Y226792D01*
X66377Y226709D01*
X66669Y226500D01*
X66794Y226209D01*
X66711Y225917D01*
X66502Y225709D01*
X66252Y225625D01*
X65836D01*
X65461Y225500D01*
X65211Y225250D01*
X65127Y224959D01*
X65211Y224667D01*
X65419Y224459D01*
X65752Y224334D01*
X66044Y224292D01*
G01X55911Y228292D02*
Y230792D01*
X56952D01*
X57286Y230667D01*
X57494Y230500D01*
X57577Y230167D01*
X57494Y229834D01*
X57244Y229625D01*
X56952Y229500D01*
X55911D01*
G01X56952D02*
X57577Y228292D01*
G01X58927Y228792D02*
X59177Y228500D01*
X59511Y228334D01*
X59886Y228292D01*
X60219Y228334D01*
X60552Y228542D01*
X60761Y228792D01*
X60802Y229042D01*
X60719Y229334D01*
X60427Y229542D01*
X60136Y229625D01*
X59761D01*
G01X60136D02*
X60386Y229750D01*
X60594Y229959D01*
X60677Y230209D01*
X60594Y230459D01*
X60386Y230667D01*
X60011Y230792D01*
X59636Y230750D01*
X59261Y230584D01*
G01X62944Y230792D02*
X62611Y230709D01*
X62361Y230500D01*
X62194Y230250D01*
X62069Y229917D01*
X62027Y229542D01*
X62069Y229167D01*
X62194Y228834D01*
X62361Y228584D01*
X62611Y228375D01*
X62944Y228292D01*
X63277Y228375D01*
X63527Y228584D01*
X63694Y228834D01*
X63819Y229167D01*
X63861Y229542D01*
X63819Y229917D01*
X63694Y230250D01*
X63527Y230500D01*
X63277Y230709D01*
X62944Y230792D01*
G01X66044D02*
X65711Y230709D01*
X65461Y230500D01*
X65294Y230250D01*
X65169Y229917D01*
X65127Y229542D01*
X65169Y229167D01*
X65294Y228834D01*
X65461Y228584D01*
X65711Y228375D01*
X66044Y228292D01*
X66377Y228375D01*
X66627Y228584D01*
X66794Y228834D01*
X66919Y229167D01*
X66961Y229542D01*
X66919Y229917D01*
X66794Y230250D01*
X66627Y230500D01*
X66377Y230709D01*
X66044Y230792D01*
G01X64500Y404000D02*
X74500Y397000D01*
G01Y404000D02*
X64500Y397000D01*
G01Y389900D02*
X74500D01*
X72500Y391900D01*
G01X64500D02*
Y387900D01*
G01X68666Y382467D02*
X69833Y381300D01*
X70500Y380300D01*
X70833Y378967D01*
X70500Y377800D01*
X69833Y376967D01*
X68833Y376300D01*
X67667Y376133D01*
X66667Y376300D01*
X65666Y376967D01*
X64833Y377967D01*
X64500Y379133D01*
X64833Y380467D01*
X65833Y381633D01*
X67333Y382300D01*
X69000Y382467D01*
X71166Y382133D01*
X72333Y381633D01*
X73500Y380800D01*
X74333Y379633D01*
X74500Y378467D01*
X74167Y377300D01*
X73333Y376467D01*
G01X64500Y372033D02*
X74500D01*
Y368033D01*
X74000Y366700D01*
X72833Y365700D01*
X71500Y365367D01*
X70167Y365700D01*
X69167Y366533D01*
X68666Y368033D01*
Y372033D01*
G01X73667Y354433D02*
X74167Y355433D01*
X74500Y356600D01*
Y357933D01*
X74000Y359434D01*
X73167Y360600D01*
X72167Y361433D01*
X70500Y362100D01*
X69000Y362267D01*
X67500Y361933D01*
X66500Y361433D01*
X65500Y360433D01*
X64833Y359267D01*
X64500Y358100D01*
Y356933D01*
X64833Y355767D01*
X65333Y354767D01*
X66000Y353933D01*
G01X74500Y349500D02*
Y345500D01*
G01Y347500D02*
X64500D01*
G01Y349500D02*
Y345500D01*
G01Y333567D02*
Y340233D01*
X74500D01*
Y333567D01*
G01X69667Y336233D02*
Y340233D01*
G01X61167Y331300D02*
Y321300D01*
G01X69833Y314367D02*
X70333Y313700D01*
X71166Y313200D01*
X72333Y312867D01*
X73333Y313200D01*
X74000Y313867D01*
X74500Y315033D01*
Y319533D01*
X64500D01*
Y314033D01*
X65167Y312867D01*
X66167Y312200D01*
X67333Y311867D01*
X68500Y312200D01*
X69500Y313200D01*
X69833Y314367D01*
Y319533D01*
G01X47000Y392517D02*
X44500D01*
Y393558D01*
X44625Y393892D01*
X44792Y394100D01*
X45125Y394183D01*
X45458Y394100D01*
X45667Y393850D01*
X45792Y393558D01*
Y392517D01*
G01Y393558D02*
X47000Y394183D01*
G01Y396950D02*
X44500D01*
X46292Y395408D01*
Y397492D01*
G01X44500Y399550D02*
X44583Y399217D01*
X44792Y398967D01*
X45042Y398800D01*
X45375Y398675D01*
X45750Y398633D01*
X46125Y398675D01*
X46458Y398800D01*
X46708Y398967D01*
X46917Y399217D01*
X47000Y399550D01*
X46917Y399883D01*
X46708Y400133D01*
X46458Y400300D01*
X46125Y400425D01*
X45750Y400467D01*
X45375Y400425D01*
X45042Y400300D01*
X44792Y400133D01*
X44583Y399883D01*
X44500Y399550D01*
G01X45958Y401858D02*
X45667Y402150D01*
X45500Y402400D01*
X45417Y402733D01*
X45500Y403025D01*
X45667Y403233D01*
X45917Y403400D01*
X46208Y403442D01*
X46458Y403400D01*
X46708Y403233D01*
X46917Y402983D01*
X47000Y402692D01*
X46917Y402358D01*
X46667Y402067D01*
X46292Y401900D01*
X45875Y401858D01*
X45333Y401942D01*
X45042Y402067D01*
X44750Y402275D01*
X44542Y402567D01*
X44500Y402858D01*
X44583Y403150D01*
X44792Y403358D01*
G01X44800Y406900D02*
X48800D01*
Y414300D01*
G01X43000Y392517D02*
X40500D01*
Y393558D01*
X40625Y393892D01*
X40792Y394100D01*
X41125Y394183D01*
X41458Y394100D01*
X41667Y393850D01*
X41792Y393558D01*
Y392517D01*
G01Y393558D02*
X43000Y394183D01*
G01Y396950D02*
X40500D01*
X42292Y395408D01*
Y397492D01*
G01X40500Y399550D02*
X40583Y399217D01*
X40792Y398967D01*
X41042Y398800D01*
X41375Y398675D01*
X41750Y398633D01*
X42125Y398675D01*
X42458Y398800D01*
X42708Y398967D01*
X42917Y399217D01*
X43000Y399550D01*
X42917Y399883D01*
X42708Y400133D01*
X42458Y400300D01*
X42125Y400425D01*
X41750Y400467D01*
X41375Y400425D01*
X41042Y400300D01*
X40792Y400133D01*
X40583Y399883D01*
X40500Y399550D01*
G01X43000Y402567D02*
X42458Y402650D01*
X42000Y402775D01*
X41583Y402942D01*
X41125Y403150D01*
X40500Y403483D01*
Y401817D01*
G01X44700Y414300D02*
X40700D01*
Y406900D01*
G01X50000Y596017D02*
X47500D01*
Y597058D01*
X47625Y597392D01*
X47792Y597600D01*
X48125Y597683D01*
X48458Y597600D01*
X48667Y597350D01*
X48792Y597058D01*
Y596017D01*
G01Y597058D02*
X50000Y597683D01*
G01X49625Y599033D02*
X49833Y599283D01*
X49958Y599575D01*
X50000Y599950D01*
X49917Y600325D01*
X49750Y600617D01*
X49458Y600825D01*
X49125Y600867D01*
X48792Y600783D01*
X48583Y600575D01*
X48417Y600283D01*
X48375Y599992D01*
X48417Y599700D01*
X48583Y599325D01*
X47500Y599450D01*
Y600575D01*
G01X50000Y603550D02*
X47500D01*
X49292Y602008D01*
Y604092D01*
G01X49625Y605233D02*
X49833Y605483D01*
X49958Y605775D01*
X50000Y606150D01*
X49917Y606525D01*
X49750Y606817D01*
X49458Y607025D01*
X49125Y607067D01*
X48792Y606983D01*
X48583Y606775D01*
X48417Y606483D01*
X48375Y606192D01*
X48417Y605900D01*
X48583Y605525D01*
X47500Y605650D01*
Y606775D01*
G01X40900Y599400D02*
X44900D01*
Y606800D01*
G01X42017Y591500D02*
Y594000D01*
X43058D01*
X43392Y593875D01*
X43600Y593708D01*
X43683Y593375D01*
X43600Y593042D01*
X43350Y592833D01*
X43058Y592708D01*
X42017D01*
G01X43058D02*
X43683Y591500D01*
G01X45033Y591875D02*
X45283Y591667D01*
X45575Y591542D01*
X45950Y591500D01*
X46325Y591583D01*
X46617Y591750D01*
X46825Y592042D01*
X46867Y592375D01*
X46783Y592708D01*
X46575Y592917D01*
X46283Y593083D01*
X45992Y593125D01*
X45700Y593083D01*
X45325Y592917D01*
X45450Y594000D01*
X46575D01*
G01X49550Y591500D02*
Y594000D01*
X48008Y592208D01*
X50092D01*
G01X52650Y591500D02*
Y594000D01*
X51108Y592208D01*
X53192D01*
G01X40517Y624000D02*
Y626500D01*
X41558D01*
X41892Y626375D01*
X42100Y626208D01*
X42183Y625875D01*
X42100Y625542D01*
X41850Y625333D01*
X41558Y625208D01*
X40517D01*
G01X41558D02*
X42183Y624000D01*
G01X43533Y624500D02*
X43783Y624208D01*
X44117Y624042D01*
X44492Y624000D01*
X44825Y624042D01*
X45158Y624250D01*
X45367Y624500D01*
X45408Y624750D01*
X45325Y625042D01*
X45033Y625250D01*
X44742Y625333D01*
X44367D01*
G01X44742D02*
X44992Y625458D01*
X45200Y625667D01*
X45283Y625917D01*
X45200Y626167D01*
X44992Y626375D01*
X44617Y626500D01*
X44242Y626458D01*
X43867Y626292D01*
G01X46633Y624375D02*
X46883Y624167D01*
X47175Y624042D01*
X47550Y624000D01*
X47925Y624083D01*
X48217Y624250D01*
X48425Y624542D01*
X48467Y624875D01*
X48383Y625208D01*
X48175Y625417D01*
X47883Y625583D01*
X47592Y625625D01*
X47300Y625583D01*
X46925Y625417D01*
X47050Y626500D01*
X48175D01*
G01X50567Y624000D02*
X50650Y624542D01*
X50775Y625000D01*
X50942Y625417D01*
X51150Y625875D01*
X51483Y626500D01*
X49817D01*
G01X48500Y610850D02*
X51000D01*
G01X48500Y609892D02*
Y611808D01*
G01X51000Y613117D02*
X48500D01*
Y614117D01*
X48625Y614450D01*
X48917Y614700D01*
X49250Y614783D01*
X49583Y614700D01*
X49833Y614492D01*
X49958Y614117D01*
Y613117D01*
G01X51000Y617050D02*
X48500D01*
X49000Y616550D01*
G01X51000D02*
Y617550D01*
G01X48917Y619358D02*
X48667Y619608D01*
X48542Y619900D01*
X48500Y620233D01*
X48583Y620650D01*
X48792Y620942D01*
X49042Y621025D01*
X49292Y620983D01*
X49500Y620817D01*
X49917Y619983D01*
X50208Y619608D01*
X50625Y619358D01*
X51000Y619275D01*
Y621025D01*
G01X43000Y637500D02*
Y633500D01*
X50400D01*
G01X43000Y641600D02*
Y637600D01*
X50400D01*
G01X55049Y658487D02*
Y654487D01*
X62449D01*
G01X55049D02*
Y650487D01*
X62449D01*
G01X56271Y664078D02*
Y666578D01*
X57312D01*
X57646Y666453D01*
X57854Y666286D01*
X57937Y665953D01*
X57854Y665620D01*
X57604Y665411D01*
X57312Y665286D01*
X56271D01*
G01X57312D02*
X57937Y664078D01*
G01X59412Y666161D02*
X59662Y666411D01*
X59954Y666536D01*
X60287Y666578D01*
X60704Y666495D01*
X60996Y666286D01*
X61079Y666036D01*
X61037Y665786D01*
X60871Y665578D01*
X60037Y665161D01*
X59662Y664870D01*
X59412Y664453D01*
X59329Y664078D01*
X61079D01*
G01X63304D02*
X63596Y664120D01*
X63929Y664245D01*
X64137Y664453D01*
X64221Y664745D01*
X64137Y665036D01*
X63887Y665286D01*
X63512Y665411D01*
X63096D01*
X62846Y665495D01*
X62637Y665703D01*
X62554Y665995D01*
X62679Y666286D01*
X62971Y666495D01*
X63304Y666578D01*
X63637Y666495D01*
X63929Y666286D01*
X64054Y665995D01*
X63971Y665703D01*
X63762Y665495D01*
X63512Y665411D01*
X63096D01*
X62721Y665286D01*
X62471Y665036D01*
X62387Y664745D01*
X62471Y664453D01*
X62679Y664245D01*
X63012Y664120D01*
X63304Y664078D01*
G01X65612Y665120D02*
X65904Y665411D01*
X66154Y665578D01*
X66487Y665661D01*
X66779Y665578D01*
X66987Y665411D01*
X67154Y665161D01*
X67196Y664870D01*
X67154Y664620D01*
X66987Y664370D01*
X66737Y664161D01*
X66446Y664078D01*
X66112Y664161D01*
X65821Y664411D01*
X65654Y664786D01*
X65612Y665203D01*
X65696Y665745D01*
X65821Y666036D01*
X66029Y666328D01*
X66321Y666536D01*
X66612Y666578D01*
X66904Y666495D01*
X67112Y666286D01*
G01X55049Y650487D02*
Y646487D01*
X62449D01*
G01X41570Y648047D02*
Y650547D01*
X42611D01*
X42945Y650422D01*
X43153Y650255D01*
X43236Y649922D01*
X43153Y649589D01*
X42903Y649380D01*
X42611Y649255D01*
X41570D01*
G01X42611D02*
X43236Y648047D01*
G01X44586Y648547D02*
X44836Y648255D01*
X45170Y648089D01*
X45545Y648047D01*
X45878Y648089D01*
X46211Y648297D01*
X46420Y648547D01*
X46461Y648797D01*
X46378Y649089D01*
X46086Y649297D01*
X45795Y649380D01*
X45420D01*
G01X45795D02*
X46045Y649505D01*
X46253Y649714D01*
X46336Y649964D01*
X46253Y650214D01*
X46045Y650422D01*
X45670Y650547D01*
X45295Y650505D01*
X44920Y650339D01*
G01X47811Y649089D02*
X48103Y649380D01*
X48353Y649547D01*
X48686Y649630D01*
X48978Y649547D01*
X49186Y649380D01*
X49353Y649130D01*
X49395Y648839D01*
X49353Y648589D01*
X49186Y648339D01*
X48936Y648130D01*
X48645Y648047D01*
X48311Y648130D01*
X48020Y648380D01*
X47853Y648755D01*
X47811Y649172D01*
X47895Y649714D01*
X48020Y650005D01*
X48228Y650297D01*
X48520Y650505D01*
X48811Y650547D01*
X49103Y650464D01*
X49311Y650255D01*
G01X51703Y650547D02*
X51370Y650464D01*
X51120Y650255D01*
X50953Y650005D01*
X50828Y649672D01*
X50786Y649297D01*
X50828Y648922D01*
X50953Y648589D01*
X51120Y648339D01*
X51370Y648130D01*
X51703Y648047D01*
X52036Y648130D01*
X52286Y648339D01*
X52453Y648589D01*
X52578Y648922D01*
X52620Y649297D01*
X52578Y649672D01*
X52453Y650005D01*
X52286Y650255D01*
X52036Y650464D01*
X51703Y650547D01*
G01X56271Y672078D02*
Y674578D01*
X57312D01*
X57646Y674453D01*
X57854Y674286D01*
X57937Y673953D01*
X57854Y673620D01*
X57604Y673411D01*
X57312Y673286D01*
X56271D01*
G01X57312D02*
X57937Y672078D01*
G01X59412Y674161D02*
X59662Y674411D01*
X59954Y674536D01*
X60287Y674578D01*
X60704Y674495D01*
X60996Y674286D01*
X61079Y674036D01*
X61037Y673786D01*
X60871Y673578D01*
X60037Y673161D01*
X59662Y672870D01*
X59412Y672453D01*
X59329Y672078D01*
X61079D01*
G01X63304D02*
X63596Y672120D01*
X63929Y672245D01*
X64137Y672453D01*
X64221Y672745D01*
X64137Y673036D01*
X63887Y673286D01*
X63512Y673411D01*
X63096D01*
X62846Y673495D01*
X62637Y673703D01*
X62554Y673995D01*
X62679Y674286D01*
X62971Y674495D01*
X63304Y674578D01*
X63637Y674495D01*
X63929Y674286D01*
X64054Y673995D01*
X63971Y673703D01*
X63762Y673495D01*
X63512Y673411D01*
X63096D01*
X62721Y673286D01*
X62471Y673036D01*
X62387Y672745D01*
X62471Y672453D01*
X62679Y672245D01*
X63012Y672120D01*
X63304Y672078D01*
G01X65612Y674161D02*
X65862Y674411D01*
X66154Y674536D01*
X66487Y674578D01*
X66904Y674495D01*
X67196Y674286D01*
X67279Y674036D01*
X67237Y673786D01*
X67071Y673578D01*
X66237Y673161D01*
X65862Y672870D01*
X65612Y672453D01*
X65529Y672078D01*
X67279D01*
G01X56271Y668078D02*
Y670578D01*
X57312D01*
X57646Y670453D01*
X57854Y670286D01*
X57937Y669953D01*
X57854Y669620D01*
X57604Y669411D01*
X57312Y669286D01*
X56271D01*
G01X57312D02*
X57937Y668078D01*
G01X59412Y670161D02*
X59662Y670411D01*
X59954Y670536D01*
X60287Y670578D01*
X60704Y670495D01*
X60996Y670286D01*
X61079Y670036D01*
X61037Y669786D01*
X60871Y669578D01*
X60037Y669161D01*
X59662Y668870D01*
X59412Y668453D01*
X59329Y668078D01*
X61079D01*
G01X63304D02*
X63596Y668120D01*
X63929Y668245D01*
X64137Y668453D01*
X64221Y668745D01*
X64137Y669036D01*
X63887Y669286D01*
X63512Y669411D01*
X63096D01*
X62846Y669495D01*
X62637Y669703D01*
X62554Y669995D01*
X62679Y670286D01*
X62971Y670495D01*
X63304Y670578D01*
X63637Y670495D01*
X63929Y670286D01*
X64054Y669995D01*
X63971Y669703D01*
X63762Y669495D01*
X63512Y669411D01*
X63096D01*
X62721Y669286D01*
X62471Y669036D01*
X62387Y668745D01*
X62471Y668453D01*
X62679Y668245D01*
X63012Y668120D01*
X63304Y668078D01*
G01X66904D02*
Y670578D01*
X65362Y668786D01*
X67446D01*
G01X58608Y721500D02*
Y724000D01*
X60192D01*
G01X59608Y722792D02*
X58608D01*
G01X61583Y722000D02*
X61833Y721708D01*
X62167Y721542D01*
X62542Y721500D01*
X62875Y721542D01*
X63208Y721750D01*
X63417Y722000D01*
X63458Y722250D01*
X63375Y722542D01*
X63083Y722750D01*
X62792Y722833D01*
X62417D01*
G01X62792D02*
X63042Y722958D01*
X63250Y723167D01*
X63333Y723417D01*
X63250Y723667D01*
X63042Y723875D01*
X62667Y724000D01*
X62292Y723958D01*
X61917Y723792D01*
G01X64808Y723583D02*
X65058Y723833D01*
X65350Y723958D01*
X65683Y724000D01*
X66100Y723917D01*
X66392Y723708D01*
X66475Y723458D01*
X66433Y723208D01*
X66267Y723000D01*
X65433Y722583D01*
X65058Y722292D01*
X64808Y721875D01*
X64725Y721500D01*
X66475D01*
G01X73999Y727150D02*
X50999D01*
G01D02*
Y765950D01*
G01X58999Y767350D02*
X76999D01*
G01X58999Y778550D02*
Y767350D01*
G01X50999Y765950D02*
X73999D01*
G01X45207Y778817D02*
X45082Y778567D01*
X44999Y778275D01*
Y777942D01*
X45124Y777567D01*
X45332Y777275D01*
X45582Y777067D01*
X45999Y776900D01*
X46374Y776858D01*
X46749Y776942D01*
X46999Y777067D01*
X47249Y777317D01*
X47416Y777608D01*
X47499Y777900D01*
Y778192D01*
X47416Y778483D01*
X47291Y778733D01*
X47124Y778942D01*
G01X46999Y780083D02*
X47291Y780333D01*
X47457Y780667D01*
X47499Y781042D01*
X47457Y781375D01*
X47249Y781708D01*
X46999Y781917D01*
X46749Y781958D01*
X46457Y781875D01*
X46249Y781583D01*
X46166Y781292D01*
Y780917D01*
G01Y781292D02*
X46041Y781542D01*
X45832Y781750D01*
X45582Y781833D01*
X45332Y781750D01*
X45124Y781542D01*
X44999Y781167D01*
X45041Y780792D01*
X45207Y780417D01*
G01X47124Y783183D02*
X47332Y783433D01*
X47457Y783725D01*
X47499Y784100D01*
X47416Y784475D01*
X47249Y784767D01*
X46957Y784975D01*
X46624Y785017D01*
X46291Y784933D01*
X46082Y784725D01*
X45916Y784433D01*
X45874Y784142D01*
X45916Y783850D01*
X46082Y783475D01*
X44999Y783600D01*
Y784725D01*
G01X47499Y787200D02*
X44999D01*
X45499Y786700D01*
G01X47499D02*
Y787700D01*
G01X58999Y805750D02*
X76999D01*
G01X58999Y794550D02*
Y805750D01*
G01X40951Y998915D02*
Y1001415D01*
X41992D01*
X42326Y1001290D01*
X42534Y1001123D01*
X42617Y1000790D01*
X42534Y1000457D01*
X42284Y1000248D01*
X41992Y1000123D01*
X40951D01*
G01X41992D02*
X42617Y998915D01*
G01X44092Y1000998D02*
X44342Y1001248D01*
X44634Y1001373D01*
X44967Y1001415D01*
X45384Y1001332D01*
X45676Y1001123D01*
X45759Y1000873D01*
X45717Y1000623D01*
X45551Y1000415D01*
X44717Y999998D01*
X44342Y999707D01*
X44092Y999290D01*
X44009Y998915D01*
X45759D01*
G01X47192Y999957D02*
X47484Y1000248D01*
X47734Y1000415D01*
X48067Y1000498D01*
X48359Y1000415D01*
X48567Y1000248D01*
X48734Y999998D01*
X48776Y999707D01*
X48734Y999457D01*
X48567Y999207D01*
X48317Y998998D01*
X48026Y998915D01*
X47692Y998998D01*
X47401Y999248D01*
X47234Y999623D01*
X47192Y1000040D01*
X47276Y1000582D01*
X47401Y1000873D01*
X47609Y1001165D01*
X47901Y1001373D01*
X48192Y1001415D01*
X48484Y1001332D01*
X48692Y1001123D01*
G01X51084Y998915D02*
X51376Y998957D01*
X51709Y999082D01*
X51917Y999290D01*
X52001Y999582D01*
X51917Y999873D01*
X51667Y1000123D01*
X51292Y1000248D01*
X50876D01*
X50626Y1000332D01*
X50417Y1000540D01*
X50334Y1000832D01*
X50459Y1001123D01*
X50751Y1001332D01*
X51084Y1001415D01*
X51417Y1001332D01*
X51709Y1001123D01*
X51834Y1000832D01*
X51751Y1000540D01*
X51542Y1000332D01*
X51292Y1000248D01*
X50876D01*
X50501Y1000123D01*
X50251Y999873D01*
X50167Y999582D01*
X50251Y999290D01*
X50459Y999082D01*
X50792Y998957D01*
X51084Y998915D01*
G01X40888Y1002915D02*
Y1005415D01*
X41929D01*
X42263Y1005290D01*
X42471Y1005123D01*
X42554Y1004790D01*
X42471Y1004457D01*
X42221Y1004248D01*
X41929Y1004123D01*
X40888D01*
G01X41929D02*
X42554Y1002915D01*
G01X44029Y1004998D02*
X44279Y1005248D01*
X44571Y1005373D01*
X44904Y1005415D01*
X45321Y1005332D01*
X45613Y1005123D01*
X45696Y1004873D01*
X45654Y1004623D01*
X45488Y1004415D01*
X44654Y1003998D01*
X44279Y1003707D01*
X44029Y1003290D01*
X43946Y1002915D01*
X45696D01*
G01X47838D02*
X47921Y1003457D01*
X48046Y1003915D01*
X48213Y1004332D01*
X48421Y1004790D01*
X48754Y1005415D01*
X47088D01*
G01X51021D02*
X50688Y1005332D01*
X50438Y1005123D01*
X50271Y1004873D01*
X50146Y1004540D01*
X50104Y1004165D01*
X50146Y1003790D01*
X50271Y1003457D01*
X50438Y1003207D01*
X50688Y1002998D01*
X51021Y1002915D01*
X51354Y1002998D01*
X51604Y1003207D01*
X51771Y1003457D01*
X51896Y1003790D01*
X51938Y1004165D01*
X51896Y1004540D01*
X51771Y1004873D01*
X51604Y1005123D01*
X51354Y1005332D01*
X51021Y1005415D01*
G01X61699Y1015050D02*
Y1019050D01*
X54299D01*
G01X61636D02*
Y1023050D01*
X54236D01*
G01X40888Y1006915D02*
Y1009415D01*
X41929D01*
X42263Y1009290D01*
X42471Y1009123D01*
X42554Y1008790D01*
X42471Y1008457D01*
X42221Y1008248D01*
X41929Y1008123D01*
X40888D01*
G01X41929D02*
X42554Y1006915D01*
G01X44029Y1008998D02*
X44279Y1009248D01*
X44571Y1009373D01*
X44904Y1009415D01*
X45321Y1009332D01*
X45613Y1009123D01*
X45696Y1008873D01*
X45654Y1008623D01*
X45488Y1008415D01*
X44654Y1007998D01*
X44279Y1007707D01*
X44029Y1007290D01*
X43946Y1006915D01*
X45696D01*
G01X47838D02*
X47921Y1007457D01*
X48046Y1007915D01*
X48213Y1008332D01*
X48421Y1008790D01*
X48754Y1009415D01*
X47088D01*
G01X50229Y1008998D02*
X50479Y1009248D01*
X50771Y1009373D01*
X51104Y1009415D01*
X51521Y1009332D01*
X51813Y1009123D01*
X51896Y1008873D01*
X51854Y1008623D01*
X51688Y1008415D01*
X50854Y1007998D01*
X50479Y1007707D01*
X50229Y1007290D01*
X50146Y1006915D01*
X51896D01*
G01X61636Y1023050D02*
Y1027050D01*
X54236D01*
G01X46674Y1040717D02*
Y1043217D01*
G01X48424D02*
Y1040717D01*
G01Y1041967D02*
X46674D01*
G01X50566Y1040717D02*
X50649Y1041259D01*
X50774Y1041717D01*
X50941Y1042134D01*
X51149Y1042592D01*
X51482Y1043217D01*
X49816D01*
G01X47500Y1142500D02*
X57500D01*
G01Y1135500D02*
X47500D01*
G01X52500D02*
Y1142500D01*
G01X47500Y1132067D02*
X57500D01*
Y1128733D01*
X57000Y1127400D01*
X56333Y1126400D01*
X55333Y1125567D01*
X54166Y1124900D01*
X52500Y1124733D01*
X50833Y1124900D01*
X49667Y1125567D01*
X48666Y1126400D01*
X48000Y1127400D01*
X47500Y1128733D01*
Y1132067D01*
G01Y1121467D02*
X57500D01*
Y1118133D01*
X57000Y1116800D01*
X56333Y1115800D01*
X55333Y1114967D01*
X54166Y1114300D01*
X52500Y1114133D01*
X50833Y1114300D01*
X49667Y1114967D01*
X48666Y1115800D01*
X48000Y1116800D01*
X47500Y1118133D01*
Y1121467D01*
G01Y1107200D02*
X57500D01*
X55500Y1109200D01*
G01X47500D02*
Y1105200D01*
G01X55833Y1099767D02*
X56833Y1098767D01*
X57333Y1097600D01*
X57500Y1096267D01*
X57167Y1094600D01*
X56333Y1093433D01*
X55333Y1093100D01*
X54333Y1093267D01*
X53500Y1093933D01*
X51833Y1097267D01*
X50667Y1098767D01*
X49000Y1099767D01*
X47500Y1100100D01*
Y1093100D01*
G01X44167Y1091000D02*
Y1081000D01*
G01X57500Y1078733D02*
X47500D01*
Y1072067D01*
G01Y1061467D02*
Y1068133D01*
X57500D01*
Y1061467D01*
G01X52667Y1064133D02*
Y1068133D01*
G01X47500Y1057867D02*
X57500D01*
Y1054533D01*
X57000Y1053200D01*
X56333Y1052200D01*
X55333Y1051367D01*
X54166Y1050700D01*
X52500Y1050533D01*
X50833Y1050700D01*
X49667Y1051367D01*
X48666Y1052200D01*
X48000Y1053200D01*
X47500Y1054533D01*
Y1057867D01*
G01X44965Y1627950D02*
X54965Y1620950D01*
G01Y1627950D02*
X44965Y1620950D01*
G01Y1613850D02*
X54965D01*
X52965Y1615850D01*
G01X44965D02*
Y1611850D01*
G01X49131Y1606417D02*
X50298Y1605250D01*
X50965Y1604250D01*
X51298Y1602917D01*
X50965Y1601750D01*
X50298Y1600917D01*
X49298Y1600250D01*
X48132Y1600083D01*
X47132Y1600250D01*
X46131Y1600917D01*
X45298Y1601917D01*
X44965Y1603083D01*
X45298Y1604417D01*
X46298Y1605583D01*
X47798Y1606250D01*
X49465Y1606417D01*
X51631Y1606083D01*
X52798Y1605583D01*
X53965Y1604750D01*
X54798Y1603583D01*
X54965Y1602417D01*
X54632Y1601250D01*
X53798Y1600417D01*
G01X44965Y1595983D02*
X54965D01*
Y1591983D01*
X54465Y1590650D01*
X53298Y1589650D01*
X51965Y1589317D01*
X50632Y1589650D01*
X49632Y1590483D01*
X49131Y1591983D01*
Y1595983D01*
G01X54132Y1578383D02*
X54632Y1579383D01*
X54965Y1580550D01*
Y1581883D01*
X54465Y1583384D01*
X53632Y1584550D01*
X52632Y1585383D01*
X50965Y1586050D01*
X49465Y1586217D01*
X47965Y1585883D01*
X46965Y1585383D01*
X45965Y1584383D01*
X45298Y1583217D01*
X44965Y1582050D01*
Y1580883D01*
X45298Y1579717D01*
X45798Y1578717D01*
X46465Y1577883D01*
G01X54965Y1573450D02*
Y1569450D01*
G01Y1571450D02*
X44965D01*
G01Y1573450D02*
Y1569450D01*
G01Y1557517D02*
Y1564183D01*
X54965D01*
Y1557517D01*
G01X50132Y1560183D02*
Y1564183D01*
G01X41632Y1555250D02*
Y1545250D01*
G01X44965Y1543817D02*
X54965Y1539650D01*
X44965Y1535483D01*
G01X48465Y1536983D02*
Y1542317D01*
G01X61467Y1823563D02*
Y1821063D01*
X63133D01*
G01X66233D02*
X64567D01*
Y1823563D01*
X66233D01*
G01X65567Y1822355D02*
X64567D01*
G01X67583Y1821063D02*
Y1823563D01*
X68417D01*
X68750Y1823438D01*
X69000Y1823271D01*
X69208Y1823021D01*
X69375Y1822730D01*
X69417Y1822313D01*
X69375Y1821896D01*
X69208Y1821605D01*
X69000Y1821355D01*
X68750Y1821188D01*
X68417Y1821063D01*
X67583D01*
G01X71600D02*
Y1823563D01*
X71100Y1823063D01*
G01Y1821063D02*
X72100D01*
G01X74700D02*
Y1823563D01*
X74200Y1823063D01*
G01Y1821063D02*
X75200D01*
G01X53000Y1837900D02*
X52958Y1837567D01*
X52792Y1837275D01*
X52542Y1837025D01*
X52250Y1836858D01*
X51917Y1836775D01*
X51583D01*
X51250Y1836858D01*
X50958Y1837025D01*
X50708Y1837275D01*
X50542Y1837567D01*
X50500Y1837900D01*
X50542Y1838233D01*
X50708Y1838525D01*
X50958Y1838775D01*
X51250Y1838942D01*
X51583Y1839025D01*
X51917D01*
X52250Y1838942D01*
X52542Y1838775D01*
X52792Y1838525D01*
X52958Y1838233D01*
X53000Y1837900D01*
G01X52333Y1838233D02*
X53000Y1838733D01*
G01Y1841500D02*
X50500D01*
X52292Y1839958D01*
Y1842042D01*
G01X53000Y1844600D02*
X50500D01*
X52292Y1843058D01*
Y1845142D01*
G01X71199Y1849100D02*
X57199D01*
G01Y1836100D02*
X71199D01*
G01X57199Y1849100D02*
Y1836100D01*
G01X43500Y1896750D02*
X48500Y1893250D01*
G01Y1896750D02*
X43500Y1893250D01*
G01Y1889400D02*
X48500D01*
X47500Y1890400D01*
G01X43500D02*
Y1888400D01*
G01Y1885467D02*
X48500D01*
Y1883467D01*
X48250Y1882800D01*
X47667Y1882300D01*
X47000Y1882133D01*
X46333Y1882300D01*
X45833Y1882717D01*
X45583Y1883467D01*
Y1885467D01*
G01X48083Y1876367D02*
X48333Y1876867D01*
X48500Y1877450D01*
Y1878117D01*
X48250Y1878867D01*
X47833Y1879450D01*
X47333Y1879867D01*
X46500Y1880200D01*
X45750Y1880283D01*
X45000Y1880117D01*
X44500Y1879867D01*
X44000Y1879367D01*
X43667Y1878783D01*
X43500Y1878200D01*
Y1877617D01*
X43667Y1877033D01*
X43917Y1876533D01*
X44250Y1876117D01*
G01X48500Y1873600D02*
Y1871600D01*
G01Y1872600D02*
X43500D01*
G01Y1873600D02*
Y1871600D01*
G01Y1865333D02*
Y1868667D01*
X48500D01*
Y1865333D01*
G01X46083Y1866667D02*
Y1868667D01*
G01X41833Y1863900D02*
Y1858900D01*
G01X43500Y1857883D02*
X48500Y1855800D01*
X43500Y1853717D01*
G01X45250Y1854467D02*
Y1857133D01*
G01X59999Y1867750D02*
Y1873250D01*
G01X67999Y1867750D02*
X59999D01*
G01X57500Y1873017D02*
X55000D01*
Y1874017D01*
X55125Y1874350D01*
X55417Y1874600D01*
X55750Y1874683D01*
X56083Y1874600D01*
X56333Y1874392D01*
X56458Y1874017D01*
Y1873017D01*
G01X55208Y1877867D02*
X55083Y1877617D01*
X55000Y1877325D01*
Y1876992D01*
X55125Y1876617D01*
X55333Y1876325D01*
X55583Y1876117D01*
X56000Y1875950D01*
X56375Y1875908D01*
X56750Y1875992D01*
X57000Y1876117D01*
X57250Y1876367D01*
X57417Y1876658D01*
X57500Y1876950D01*
Y1877242D01*
X57417Y1877533D01*
X57292Y1877783D01*
X57125Y1877992D01*
G01X57000Y1879133D02*
X57292Y1879383D01*
X57458Y1879717D01*
X57500Y1880092D01*
X57458Y1880425D01*
X57250Y1880758D01*
X57000Y1880967D01*
X56750Y1881008D01*
X56458Y1880925D01*
X56250Y1880633D01*
X56167Y1880342D01*
Y1879967D01*
G01Y1880342D02*
X56042Y1880592D01*
X55833Y1880800D01*
X55583Y1880883D01*
X55333Y1880800D01*
X55125Y1880592D01*
X55000Y1880217D01*
X55042Y1879842D01*
X55208Y1879467D01*
G01X57208Y1882442D02*
X57417Y1882733D01*
X57500Y1883067D01*
X57417Y1883400D01*
X57167Y1883692D01*
X56792Y1883900D01*
X56417Y1883983D01*
X55958D01*
X55583Y1883900D01*
X55250Y1883692D01*
X55083Y1883442D01*
X55000Y1883150D01*
X55083Y1882817D01*
X55250Y1882567D01*
X55500Y1882400D01*
X55833Y1882317D01*
X56125Y1882400D01*
X56417Y1882608D01*
X56583Y1882858D01*
X56625Y1883150D01*
X56542Y1883483D01*
X56333Y1883733D01*
X55958Y1883983D01*
G01X59999Y1885350D02*
X67999D01*
G01X59999Y1879850D02*
Y1885350D01*
G01X54016Y1905550D02*
Y1908050D01*
X55016D01*
X55349Y1907925D01*
X55599Y1907633D01*
X55682Y1907300D01*
X55599Y1906967D01*
X55391Y1906717D01*
X55016Y1906592D01*
X54016D01*
G01X58866Y1907842D02*
X58616Y1907967D01*
X58324Y1908050D01*
X57991D01*
X57616Y1907925D01*
X57324Y1907717D01*
X57116Y1907467D01*
X56949Y1907050D01*
X56907Y1906675D01*
X56991Y1906300D01*
X57116Y1906050D01*
X57366Y1905800D01*
X57657Y1905633D01*
X57949Y1905550D01*
X58241D01*
X58532Y1905633D01*
X58782Y1905758D01*
X58991Y1905925D01*
G01X60132Y1906050D02*
X60382Y1905758D01*
X60716Y1905592D01*
X61091Y1905550D01*
X61424Y1905592D01*
X61757Y1905800D01*
X61966Y1906050D01*
X62007Y1906300D01*
X61924Y1906592D01*
X61632Y1906800D01*
X61341Y1906883D01*
X60966D01*
G01X61341D02*
X61591Y1907008D01*
X61799Y1907217D01*
X61882Y1907467D01*
X61799Y1907717D01*
X61591Y1907925D01*
X61216Y1908050D01*
X60841Y1908008D01*
X60466Y1907842D01*
G01X64649Y1905550D02*
Y1908050D01*
X63107Y1906258D01*
X65191D01*
G01X44999Y1899567D02*
X42499D01*
Y1900567D01*
X42624Y1900900D01*
X42916Y1901150D01*
X43249Y1901233D01*
X43582Y1901150D01*
X43832Y1900942D01*
X43957Y1900567D01*
Y1899567D01*
G01X44999Y1902667D02*
X42499D01*
Y1903708D01*
X42624Y1904042D01*
X42791Y1904250D01*
X43124Y1904333D01*
X43457Y1904250D01*
X43666Y1904000D01*
X43791Y1903708D01*
Y1902667D01*
G01Y1903708D02*
X44999Y1904333D01*
G01X44624Y1905683D02*
X44832Y1905933D01*
X44957Y1906225D01*
X44999Y1906600D01*
X44916Y1906975D01*
X44749Y1907267D01*
X44457Y1907475D01*
X44124Y1907517D01*
X43791Y1907433D01*
X43582Y1907225D01*
X43416Y1906933D01*
X43374Y1906642D01*
X43416Y1906350D01*
X43582Y1905975D01*
X42499Y1906100D01*
Y1907225D01*
G01X44999Y1909700D02*
X42499D01*
X42999Y1909200D01*
G01X44999D02*
Y1910200D01*
G01X51499Y1907250D02*
X47499D01*
Y1899850D01*
G01X59517Y1895500D02*
Y1898000D01*
X60517D01*
X60850Y1897875D01*
X61100Y1897583D01*
X61183Y1897250D01*
X61100Y1896917D01*
X60892Y1896667D01*
X60517Y1896542D01*
X59517D01*
G01X62617Y1895500D02*
Y1898000D01*
X63658D01*
X63992Y1897875D01*
X64200Y1897708D01*
X64283Y1897375D01*
X64200Y1897042D01*
X63950Y1896833D01*
X63658Y1896708D01*
X62617D01*
G01X63658D02*
X64283Y1895500D01*
G01X65633Y1896000D02*
X65883Y1895708D01*
X66217Y1895542D01*
X66592Y1895500D01*
X66925Y1895542D01*
X67258Y1895750D01*
X67467Y1896000D01*
X67508Y1896250D01*
X67425Y1896542D01*
X67133Y1896750D01*
X66842Y1896833D01*
X66467D01*
G01X66842D02*
X67092Y1896958D01*
X67300Y1897167D01*
X67383Y1897417D01*
X67300Y1897667D01*
X67092Y1897875D01*
X66717Y1898000D01*
X66342Y1897958D01*
X65967Y1897792D01*
G01X69567Y1895500D02*
X69650Y1896042D01*
X69775Y1896500D01*
X69942Y1896917D01*
X70150Y1897375D01*
X70483Y1898000D01*
X68817D01*
G01X57699Y1895050D02*
Y1899050D01*
X50299D01*
G01X51111Y1915007D02*
Y1917507D01*
X52111D01*
X52444Y1917382D01*
X52694Y1917090D01*
X52777Y1916757D01*
X52694Y1916424D01*
X52486Y1916174D01*
X52111Y1916049D01*
X51111D01*
G01X55961Y1917299D02*
X55711Y1917424D01*
X55419Y1917507D01*
X55086D01*
X54711Y1917382D01*
X54419Y1917174D01*
X54211Y1916924D01*
X54044Y1916507D01*
X54002Y1916132D01*
X54086Y1915757D01*
X54211Y1915507D01*
X54461Y1915257D01*
X54752Y1915090D01*
X55044Y1915007D01*
X55336D01*
X55627Y1915090D01*
X55877Y1915215D01*
X56086Y1915382D01*
G01X57352Y1917090D02*
X57602Y1917340D01*
X57894Y1917465D01*
X58227Y1917507D01*
X58644Y1917424D01*
X58936Y1917215D01*
X59019Y1916965D01*
X58977Y1916715D01*
X58811Y1916507D01*
X57977Y1916090D01*
X57602Y1915799D01*
X57352Y1915382D01*
X57269Y1915007D01*
X59019D01*
G01X61244D02*
X61536Y1915049D01*
X61869Y1915174D01*
X62077Y1915382D01*
X62161Y1915674D01*
X62077Y1915965D01*
X61827Y1916215D01*
X61452Y1916340D01*
X61036D01*
X60786Y1916424D01*
X60577Y1916632D01*
X60494Y1916924D01*
X60619Y1917215D01*
X60911Y1917424D01*
X61244Y1917507D01*
X61577Y1917424D01*
X61869Y1917215D01*
X61994Y1916924D01*
X61911Y1916632D01*
X61702Y1916424D01*
X61452Y1916340D01*
X61036D01*
X60661Y1916215D01*
X60411Y1915965D01*
X60327Y1915674D01*
X60411Y1915382D01*
X60619Y1915174D01*
X60952Y1915049D01*
X61244Y1915007D01*
G01X51111Y1918507D02*
Y1921007D01*
X52111D01*
X52444Y1920882D01*
X52694Y1920590D01*
X52777Y1920257D01*
X52694Y1919924D01*
X52486Y1919674D01*
X52111Y1919549D01*
X51111D01*
G01X55961Y1920799D02*
X55711Y1920924D01*
X55419Y1921007D01*
X55086D01*
X54711Y1920882D01*
X54419Y1920674D01*
X54211Y1920424D01*
X54044Y1920007D01*
X54002Y1919632D01*
X54086Y1919257D01*
X54211Y1919007D01*
X54461Y1918757D01*
X54752Y1918590D01*
X55044Y1918507D01*
X55336D01*
X55627Y1918590D01*
X55877Y1918715D01*
X56086Y1918882D01*
G01X57227Y1919007D02*
X57477Y1918715D01*
X57811Y1918549D01*
X58186Y1918507D01*
X58519Y1918549D01*
X58852Y1918757D01*
X59061Y1919007D01*
X59102Y1919257D01*
X59019Y1919549D01*
X58727Y1919757D01*
X58436Y1919840D01*
X58061D01*
G01X58436D02*
X58686Y1919965D01*
X58894Y1920174D01*
X58977Y1920424D01*
X58894Y1920674D01*
X58686Y1920882D01*
X58311Y1921007D01*
X57936Y1920965D01*
X57561Y1920799D01*
G01X60327Y1919007D02*
X60577Y1918715D01*
X60911Y1918549D01*
X61286Y1918507D01*
X61619Y1918549D01*
X61952Y1918757D01*
X62161Y1919007D01*
X62202Y1919257D01*
X62119Y1919549D01*
X61827Y1919757D01*
X61536Y1919840D01*
X61161D01*
G01X61536D02*
X61786Y1919965D01*
X61994Y1920174D01*
X62077Y1920424D01*
X61994Y1920674D01*
X61786Y1920882D01*
X61411Y1921007D01*
X61036Y1920965D01*
X60661Y1920799D01*
G01X49094Y1915524D02*
X46594D01*
Y1916524D01*
X46719Y1916857D01*
X47011Y1917107D01*
X47344Y1917190D01*
X47677Y1917107D01*
X47927Y1916899D01*
X48052Y1916524D01*
Y1915524D01*
G01X49094Y1918624D02*
X46594D01*
Y1919665D01*
X46719Y1919999D01*
X46886Y1920207D01*
X47219Y1920290D01*
X47552Y1920207D01*
X47761Y1919957D01*
X47886Y1919665D01*
Y1918624D01*
G01Y1919665D02*
X49094Y1920290D01*
G01X48594Y1921640D02*
X48886Y1921890D01*
X49052Y1922224D01*
X49094Y1922599D01*
X49052Y1922932D01*
X48844Y1923265D01*
X48594Y1923474D01*
X48344Y1923515D01*
X48052Y1923432D01*
X47844Y1923140D01*
X47761Y1922849D01*
Y1922474D01*
G01Y1922849D02*
X47636Y1923099D01*
X47427Y1923307D01*
X47177Y1923390D01*
X46927Y1923307D01*
X46719Y1923099D01*
X46594Y1922724D01*
X46636Y1922349D01*
X46802Y1921974D01*
G01X48052Y1924865D02*
X47761Y1925157D01*
X47594Y1925407D01*
X47511Y1925740D01*
X47594Y1926032D01*
X47761Y1926240D01*
X48011Y1926407D01*
X48302Y1926449D01*
X48552Y1926407D01*
X48802Y1926240D01*
X49011Y1925990D01*
X49094Y1925699D01*
X49011Y1925365D01*
X48761Y1925074D01*
X48386Y1924907D01*
X47969Y1924865D01*
X47427Y1924949D01*
X47136Y1925074D01*
X46844Y1925282D01*
X46636Y1925574D01*
X46594Y1925865D01*
X46677Y1926157D01*
X46886Y1926365D01*
G01X52980Y1929476D02*
Y1926976D01*
G01X52022Y1929476D02*
X53938D01*
G01X55247Y1926976D02*
Y1929476D01*
X56247D01*
X56580Y1929351D01*
X56830Y1929059D01*
X56913Y1928726D01*
X56830Y1928393D01*
X56622Y1928143D01*
X56247Y1928018D01*
X55247D01*
G01X58388Y1929059D02*
X58638Y1929309D01*
X58930Y1929434D01*
X59263Y1929476D01*
X59680Y1929393D01*
X59972Y1929184D01*
X60055Y1928934D01*
X60013Y1928684D01*
X59847Y1928476D01*
X59013Y1928059D01*
X58638Y1927768D01*
X58388Y1927351D01*
X58305Y1926976D01*
X60055D01*
G01X62280D02*
Y1929476D01*
X61780Y1928976D01*
G01Y1926976D02*
X62780D01*
G01X52980Y1925635D02*
Y1923135D01*
G01X52022Y1925635D02*
X53938D01*
G01X55247Y1923135D02*
Y1925635D01*
X56247D01*
X56580Y1925510D01*
X56830Y1925218D01*
X56913Y1924885D01*
X56830Y1924552D01*
X56622Y1924302D01*
X56247Y1924177D01*
X55247D01*
G01X58388Y1925218D02*
X58638Y1925468D01*
X58930Y1925593D01*
X59263Y1925635D01*
X59680Y1925552D01*
X59972Y1925343D01*
X60055Y1925093D01*
X60013Y1924843D01*
X59847Y1924635D01*
X59013Y1924218D01*
X58638Y1923927D01*
X58388Y1923510D01*
X58305Y1923135D01*
X60055D01*
G01X62780D02*
Y1925635D01*
X61238Y1923843D01*
X63322D01*
G01X53368Y1932862D02*
X58368D01*
Y1937862D01*
G01X52242Y1933869D02*
Y1930869D01*
G01X42399Y1933869D02*
Y1931869D01*
G01X62499Y1943117D02*
X59999D01*
Y1944117D01*
X60124Y1944450D01*
X60416Y1944700D01*
X60749Y1944783D01*
X61082Y1944700D01*
X61332Y1944492D01*
X61457Y1944117D01*
Y1943117D01*
G01X59999Y1946133D02*
X61791D01*
X62166Y1946300D01*
X62416Y1946633D01*
X62499Y1947050D01*
X62416Y1947467D01*
X62166Y1947800D01*
X61791Y1947967D01*
X59999D01*
G01X61999Y1949233D02*
X62291Y1949483D01*
X62457Y1949817D01*
X62499Y1950192D01*
X62457Y1950525D01*
X62249Y1950858D01*
X61999Y1951067D01*
X61749Y1951108D01*
X61457Y1951025D01*
X61249Y1950733D01*
X61166Y1950442D01*
Y1950067D01*
G01Y1950442D02*
X61041Y1950692D01*
X60832Y1950900D01*
X60582Y1950983D01*
X60332Y1950900D01*
X60124Y1950692D01*
X59999Y1950317D01*
X60041Y1949942D01*
X60207Y1949567D01*
G01X58368Y1955562D02*
Y1960562D01*
X53368D01*
G01X50999Y1977067D02*
X48499D01*
Y1978067D01*
X48624Y1978400D01*
X48916Y1978650D01*
X49249Y1978733D01*
X49582Y1978650D01*
X49832Y1978442D01*
X49957Y1978067D01*
Y1977067D01*
G01X50999Y1980167D02*
X48499D01*
Y1981208D01*
X48624Y1981542D01*
X48791Y1981750D01*
X49124Y1981833D01*
X49457Y1981750D01*
X49666Y1981500D01*
X49791Y1981208D01*
Y1980167D01*
G01Y1981208D02*
X50999Y1981833D01*
G01X50499Y1983183D02*
X50791Y1983433D01*
X50957Y1983767D01*
X50999Y1984142D01*
X50957Y1984475D01*
X50749Y1984808D01*
X50499Y1985017D01*
X50249Y1985058D01*
X49957Y1984975D01*
X49749Y1984683D01*
X49666Y1984392D01*
Y1984017D01*
G01Y1984392D02*
X49541Y1984642D01*
X49332Y1984850D01*
X49082Y1984933D01*
X48832Y1984850D01*
X48624Y1984642D01*
X48499Y1984267D01*
X48541Y1983892D01*
X48707Y1983517D01*
G01X50624Y1986283D02*
X50832Y1986533D01*
X50957Y1986825D01*
X50999Y1987200D01*
X50916Y1987575D01*
X50749Y1987867D01*
X50457Y1988075D01*
X50124Y1988117D01*
X49791Y1988033D01*
X49582Y1987825D01*
X49416Y1987533D01*
X49374Y1987242D01*
X49416Y1986950D01*
X49582Y1986575D01*
X48499Y1986700D01*
Y1987825D01*
G01X48305Y1959555D02*
Y1961555D01*
G01X46000Y1978017D02*
X43500D01*
Y1979017D01*
X43625Y1979350D01*
X43917Y1979600D01*
X44250Y1979683D01*
X44583Y1979600D01*
X44833Y1979392D01*
X44958Y1979017D01*
Y1978017D01*
G01X43708Y1982867D02*
X43583Y1982617D01*
X43500Y1982325D01*
Y1981992D01*
X43625Y1981617D01*
X43833Y1981325D01*
X44083Y1981117D01*
X44500Y1980950D01*
X44875Y1980908D01*
X45250Y1980992D01*
X45500Y1981117D01*
X45750Y1981367D01*
X45917Y1981658D01*
X46000Y1981950D01*
Y1982242D01*
X45917Y1982533D01*
X45792Y1982783D01*
X45625Y1982992D01*
G01X45500Y1984133D02*
X45792Y1984383D01*
X45958Y1984717D01*
X46000Y1985092D01*
X45958Y1985425D01*
X45750Y1985758D01*
X45500Y1985967D01*
X45250Y1986008D01*
X44958Y1985925D01*
X44750Y1985633D01*
X44667Y1985342D01*
Y1984967D01*
G01Y1985342D02*
X44542Y1985592D01*
X44333Y1985800D01*
X44083Y1985883D01*
X43833Y1985800D01*
X43625Y1985592D01*
X43500Y1985217D01*
X43542Y1984842D01*
X43708Y1984467D01*
G01X43500Y1988150D02*
X43583Y1987817D01*
X43792Y1987567D01*
X44042Y1987400D01*
X44375Y1987275D01*
X44750Y1987233D01*
X45125Y1987275D01*
X45458Y1987400D01*
X45708Y1987567D01*
X45917Y1987817D01*
X46000Y1988150D01*
X45917Y1988483D01*
X45708Y1988733D01*
X45458Y1988900D01*
X45125Y1989025D01*
X44750Y1989067D01*
X44375Y1989025D01*
X44042Y1988900D01*
X43792Y1988733D01*
X43583Y1988483D01*
X43500Y1988150D01*
G01X58000Y1978517D02*
X55500D01*
Y1979517D01*
X55625Y1979850D01*
X55917Y1980100D01*
X56250Y1980183D01*
X56583Y1980100D01*
X56833Y1979892D01*
X56958Y1979517D01*
Y1978517D01*
G01X55708Y1983367D02*
X55583Y1983117D01*
X55500Y1982825D01*
Y1982492D01*
X55625Y1982117D01*
X55833Y1981825D01*
X56083Y1981617D01*
X56500Y1981450D01*
X56875Y1981408D01*
X57250Y1981492D01*
X57500Y1981617D01*
X57750Y1981867D01*
X57917Y1982158D01*
X58000Y1982450D01*
Y1982742D01*
X57917Y1983033D01*
X57792Y1983283D01*
X57625Y1983492D01*
G01X57500Y1984633D02*
X57792Y1984883D01*
X57958Y1985217D01*
X58000Y1985592D01*
X57958Y1985925D01*
X57750Y1986258D01*
X57500Y1986467D01*
X57250Y1986508D01*
X56958Y1986425D01*
X56750Y1986133D01*
X56667Y1985842D01*
Y1985467D01*
G01Y1985842D02*
X56542Y1986092D01*
X56333Y1986300D01*
X56083Y1986383D01*
X55833Y1986300D01*
X55625Y1986092D01*
X55500Y1985717D01*
X55542Y1985342D01*
X55708Y1984967D01*
G01X58000Y1988567D02*
X57458Y1988650D01*
X57000Y1988775D01*
X56583Y1988942D01*
X56125Y1989150D01*
X55500Y1989483D01*
Y1987817D01*
G01X62967Y201562D02*
Y199062D01*
X64633D01*
G01X67733D02*
X66067D01*
Y201562D01*
X67733D01*
G01X67067Y200354D02*
X66067D01*
G01X69083Y199062D02*
Y201562D01*
X69917D01*
X70250Y201437D01*
X70500Y201270D01*
X70708Y201020D01*
X70875Y200729D01*
X70917Y200312D01*
X70875Y199895D01*
X70708Y199604D01*
X70500Y199354D01*
X70250Y199187D01*
X69917Y199062D01*
X69083D01*
G01X73100D02*
Y201562D01*
X72600Y201062D01*
G01Y199062D02*
X73600D01*
G01X75283Y199437D02*
X75533Y199229D01*
X75825Y199104D01*
X76200Y199062D01*
X76575Y199145D01*
X76867Y199312D01*
X77075Y199604D01*
X77117Y199937D01*
X77033Y200270D01*
X76825Y200479D01*
X76533Y200645D01*
X76242Y200687D01*
X75950Y200645D01*
X75575Y200479D01*
X75700Y201562D01*
X76825D01*
G01X63198Y204231D02*
Y211831D01*
X74598D01*
Y204231D01*
X63198D01*
G01X83199Y202550D02*
Y206550D01*
X75799D01*
G01X83199D02*
Y210550D01*
X75799D01*
G01X64467Y607563D02*
Y605063D01*
X66133D01*
G01X69233D02*
X67567D01*
Y607563D01*
X69233D01*
G01X68567Y606355D02*
X67567D01*
G01X70583Y605063D02*
Y607563D01*
X71417D01*
X71750Y607438D01*
X72000Y607271D01*
X72208Y607021D01*
X72375Y606730D01*
X72417Y606313D01*
X72375Y605896D01*
X72208Y605605D01*
X72000Y605355D01*
X71750Y605188D01*
X71417Y605063D01*
X70583D01*
G01X74600D02*
Y607563D01*
X74100Y607063D01*
G01Y605063D02*
X75100D01*
G01X78200D02*
Y607563D01*
X76658Y605771D01*
X78742D01*
G01X63198Y609743D02*
Y617343D01*
X74598D01*
Y609743D01*
X63198D01*
G01X77518Y619450D02*
Y621950D01*
X78559D01*
X78893Y621825D01*
X79101Y621658D01*
X79184Y621325D01*
X79101Y620992D01*
X78851Y620783D01*
X78559Y620658D01*
X77518D01*
G01X78559D02*
X79184Y619450D01*
G01X80659Y621533D02*
X80909Y621783D01*
X81201Y621908D01*
X81534Y621950D01*
X81951Y621867D01*
X82243Y621658D01*
X82326Y621408D01*
X82284Y621158D01*
X82118Y620950D01*
X81284Y620533D01*
X80909Y620242D01*
X80659Y619825D01*
X80576Y619450D01*
X82326D01*
G01X84551D02*
X84843Y619492D01*
X85176Y619617D01*
X85384Y619825D01*
X85468Y620117D01*
X85384Y620408D01*
X85134Y620658D01*
X84759Y620783D01*
X84343D01*
X84093Y620867D01*
X83884Y621075D01*
X83801Y621367D01*
X83926Y621658D01*
X84218Y621867D01*
X84551Y621950D01*
X84884Y621867D01*
X85176Y621658D01*
X85301Y621367D01*
X85218Y621075D01*
X85009Y620867D01*
X84759Y620783D01*
X84343D01*
X83968Y620658D01*
X83718Y620408D01*
X83634Y620117D01*
X83718Y619825D01*
X83926Y619617D01*
X84259Y619492D01*
X84551Y619450D01*
G01X86734Y619950D02*
X86984Y619658D01*
X87318Y619492D01*
X87693Y619450D01*
X88026Y619492D01*
X88359Y619700D01*
X88568Y619950D01*
X88609Y620200D01*
X88526Y620492D01*
X88234Y620700D01*
X87943Y620783D01*
X87568D01*
G01X87943D02*
X88193Y620908D01*
X88401Y621117D01*
X88484Y621367D01*
X88401Y621617D01*
X88193Y621825D01*
X87818Y621950D01*
X87443Y621908D01*
X87068Y621742D01*
G01X83201Y609450D02*
Y613450D01*
X75801D01*
G01X83201D02*
Y617450D01*
X75801D01*
G01X77017Y624500D02*
Y627000D01*
X78058D01*
X78392Y626875D01*
X78600Y626708D01*
X78683Y626375D01*
X78600Y626042D01*
X78350Y625833D01*
X78058Y625708D01*
X77017D01*
G01X78058D02*
X78683Y624500D01*
G01X80158Y626583D02*
X80408Y626833D01*
X80700Y626958D01*
X81033Y627000D01*
X81450Y626917D01*
X81742Y626708D01*
X81825Y626458D01*
X81783Y626208D01*
X81617Y626000D01*
X80783Y625583D01*
X80408Y625292D01*
X80158Y624875D01*
X80075Y624500D01*
X81825D01*
G01X84050D02*
X84342Y624542D01*
X84675Y624667D01*
X84883Y624875D01*
X84967Y625167D01*
X84883Y625458D01*
X84633Y625708D01*
X84258Y625833D01*
X83842D01*
X83592Y625917D01*
X83383Y626125D01*
X83300Y626417D01*
X83425Y626708D01*
X83717Y626917D01*
X84050Y627000D01*
X84383Y626917D01*
X84675Y626708D01*
X84800Y626417D01*
X84717Y626125D01*
X84508Y625917D01*
X84258Y625833D01*
X83842D01*
X83467Y625708D01*
X83217Y625458D01*
X83133Y625167D01*
X83217Y624875D01*
X83425Y624667D01*
X83758Y624542D01*
X84050Y624500D01*
G01X86233Y624875D02*
X86483Y624667D01*
X86775Y624542D01*
X87150Y624500D01*
X87525Y624583D01*
X87817Y624750D01*
X88025Y625042D01*
X88067Y625375D01*
X87983Y625708D01*
X87775Y625917D01*
X87483Y626083D01*
X87192Y626125D01*
X86900Y626083D01*
X86525Y625917D01*
X86650Y627000D01*
X87775D01*
G01X73799Y644550D02*
Y640550D01*
X81199D01*
G01X79900Y653000D02*
X79567Y653042D01*
X79275Y653208D01*
X79025Y653458D01*
X78858Y653750D01*
X78775Y654083D01*
Y654417D01*
X78858Y654750D01*
X79025Y655042D01*
X79275Y655292D01*
X79567Y655458D01*
X79900Y655500D01*
X80233Y655458D01*
X80525Y655292D01*
X80775Y655042D01*
X80942Y654750D01*
X81025Y654417D01*
Y654083D01*
X80942Y653750D01*
X80775Y653458D01*
X80525Y653208D01*
X80233Y653042D01*
X79900Y653000D01*
G01X80233Y653667D02*
X80733Y653000D01*
G01X83500D02*
Y655500D01*
X81958Y653708D01*
X84042D01*
G01X86017Y653000D02*
X86100Y653542D01*
X86225Y654000D01*
X86392Y654417D01*
X86600Y654875D01*
X86933Y655500D01*
X85267D01*
G01X63299Y645400D02*
X77299D01*
G01X63299Y658400D02*
Y645400D01*
G01X77299Y658400D02*
X63299D01*
G01X77299Y645400D02*
Y658400D01*
G01X80917Y706000D02*
Y711000D01*
X84083D01*
G01X82917Y708583D02*
X80917D01*
G01X86267Y707000D02*
X86767Y706417D01*
X87433Y706083D01*
X88183Y706000D01*
X88850Y706083D01*
X89517Y706500D01*
X89933Y707000D01*
X90017Y707500D01*
X89850Y708083D01*
X89267Y708500D01*
X88683Y708667D01*
X87933D01*
G01X88683D02*
X89183Y708917D01*
X89600Y709333D01*
X89767Y709833D01*
X89600Y710333D01*
X89183Y710750D01*
X88433Y711000D01*
X87683Y710917D01*
X86933Y710583D01*
G01X92117Y710167D02*
X92617Y710667D01*
X93200Y710917D01*
X93867Y711000D01*
X94700Y710833D01*
X95283Y710417D01*
X95450Y709917D01*
X95367Y709417D01*
X95033Y709000D01*
X93367Y708167D01*
X92617Y707583D01*
X92117Y706750D01*
X91950Y706000D01*
X95450D01*
G01X99300Y705833D02*
X99133Y705917D01*
Y706083D01*
X99300Y706167D01*
X99467Y706083D01*
Y705917D01*
X99300Y705833D01*
G01Y708083D02*
X99133Y708167D01*
Y708333D01*
X99300Y708417D01*
X99467Y708333D01*
Y708167D01*
X99300Y708083D01*
G01X103067Y707000D02*
X103567Y706417D01*
X104233Y706083D01*
X104983Y706000D01*
X105650Y706083D01*
X106317Y706500D01*
X106733Y707000D01*
X106817Y707500D01*
X106650Y708083D01*
X106067Y708500D01*
X105483Y708667D01*
X104733D01*
G01X105483D02*
X105983Y708917D01*
X106400Y709333D01*
X106567Y709833D01*
X106400Y710333D01*
X105983Y710750D01*
X105233Y711000D01*
X104483Y710917D01*
X103733Y710583D01*
G01X108417Y706000D02*
X110500Y711000D01*
X112583Y706000D01*
G01X111833Y707750D02*
X109167D01*
G01X114600Y705833D02*
X117600Y711000D01*
G01X121700Y706000D02*
Y711000D01*
X120700Y710000D01*
G01Y706000D02*
X122700D01*
G01X125467Y706750D02*
X125967Y706333D01*
X126550Y706083D01*
X127300Y706000D01*
X128050Y706167D01*
X128633Y706500D01*
X129050Y707083D01*
X129133Y707750D01*
X128967Y708417D01*
X128550Y708833D01*
X127967Y709167D01*
X127383Y709250D01*
X126800Y709167D01*
X126050Y708833D01*
X126300Y711000D01*
X128550D01*
G01X130817D02*
X132900Y706000D01*
X134983Y711000D01*
G01X73999Y765950D02*
Y727150D01*
G01X75200Y739300D02*
X83200D01*
G01X75200Y756900D02*
Y739300D01*
G01X76999Y767350D02*
Y778550D01*
G01X83200Y756900D02*
X75200D01*
G01X76999Y805750D02*
Y794550D01*
G01X81899Y1002450D02*
Y998450D01*
X89299D01*
G01X81899Y1006450D02*
Y1002450D01*
X89299D01*
G01X63198Y1015255D02*
Y1022855D01*
X74598D01*
Y1015255D01*
X63198D01*
G01X86700Y1006500D02*
Y1010500D01*
X79300D01*
G01X77300Y1015000D02*
Y1011000D01*
X84700D01*
G01X62967Y1035500D02*
Y1033000D01*
X64633D01*
G01X67733D02*
X66067D01*
Y1035500D01*
X67733D01*
G01X67067Y1034292D02*
X66067D01*
G01X69083Y1033000D02*
Y1035500D01*
X69917D01*
X70250Y1035375D01*
X70500Y1035208D01*
X70708Y1034958D01*
X70875Y1034667D01*
X70917Y1034250D01*
X70875Y1033833D01*
X70708Y1033542D01*
X70500Y1033292D01*
X70250Y1033125D01*
X69917Y1033000D01*
X69083D01*
G01X73100D02*
Y1035500D01*
X72600Y1035000D01*
G01Y1033000D02*
X73600D01*
G01X75283Y1033500D02*
X75533Y1033208D01*
X75867Y1033042D01*
X76242Y1033000D01*
X76575Y1033042D01*
X76908Y1033250D01*
X77117Y1033500D01*
X77158Y1033750D01*
X77075Y1034042D01*
X76783Y1034250D01*
X76492Y1034333D01*
X76117D01*
G01X76492D02*
X76742Y1034458D01*
X76950Y1034667D01*
X77033Y1034917D01*
X76950Y1035167D01*
X76742Y1035375D01*
X76367Y1035500D01*
X75992Y1035458D01*
X75617Y1035292D01*
G01X70767Y1098292D02*
X70517Y1098417D01*
X70225Y1098500D01*
X69892D01*
X69517Y1098375D01*
X69225Y1098167D01*
X69017Y1097917D01*
X68850Y1097500D01*
X68808Y1097125D01*
X68892Y1096750D01*
X69017Y1096500D01*
X69267Y1096250D01*
X69558Y1096083D01*
X69850Y1096000D01*
X70142D01*
X70433Y1096083D01*
X70683Y1096208D01*
X70892Y1096375D01*
G01X72158Y1098083D02*
X72408Y1098333D01*
X72700Y1098458D01*
X73033Y1098500D01*
X73450Y1098417D01*
X73742Y1098208D01*
X73825Y1097958D01*
X73783Y1097708D01*
X73617Y1097500D01*
X72783Y1097083D01*
X72408Y1096792D01*
X72158Y1096375D01*
X72075Y1096000D01*
X73825D01*
G01X76050D02*
Y1098500D01*
X75550Y1098000D01*
G01Y1096000D02*
X76550D01*
G01X78442Y1096292D02*
X78733Y1096083D01*
X79067Y1096000D01*
X79400Y1096083D01*
X79692Y1096333D01*
X79900Y1096708D01*
X79983Y1097083D01*
Y1097542D01*
X79900Y1097917D01*
X79692Y1098250D01*
X79442Y1098417D01*
X79150Y1098500D01*
X78817Y1098417D01*
X78567Y1098250D01*
X78400Y1098000D01*
X78317Y1097667D01*
X78400Y1097375D01*
X78608Y1097083D01*
X78858Y1096917D01*
X79150Y1096875D01*
X79483Y1096958D01*
X79733Y1097167D01*
X79983Y1097542D01*
G01X69267Y1112292D02*
X69017Y1112417D01*
X68725Y1112500D01*
X68392D01*
X68017Y1112375D01*
X67725Y1112167D01*
X67517Y1111917D01*
X67350Y1111500D01*
X67308Y1111125D01*
X67392Y1110750D01*
X67517Y1110500D01*
X67767Y1110250D01*
X68058Y1110083D01*
X68350Y1110000D01*
X68642D01*
X68933Y1110083D01*
X69183Y1110208D01*
X69392Y1110375D01*
G01X70658Y1112083D02*
X70908Y1112333D01*
X71200Y1112458D01*
X71533Y1112500D01*
X71950Y1112417D01*
X72242Y1112208D01*
X72325Y1111958D01*
X72283Y1111708D01*
X72117Y1111500D01*
X71283Y1111083D01*
X70908Y1110792D01*
X70658Y1110375D01*
X70575Y1110000D01*
X72325D01*
G01X74550D02*
Y1112500D01*
X74050Y1112000D01*
G01Y1110000D02*
X75050D01*
G01X76733Y1110500D02*
X76983Y1110208D01*
X77317Y1110042D01*
X77692Y1110000D01*
X78025Y1110042D01*
X78358Y1110250D01*
X78567Y1110500D01*
X78608Y1110750D01*
X78525Y1111042D01*
X78233Y1111250D01*
X77942Y1111333D01*
X77567D01*
G01X77942D02*
X78192Y1111458D01*
X78400Y1111667D01*
X78483Y1111917D01*
X78400Y1112167D01*
X78192Y1112375D01*
X77817Y1112500D01*
X77442Y1112458D01*
X77067Y1112292D01*
G01X68517Y1115000D02*
Y1117500D01*
X69558D01*
X69892Y1117375D01*
X70100Y1117208D01*
X70183Y1116875D01*
X70100Y1116542D01*
X69850Y1116333D01*
X69558Y1116208D01*
X68517D01*
G01X69558D02*
X70183Y1115000D01*
G01X71658Y1117083D02*
X71908Y1117333D01*
X72200Y1117458D01*
X72533Y1117500D01*
X72950Y1117417D01*
X73242Y1117208D01*
X73325Y1116958D01*
X73283Y1116708D01*
X73117Y1116500D01*
X72283Y1116083D01*
X71908Y1115792D01*
X71658Y1115375D01*
X71575Y1115000D01*
X73325D01*
G01X75550Y1117500D02*
X75217Y1117417D01*
X74967Y1117208D01*
X74800Y1116958D01*
X74675Y1116625D01*
X74633Y1116250D01*
X74675Y1115875D01*
X74800Y1115542D01*
X74967Y1115292D01*
X75217Y1115083D01*
X75550Y1115000D01*
X75883Y1115083D01*
X76133Y1115292D01*
X76300Y1115542D01*
X76425Y1115875D01*
X76467Y1116250D01*
X76425Y1116625D01*
X76300Y1116958D01*
X76133Y1117208D01*
X75883Y1117417D01*
X75550Y1117500D01*
G01X79150Y1115000D02*
Y1117500D01*
X77608Y1115708D01*
X79692D01*
G01X70274Y1134677D02*
Y1132885D01*
X70441Y1132510D01*
X70774Y1132260D01*
X71191Y1132177D01*
X71608Y1132260D01*
X71941Y1132510D01*
X72108Y1132885D01*
Y1134677D01*
G01X73499Y1134260D02*
X73749Y1134510D01*
X74041Y1134635D01*
X74374Y1134677D01*
X74791Y1134594D01*
X75083Y1134385D01*
X75166Y1134135D01*
X75124Y1133885D01*
X74958Y1133677D01*
X74124Y1133260D01*
X73749Y1132969D01*
X73499Y1132552D01*
X73416Y1132177D01*
X75166D01*
G01X76474Y1132677D02*
X76724Y1132385D01*
X77058Y1132219D01*
X77433Y1132177D01*
X77766Y1132219D01*
X78099Y1132427D01*
X78308Y1132677D01*
X78349Y1132927D01*
X78266Y1133219D01*
X77974Y1133427D01*
X77683Y1133510D01*
X77308D01*
G01X77683D02*
X77933Y1133635D01*
X78141Y1133844D01*
X78224Y1134094D01*
X78141Y1134344D01*
X77933Y1134552D01*
X77558Y1134677D01*
X77183Y1134635D01*
X76808Y1134469D01*
G01X69000Y1151608D02*
X66500D01*
Y1153192D01*
G01X67708Y1152608D02*
Y1151608D01*
G01X69000Y1155500D02*
X66500D01*
X67000Y1155000D01*
G01X69000D02*
Y1156000D01*
G01X67958Y1157808D02*
X67667Y1158100D01*
X67500Y1158350D01*
X67417Y1158683D01*
X67500Y1158975D01*
X67667Y1159183D01*
X67917Y1159350D01*
X68208Y1159392D01*
X68458Y1159350D01*
X68708Y1159183D01*
X68917Y1158933D01*
X69000Y1158642D01*
X68917Y1158308D01*
X68667Y1158017D01*
X68292Y1157850D01*
X67875Y1157808D01*
X67333Y1157892D01*
X67042Y1158017D01*
X66750Y1158225D01*
X66542Y1158517D01*
X66500Y1158808D01*
X66583Y1159100D01*
X66792Y1159308D01*
G01X97999Y1141150D02*
X74999D01*
G01D02*
Y1179950D01*
G01X73000Y1151017D02*
X70500D01*
Y1152058D01*
X70625Y1152392D01*
X70792Y1152600D01*
X71125Y1152683D01*
X71458Y1152600D01*
X71667Y1152350D01*
X71792Y1152058D01*
Y1151017D01*
G01Y1152058D02*
X73000Y1152683D01*
G01X72625Y1154033D02*
X72833Y1154283D01*
X72958Y1154575D01*
X73000Y1154950D01*
X72917Y1155325D01*
X72750Y1155617D01*
X72458Y1155825D01*
X72125Y1155867D01*
X71792Y1155783D01*
X71583Y1155575D01*
X71417Y1155283D01*
X71375Y1154992D01*
X71417Y1154700D01*
X71583Y1154325D01*
X70500Y1154450D01*
Y1155575D01*
G01X70917Y1157258D02*
X70667Y1157508D01*
X70542Y1157800D01*
X70500Y1158133D01*
X70583Y1158550D01*
X70792Y1158842D01*
X71042Y1158925D01*
X71292Y1158883D01*
X71500Y1158717D01*
X71917Y1157883D01*
X72208Y1157508D01*
X72625Y1157258D01*
X73000Y1157175D01*
Y1158925D01*
G01Y1161067D02*
X72458Y1161150D01*
X72000Y1161275D01*
X71583Y1161442D01*
X71125Y1161650D01*
X70500Y1161983D01*
Y1160317D01*
G01X74999Y1179950D02*
X97999D01*
G01X83417Y1212065D02*
X80917D01*
Y1213106D01*
X81042Y1213440D01*
X81209Y1213648D01*
X81542Y1213731D01*
X81875Y1213648D01*
X82084Y1213398D01*
X82209Y1213106D01*
Y1212065D01*
G01Y1213106D02*
X83417Y1213731D01*
G01X81334Y1215206D02*
X81084Y1215456D01*
X80959Y1215748D01*
X80917Y1216081D01*
X81000Y1216498D01*
X81209Y1216790D01*
X81459Y1216873D01*
X81709Y1216831D01*
X81917Y1216665D01*
X82334Y1215831D01*
X82625Y1215456D01*
X83042Y1215206D01*
X83417Y1215123D01*
Y1216873D01*
G01X83042Y1218181D02*
X83250Y1218431D01*
X83375Y1218723D01*
X83417Y1219098D01*
X83334Y1219473D01*
X83167Y1219765D01*
X82875Y1219973D01*
X82542Y1220015D01*
X82209Y1219931D01*
X82000Y1219723D01*
X81834Y1219431D01*
X81792Y1219140D01*
X81834Y1218848D01*
X82000Y1218473D01*
X80917Y1218598D01*
Y1219723D01*
G01X83125Y1221490D02*
X83334Y1221781D01*
X83417Y1222115D01*
X83334Y1222448D01*
X83084Y1222740D01*
X82709Y1222948D01*
X82334Y1223031D01*
X81875D01*
X81500Y1222948D01*
X81167Y1222740D01*
X81000Y1222490D01*
X80917Y1222198D01*
X81000Y1221865D01*
X81167Y1221615D01*
X81417Y1221448D01*
X81750Y1221365D01*
X82042Y1221448D01*
X82334Y1221656D01*
X82500Y1221906D01*
X82542Y1222198D01*
X82459Y1222531D01*
X82250Y1222781D01*
X81875Y1223031D01*
G01X63198Y1420767D02*
Y1428367D01*
X74598D01*
Y1420767D01*
X63198D01*
G01X74265Y1534550D02*
X67265D01*
G01X74265Y1537617D02*
Y1531483D01*
G01X67265Y1523283D02*
Y1528617D01*
X74265D01*
Y1523283D01*
G01X70882Y1525417D02*
Y1528617D01*
G01X67265Y1520817D02*
X74265D01*
X68432Y1517350D01*
X74265Y1513883D01*
X67265D01*
G01Y1511417D02*
X74265D01*
Y1508217D01*
X73915Y1507150D01*
X73098Y1506350D01*
X72165Y1506083D01*
X71232Y1506350D01*
X70532Y1507017D01*
X70181Y1508217D01*
Y1511417D01*
G01X64932Y1504150D02*
Y1496150D01*
G01X68198Y1494350D02*
X67615Y1493283D01*
X67265Y1492083D01*
Y1491017D01*
X67615Y1489950D01*
X68198Y1489150D01*
X69015Y1488750D01*
X69832Y1489017D01*
X70532Y1489683D01*
X70998Y1490883D01*
X71232Y1492483D01*
X71698Y1493417D01*
X72515Y1493817D01*
X73332Y1493550D01*
X73915Y1492883D01*
X74265Y1491950D01*
Y1491017D01*
X74032Y1490083D01*
X73448Y1489283D01*
G01X67265Y1480283D02*
Y1485617D01*
X74265D01*
Y1480283D01*
G01X70882Y1482417D02*
Y1485617D01*
G01X67265Y1477417D02*
X74265D01*
X67265Y1471283D01*
X74265D01*
G01X68198Y1468550D02*
X67615Y1467483D01*
X67265Y1466283D01*
Y1465217D01*
X67615Y1464150D01*
X68198Y1463350D01*
X69015Y1462950D01*
X69832Y1463217D01*
X70532Y1463883D01*
X70998Y1465083D01*
X71232Y1466683D01*
X71698Y1467617D01*
X72515Y1468017D01*
X73332Y1467750D01*
X73915Y1467083D01*
X74265Y1466150D01*
Y1465217D01*
X74032Y1464283D01*
X73448Y1463483D01*
G01X67265Y1457150D02*
X67382Y1458217D01*
X67848Y1459150D01*
X68548Y1459950D01*
X69365Y1460483D01*
X70298Y1460750D01*
X71232D01*
X72165Y1460483D01*
X72982Y1459950D01*
X73682Y1459150D01*
X74148Y1458217D01*
X74265Y1457150D01*
X74148Y1456083D01*
X73682Y1455150D01*
X72982Y1454350D01*
X72165Y1453817D01*
X71232Y1453550D01*
X70298D01*
X69365Y1453817D01*
X68548Y1454350D01*
X67848Y1455150D01*
X67382Y1456083D01*
X67265Y1457150D01*
G01Y1451217D02*
X74265D01*
Y1447883D01*
X73915Y1446817D01*
X73448Y1446150D01*
X72515Y1445883D01*
X71582Y1446150D01*
X70998Y1446950D01*
X70648Y1447883D01*
Y1451217D01*
G01Y1447883D02*
X67265Y1445883D01*
G01Y1439950D02*
X74265D01*
X72865Y1441550D01*
G01X67265D02*
Y1438350D01*
G01X62467Y1436063D02*
Y1433563D01*
X64133D01*
G01X67233D02*
X65567D01*
Y1436063D01*
X67233D01*
G01X66567Y1434855D02*
X65567D01*
G01X68583Y1433563D02*
Y1436063D01*
X69417D01*
X69750Y1435938D01*
X70000Y1435771D01*
X70208Y1435521D01*
X70375Y1435230D01*
X70417Y1434813D01*
X70375Y1434396D01*
X70208Y1434105D01*
X70000Y1433855D01*
X69750Y1433688D01*
X69417Y1433563D01*
X68583D01*
G01X72600D02*
Y1436063D01*
X72100Y1435563D01*
G01Y1433563D02*
X73100D01*
G01X74908Y1435646D02*
X75158Y1435896D01*
X75450Y1436021D01*
X75783Y1436063D01*
X76200Y1435980D01*
X76492Y1435771D01*
X76575Y1435521D01*
X76533Y1435271D01*
X76367Y1435063D01*
X75533Y1434646D01*
X75158Y1434355D01*
X74908Y1433938D01*
X74825Y1433563D01*
X76575D01*
G01X85000Y1553700D02*
X81000D01*
Y1546300D01*
G01Y1533517D02*
X78500D01*
Y1534558D01*
X78625Y1534892D01*
X78792Y1535100D01*
X79125Y1535183D01*
X79458Y1535100D01*
X79667Y1534850D01*
X79792Y1534558D01*
Y1533517D01*
G01Y1534558D02*
X81000Y1535183D01*
G01X80625Y1536533D02*
X80833Y1536783D01*
X80958Y1537075D01*
X81000Y1537450D01*
X80917Y1537825D01*
X80750Y1538117D01*
X80458Y1538325D01*
X80125Y1538367D01*
X79792Y1538283D01*
X79583Y1538075D01*
X79417Y1537783D01*
X79375Y1537492D01*
X79417Y1537200D01*
X79583Y1536825D01*
X78500Y1536950D01*
Y1538075D01*
G01Y1540550D02*
X78583Y1540217D01*
X78792Y1539967D01*
X79042Y1539800D01*
X79375Y1539675D01*
X79750Y1539633D01*
X80125Y1539675D01*
X80458Y1539800D01*
X80708Y1539967D01*
X80917Y1540217D01*
X81000Y1540550D01*
X80917Y1540883D01*
X80708Y1541133D01*
X80458Y1541300D01*
X80125Y1541425D01*
X79750Y1541467D01*
X79375Y1541425D01*
X79042Y1541300D01*
X78792Y1541133D01*
X78583Y1540883D01*
X78500Y1540550D01*
G01X81000Y1543650D02*
X80958Y1543942D01*
X80833Y1544275D01*
X80625Y1544483D01*
X80333Y1544567D01*
X80042Y1544483D01*
X79792Y1544233D01*
X79667Y1543858D01*
Y1543442D01*
X79583Y1543192D01*
X79375Y1542983D01*
X79083Y1542900D01*
X78792Y1543025D01*
X78583Y1543317D01*
X78500Y1543650D01*
X78583Y1543983D01*
X78792Y1544275D01*
X79083Y1544400D01*
X79375Y1544317D01*
X79583Y1544108D01*
X79667Y1543858D01*
Y1543442D01*
X79792Y1543067D01*
X80042Y1542817D01*
X80333Y1542733D01*
X80625Y1542817D01*
X80833Y1543025D01*
X80958Y1543358D01*
X81000Y1543650D01*
G01Y1553700D02*
X77000D01*
Y1546300D01*
G01X75500Y1573017D02*
X73000D01*
Y1574058D01*
X73125Y1574392D01*
X73292Y1574600D01*
X73625Y1574683D01*
X73958Y1574600D01*
X74167Y1574350D01*
X74292Y1574058D01*
Y1573017D01*
G01Y1574058D02*
X75500Y1574683D01*
G01Y1577450D02*
X73000D01*
X74792Y1575908D01*
Y1577992D01*
G01X75500Y1580050D02*
X75458Y1580342D01*
X75333Y1580675D01*
X75125Y1580883D01*
X74833Y1580967D01*
X74542Y1580883D01*
X74292Y1580633D01*
X74167Y1580258D01*
Y1579842D01*
X74083Y1579592D01*
X73875Y1579383D01*
X73583Y1579300D01*
X73292Y1579425D01*
X73083Y1579717D01*
X73000Y1580050D01*
X73083Y1580383D01*
X73292Y1580675D01*
X73583Y1580800D01*
X73875Y1580717D01*
X74083Y1580508D01*
X74167Y1580258D01*
Y1579842D01*
X74292Y1579467D01*
X74542Y1579217D01*
X74833Y1579133D01*
X75125Y1579217D01*
X75333Y1579425D01*
X75458Y1579758D01*
X75500Y1580050D01*
G01Y1583150D02*
X73000D01*
X73500Y1582650D01*
G01X75500D02*
Y1583650D01*
G01X77000Y1570600D02*
X73000D01*
Y1563200D01*
G01X79500Y1573017D02*
X77000D01*
Y1574058D01*
X77125Y1574392D01*
X77292Y1574600D01*
X77625Y1574683D01*
X77958Y1574600D01*
X78167Y1574350D01*
X78292Y1574058D01*
Y1573017D01*
G01Y1574058D02*
X79500Y1574683D01*
G01X79125Y1576033D02*
X79333Y1576283D01*
X79458Y1576575D01*
X79500Y1576950D01*
X79417Y1577325D01*
X79250Y1577617D01*
X78958Y1577825D01*
X78625Y1577867D01*
X78292Y1577783D01*
X78083Y1577575D01*
X77917Y1577283D01*
X77875Y1576992D01*
X77917Y1576700D01*
X78083Y1576325D01*
X77000Y1576450D01*
Y1577575D01*
G01Y1580050D02*
X77083Y1579717D01*
X77292Y1579467D01*
X77542Y1579300D01*
X77875Y1579175D01*
X78250Y1579133D01*
X78625Y1579175D01*
X78958Y1579300D01*
X79208Y1579467D01*
X79417Y1579717D01*
X79500Y1580050D01*
X79417Y1580383D01*
X79208Y1580633D01*
X78958Y1580800D01*
X78625Y1580925D01*
X78250Y1580967D01*
X77875Y1580925D01*
X77542Y1580800D01*
X77292Y1580633D01*
X77083Y1580383D01*
X77000Y1580050D01*
G01X79500Y1583067D02*
X78958Y1583150D01*
X78500Y1583275D01*
X78083Y1583442D01*
X77625Y1583650D01*
X77000Y1583983D01*
Y1582317D01*
G01X81000Y1570600D02*
X77000D01*
Y1563200D01*
G01X63198Y1826279D02*
Y1833879D01*
X74598D01*
Y1826279D01*
X63198D01*
G01X79199Y1835550D02*
Y1839550D01*
X71799D01*
G01X87949Y1826613D02*
Y1830613D01*
X80549D01*
G01X79449Y1841113D02*
Y1845113D01*
X72049D01*
G01X87949Y1830613D02*
Y1834613D01*
X80549D01*
G01X79199Y1847050D02*
Y1851050D01*
X71799D01*
G01X61899Y1853900D02*
Y1849900D01*
X69299D01*
G01X71199Y1836100D02*
Y1849100D01*
G01X68816Y1856350D02*
Y1858850D01*
X69857D01*
X70191Y1858725D01*
X70399Y1858558D01*
X70482Y1858225D01*
X70399Y1857892D01*
X70149Y1857683D01*
X69857Y1857558D01*
X68816D01*
G01X69857D02*
X70482Y1856350D01*
G01X71832Y1856725D02*
X72082Y1856517D01*
X72374Y1856392D01*
X72749Y1856350D01*
X73124Y1856433D01*
X73416Y1856600D01*
X73624Y1856892D01*
X73666Y1857225D01*
X73582Y1857558D01*
X73374Y1857767D01*
X73082Y1857933D01*
X72791Y1857975D01*
X72499Y1857933D01*
X72124Y1857767D01*
X72249Y1858850D01*
X73374D01*
G01X75849D02*
X75516Y1858767D01*
X75266Y1858558D01*
X75099Y1858308D01*
X74974Y1857975D01*
X74932Y1857600D01*
X74974Y1857225D01*
X75099Y1856892D01*
X75266Y1856642D01*
X75516Y1856433D01*
X75849Y1856350D01*
X76182Y1856433D01*
X76432Y1856642D01*
X76599Y1856892D01*
X76724Y1857225D01*
X76766Y1857600D01*
X76724Y1857975D01*
X76599Y1858308D01*
X76432Y1858558D01*
X76182Y1858767D01*
X75849Y1858850D01*
G01X78949D02*
X78616Y1858767D01*
X78366Y1858558D01*
X78199Y1858308D01*
X78074Y1857975D01*
X78032Y1857600D01*
X78074Y1857225D01*
X78199Y1856892D01*
X78366Y1856642D01*
X78616Y1856433D01*
X78949Y1856350D01*
X79282Y1856433D01*
X79532Y1856642D01*
X79699Y1856892D01*
X79824Y1857225D01*
X79866Y1857600D01*
X79824Y1857975D01*
X79699Y1858308D01*
X79532Y1858558D01*
X79282Y1858767D01*
X78949Y1858850D01*
G01X68999Y1868250D02*
Y1873750D01*
G01X76999Y1868250D02*
X68999D01*
G01X76999Y1873750D02*
Y1868250D01*
G01X67999Y1873250D02*
Y1867750D01*
G01X77500Y1888017D02*
X75000D01*
Y1889017D01*
X75125Y1889350D01*
X75417Y1889600D01*
X75750Y1889683D01*
X76083Y1889600D01*
X76333Y1889392D01*
X76458Y1889017D01*
Y1888017D01*
G01X75208Y1892867D02*
X75083Y1892617D01*
X75000Y1892325D01*
Y1891992D01*
X75125Y1891617D01*
X75333Y1891325D01*
X75583Y1891117D01*
X76000Y1890950D01*
X76375Y1890908D01*
X76750Y1890992D01*
X77000Y1891117D01*
X77250Y1891367D01*
X77417Y1891658D01*
X77500Y1891950D01*
Y1892242D01*
X77417Y1892533D01*
X77292Y1892783D01*
X77125Y1892992D01*
G01X77000Y1894133D02*
X77292Y1894383D01*
X77458Y1894717D01*
X77500Y1895092D01*
X77458Y1895425D01*
X77250Y1895758D01*
X77000Y1895967D01*
X76750Y1896008D01*
X76458Y1895925D01*
X76250Y1895633D01*
X76167Y1895342D01*
Y1894967D01*
G01Y1895342D02*
X76042Y1895592D01*
X75833Y1895800D01*
X75583Y1895883D01*
X75333Y1895800D01*
X75125Y1895592D01*
X75000Y1895217D01*
X75042Y1894842D01*
X75208Y1894467D01*
G01X77500Y1898150D02*
X77458Y1898442D01*
X77333Y1898775D01*
X77125Y1898983D01*
X76833Y1899067D01*
X76542Y1898983D01*
X76292Y1898733D01*
X76167Y1898358D01*
Y1897942D01*
X76083Y1897692D01*
X75875Y1897483D01*
X75583Y1897400D01*
X75292Y1897525D01*
X75083Y1897817D01*
X75000Y1898150D01*
X75083Y1898483D01*
X75292Y1898775D01*
X75583Y1898900D01*
X75875Y1898817D01*
X76083Y1898608D01*
X76167Y1898358D01*
Y1897942D01*
X76292Y1897567D01*
X76542Y1897317D01*
X76833Y1897233D01*
X77125Y1897317D01*
X77333Y1897525D01*
X77458Y1897858D01*
X77500Y1898150D01*
G01X76999Y1885850D02*
Y1880350D01*
G01X68999Y1885850D02*
X76999D01*
G01X68999Y1880350D02*
Y1885850D01*
G01X67999Y1885350D02*
Y1879850D01*
G01X118599Y1908850D02*
Y1950250D01*
X68399D01*
Y1908850D01*
X118599D01*
G01X84500Y1978017D02*
X82000D01*
Y1979017D01*
X82125Y1979350D01*
X82417Y1979600D01*
X82750Y1979683D01*
X83083Y1979600D01*
X83333Y1979392D01*
X83458Y1979017D01*
Y1978017D01*
G01X82208Y1982867D02*
X82083Y1982617D01*
X82000Y1982325D01*
Y1981992D01*
X82125Y1981617D01*
X82333Y1981325D01*
X82583Y1981117D01*
X83000Y1980950D01*
X83375Y1980908D01*
X83750Y1980992D01*
X84000Y1981117D01*
X84250Y1981367D01*
X84417Y1981658D01*
X84500Y1981950D01*
Y1982242D01*
X84417Y1982533D01*
X84292Y1982783D01*
X84125Y1982992D01*
G01X82417Y1984258D02*
X82167Y1984508D01*
X82042Y1984800D01*
X82000Y1985133D01*
X82083Y1985550D01*
X82292Y1985842D01*
X82542Y1985925D01*
X82792Y1985883D01*
X83000Y1985717D01*
X83417Y1984883D01*
X83708Y1984508D01*
X84125Y1984258D01*
X84500Y1984175D01*
Y1985925D01*
G01X84208Y1987442D02*
X84417Y1987733D01*
X84500Y1988067D01*
X84417Y1988400D01*
X84167Y1988692D01*
X83792Y1988900D01*
X83417Y1988983D01*
X82958D01*
X82583Y1988900D01*
X82250Y1988692D01*
X82083Y1988442D01*
X82000Y1988150D01*
X82083Y1987817D01*
X82250Y1987567D01*
X82500Y1987400D01*
X82833Y1987317D01*
X83125Y1987400D01*
X83417Y1987608D01*
X83583Y1987858D01*
X83625Y1988150D01*
X83542Y1988483D01*
X83333Y1988733D01*
X82958Y1988983D01*
G01X75500Y1978017D02*
X73000D01*
Y1979017D01*
X73125Y1979350D01*
X73417Y1979600D01*
X73750Y1979683D01*
X74083Y1979600D01*
X74333Y1979392D01*
X74458Y1979017D01*
Y1978017D01*
G01X73208Y1982867D02*
X73083Y1982617D01*
X73000Y1982325D01*
Y1981992D01*
X73125Y1981617D01*
X73333Y1981325D01*
X73583Y1981117D01*
X74000Y1980950D01*
X74375Y1980908D01*
X74750Y1980992D01*
X75000Y1981117D01*
X75250Y1981367D01*
X75417Y1981658D01*
X75500Y1981950D01*
Y1982242D01*
X75417Y1982533D01*
X75292Y1982783D01*
X75125Y1982992D01*
G01X75000Y1984133D02*
X75292Y1984383D01*
X75458Y1984717D01*
X75500Y1985092D01*
X75458Y1985425D01*
X75250Y1985758D01*
X75000Y1985967D01*
X74750Y1986008D01*
X74458Y1985925D01*
X74250Y1985633D01*
X74167Y1985342D01*
Y1984967D01*
G01Y1985342D02*
X74042Y1985592D01*
X73833Y1985800D01*
X73583Y1985883D01*
X73333Y1985800D01*
X73125Y1985592D01*
X73000Y1985217D01*
X73042Y1984842D01*
X73208Y1984467D01*
G01X75500Y1988150D02*
X73000D01*
X73500Y1987650D01*
G01X75500D02*
Y1988650D01*
G01X67500Y1978017D02*
X65000D01*
Y1979017D01*
X65125Y1979350D01*
X65417Y1979600D01*
X65750Y1979683D01*
X66083Y1979600D01*
X66333Y1979392D01*
X66458Y1979017D01*
Y1978017D01*
G01X65208Y1982867D02*
X65083Y1982617D01*
X65000Y1982325D01*
Y1981992D01*
X65125Y1981617D01*
X65333Y1981325D01*
X65583Y1981117D01*
X66000Y1980950D01*
X66375Y1980908D01*
X66750Y1980992D01*
X67000Y1981117D01*
X67250Y1981367D01*
X67417Y1981658D01*
X67500Y1981950D01*
Y1982242D01*
X67417Y1982533D01*
X67292Y1982783D01*
X67125Y1982992D01*
G01X67000Y1984133D02*
X67292Y1984383D01*
X67458Y1984717D01*
X67500Y1985092D01*
X67458Y1985425D01*
X67250Y1985758D01*
X67000Y1985967D01*
X66750Y1986008D01*
X66458Y1985925D01*
X66250Y1985633D01*
X66167Y1985342D01*
Y1984967D01*
G01Y1985342D02*
X66042Y1985592D01*
X65833Y1985800D01*
X65583Y1985883D01*
X65333Y1985800D01*
X65125Y1985592D01*
X65000Y1985217D01*
X65042Y1984842D01*
X65208Y1984467D01*
G01X67125Y1987233D02*
X67333Y1987483D01*
X67458Y1987775D01*
X67500Y1988150D01*
X67417Y1988525D01*
X67250Y1988817D01*
X66958Y1989025D01*
X66625Y1989067D01*
X66292Y1988983D01*
X66083Y1988775D01*
X65917Y1988483D01*
X65875Y1988192D01*
X65917Y1987900D01*
X66083Y1987525D01*
X65000Y1987650D01*
Y1988775D01*
G01X100499Y35400D02*
X102999D01*
G01X100499Y34442D02*
Y36358D01*
G01X102999Y37667D02*
X100499D01*
Y38667D01*
X100624Y39000D01*
X100916Y39250D01*
X101249Y39333D01*
X101582Y39250D01*
X101832Y39042D01*
X101957Y38667D01*
Y37667D01*
G01X102499Y40683D02*
X102791Y40933D01*
X102957Y41267D01*
X102999Y41642D01*
X102957Y41975D01*
X102749Y42308D01*
X102499Y42517D01*
X102249Y42558D01*
X101957Y42475D01*
X101749Y42183D01*
X101666Y41892D01*
Y41517D01*
G01Y41892D02*
X101541Y42142D01*
X101332Y42350D01*
X101082Y42433D01*
X100832Y42350D01*
X100624Y42142D01*
X100499Y41767D01*
X100541Y41392D01*
X100707Y41017D01*
G01X102707Y43992D02*
X102916Y44283D01*
X102999Y44617D01*
X102916Y44950D01*
X102666Y45242D01*
X102291Y45450D01*
X101916Y45533D01*
X101457D01*
X101082Y45450D01*
X100749Y45242D01*
X100582Y44992D01*
X100499Y44700D01*
X100582Y44367D01*
X100749Y44117D01*
X100999Y43950D01*
X101332Y43867D01*
X101624Y43950D01*
X101916Y44158D01*
X102082Y44408D01*
X102124Y44700D01*
X102041Y45033D01*
X101832Y45283D01*
X101457Y45533D01*
G01X97165Y110250D02*
X107165D01*
G01Y103250D02*
X97165D01*
G01X102165D02*
Y110250D01*
G01X97165Y99817D02*
X107165D01*
Y96483D01*
X106665Y95150D01*
X105998Y94150D01*
X104998Y93317D01*
X103831Y92650D01*
X102165Y92483D01*
X100498Y92650D01*
X99332Y93317D01*
X98331Y94150D01*
X97665Y95150D01*
X97165Y96483D01*
Y99817D01*
G01Y89217D02*
X107165D01*
Y85883D01*
X106665Y84550D01*
X105998Y83550D01*
X104998Y82717D01*
X103831Y82050D01*
X102165Y81883D01*
X100498Y82050D01*
X99332Y82717D01*
X98331Y83550D01*
X97665Y84550D01*
X97165Y85883D01*
Y89217D01*
G01Y74950D02*
X107165D01*
X105165Y76950D01*
G01X97165D02*
Y72950D01*
G01Y62350D02*
X107165D01*
X99998Y68517D01*
Y60183D01*
G01X102266Y137842D02*
X102016Y137967D01*
X101724Y138050D01*
X101391D01*
X101016Y137925D01*
X100724Y137717D01*
X100516Y137467D01*
X100349Y137050D01*
X100307Y136675D01*
X100391Y136300D01*
X100516Y136050D01*
X100766Y135800D01*
X101057Y135633D01*
X101349Y135550D01*
X101641D01*
X101932Y135633D01*
X102182Y135758D01*
X102391Y135925D01*
G01X103532Y136050D02*
X103782Y135758D01*
X104116Y135592D01*
X104491Y135550D01*
X104824Y135592D01*
X105157Y135800D01*
X105366Y136050D01*
X105407Y136300D01*
X105324Y136592D01*
X105032Y136800D01*
X104741Y136883D01*
X104366D01*
G01X104741D02*
X104991Y137008D01*
X105199Y137217D01*
X105282Y137467D01*
X105199Y137717D01*
X104991Y137925D01*
X104616Y138050D01*
X104241Y138008D01*
X103866Y137842D01*
G01X106757Y137633D02*
X107007Y137883D01*
X107299Y138008D01*
X107632Y138050D01*
X108049Y137967D01*
X108341Y137758D01*
X108424Y137508D01*
X108382Y137258D01*
X108216Y137050D01*
X107382Y136633D01*
X107007Y136342D01*
X106757Y135925D01*
X106674Y135550D01*
X108424D01*
G01X110649D02*
X110941Y135592D01*
X111274Y135717D01*
X111482Y135925D01*
X111566Y136217D01*
X111482Y136508D01*
X111232Y136758D01*
X110857Y136883D01*
X110441D01*
X110191Y136967D01*
X109982Y137175D01*
X109899Y137467D01*
X110024Y137758D01*
X110316Y137967D01*
X110649Y138050D01*
X110982Y137967D01*
X111274Y137758D01*
X111399Y137467D01*
X111316Y137175D01*
X111107Y136967D01*
X110857Y136883D01*
X110441D01*
X110066Y136758D01*
X109816Y136508D01*
X109732Y136217D01*
X109816Y135925D01*
X110024Y135717D01*
X110357Y135592D01*
X110649Y135550D01*
G01X102266Y134342D02*
X102016Y134467D01*
X101724Y134550D01*
X101391D01*
X101016Y134425D01*
X100724Y134217D01*
X100516Y133967D01*
X100349Y133550D01*
X100307Y133175D01*
X100391Y132800D01*
X100516Y132550D01*
X100766Y132300D01*
X101057Y132133D01*
X101349Y132050D01*
X101641D01*
X101932Y132133D01*
X102182Y132258D01*
X102391Y132425D01*
G01X103532Y132550D02*
X103782Y132258D01*
X104116Y132092D01*
X104491Y132050D01*
X104824Y132092D01*
X105157Y132300D01*
X105366Y132550D01*
X105407Y132800D01*
X105324Y133092D01*
X105032Y133300D01*
X104741Y133383D01*
X104366D01*
G01X104741D02*
X104991Y133508D01*
X105199Y133717D01*
X105282Y133967D01*
X105199Y134217D01*
X104991Y134425D01*
X104616Y134550D01*
X104241Y134508D01*
X103866Y134342D01*
G01X106757Y134133D02*
X107007Y134383D01*
X107299Y134508D01*
X107632Y134550D01*
X108049Y134467D01*
X108341Y134258D01*
X108424Y134008D01*
X108382Y133758D01*
X108216Y133550D01*
X107382Y133133D01*
X107007Y132842D01*
X106757Y132425D01*
X106674Y132050D01*
X108424D01*
G01X109941Y132342D02*
X110232Y132133D01*
X110566Y132050D01*
X110899Y132133D01*
X111191Y132383D01*
X111399Y132758D01*
X111482Y133133D01*
Y133592D01*
X111399Y133967D01*
X111191Y134300D01*
X110941Y134467D01*
X110649Y134550D01*
X110316Y134467D01*
X110066Y134300D01*
X109899Y134050D01*
X109816Y133717D01*
X109899Y133425D01*
X110107Y133133D01*
X110357Y132967D01*
X110649Y132925D01*
X110982Y133008D01*
X111232Y133217D01*
X111482Y133592D01*
G01X101766Y153842D02*
X101516Y153967D01*
X101224Y154050D01*
X100891D01*
X100516Y153925D01*
X100224Y153717D01*
X100016Y153467D01*
X99849Y153050D01*
X99807Y152675D01*
X99891Y152300D01*
X100016Y152050D01*
X100266Y151800D01*
X100557Y151633D01*
X100849Y151550D01*
X101141D01*
X101432Y151633D01*
X101682Y151758D01*
X101891Y151925D01*
G01X103032Y152050D02*
X103282Y151758D01*
X103616Y151592D01*
X103991Y151550D01*
X104324Y151592D01*
X104657Y151800D01*
X104866Y152050D01*
X104907Y152300D01*
X104824Y152592D01*
X104532Y152800D01*
X104241Y152883D01*
X103866D01*
G01X104241D02*
X104491Y153008D01*
X104699Y153217D01*
X104782Y153467D01*
X104699Y153717D01*
X104491Y153925D01*
X104116Y154050D01*
X103741Y154008D01*
X103366Y153842D01*
G01X106257Y153633D02*
X106507Y153883D01*
X106799Y154008D01*
X107132Y154050D01*
X107549Y153967D01*
X107841Y153758D01*
X107924Y153508D01*
X107882Y153258D01*
X107716Y153050D01*
X106882Y152633D01*
X106507Y152342D01*
X106257Y151925D01*
X106174Y151550D01*
X107924D01*
G01X109357Y152592D02*
X109649Y152883D01*
X109899Y153050D01*
X110232Y153133D01*
X110524Y153050D01*
X110732Y152883D01*
X110899Y152633D01*
X110941Y152342D01*
X110899Y152092D01*
X110732Y151842D01*
X110482Y151633D01*
X110191Y151550D01*
X109857Y151633D01*
X109566Y151883D01*
X109399Y152258D01*
X109357Y152675D01*
X109441Y153217D01*
X109566Y153508D01*
X109774Y153800D01*
X110066Y154008D01*
X110357Y154050D01*
X110649Y153967D01*
X110857Y153758D01*
G01X101766Y150342D02*
X101516Y150467D01*
X101224Y150550D01*
X100891D01*
X100516Y150425D01*
X100224Y150217D01*
X100016Y149967D01*
X99849Y149550D01*
X99807Y149175D01*
X99891Y148800D01*
X100016Y148550D01*
X100266Y148300D01*
X100557Y148133D01*
X100849Y148050D01*
X101141D01*
X101432Y148133D01*
X101682Y148258D01*
X101891Y148425D01*
G01X103032Y148550D02*
X103282Y148258D01*
X103616Y148092D01*
X103991Y148050D01*
X104324Y148092D01*
X104657Y148300D01*
X104866Y148550D01*
X104907Y148800D01*
X104824Y149092D01*
X104532Y149300D01*
X104241Y149383D01*
X103866D01*
G01X104241D02*
X104491Y149508D01*
X104699Y149717D01*
X104782Y149967D01*
X104699Y150217D01*
X104491Y150425D01*
X104116Y150550D01*
X103741Y150508D01*
X103366Y150342D01*
G01X106257Y150133D02*
X106507Y150383D01*
X106799Y150508D01*
X107132Y150550D01*
X107549Y150467D01*
X107841Y150258D01*
X107924Y150008D01*
X107882Y149758D01*
X107716Y149550D01*
X106882Y149133D01*
X106507Y148842D01*
X106257Y148425D01*
X106174Y148050D01*
X107924D01*
G01X110066D02*
X110149Y148592D01*
X110274Y149050D01*
X110441Y149467D01*
X110649Y149925D01*
X110982Y150550D01*
X109316D01*
G01X86016Y204050D02*
Y206550D01*
X87057D01*
X87391Y206425D01*
X87599Y206258D01*
X87682Y205925D01*
X87599Y205592D01*
X87349Y205383D01*
X87057Y205258D01*
X86016D01*
G01X87057D02*
X87682Y204050D01*
G01X89157Y206133D02*
X89407Y206383D01*
X89699Y206508D01*
X90032Y206550D01*
X90449Y206467D01*
X90741Y206258D01*
X90824Y206008D01*
X90782Y205758D01*
X90616Y205550D01*
X89782Y205133D01*
X89407Y204842D01*
X89157Y204425D01*
X89074Y204050D01*
X90824D01*
G01X92341Y204342D02*
X92632Y204133D01*
X92966Y204050D01*
X93299Y204133D01*
X93591Y204383D01*
X93799Y204758D01*
X93882Y205133D01*
Y205592D01*
X93799Y205967D01*
X93591Y206300D01*
X93341Y206467D01*
X93049Y206550D01*
X92716Y206467D01*
X92466Y206300D01*
X92299Y206050D01*
X92216Y205717D01*
X92299Y205425D01*
X92507Y205133D01*
X92757Y204967D01*
X93049Y204925D01*
X93382Y205008D01*
X93632Y205217D01*
X93882Y205592D01*
G01X96066Y204050D02*
X96149Y204592D01*
X96274Y205050D01*
X96441Y205467D01*
X96649Y205925D01*
X96982Y206550D01*
X95316D01*
G01X86016Y208050D02*
Y210550D01*
X87057D01*
X87391Y210425D01*
X87599Y210258D01*
X87682Y209925D01*
X87599Y209592D01*
X87349Y209383D01*
X87057Y209258D01*
X86016D01*
G01X87057D02*
X87682Y208050D01*
G01X89157Y210133D02*
X89407Y210383D01*
X89699Y210508D01*
X90032Y210550D01*
X90449Y210467D01*
X90741Y210258D01*
X90824Y210008D01*
X90782Y209758D01*
X90616Y209550D01*
X89782Y209133D01*
X89407Y208842D01*
X89157Y208425D01*
X89074Y208050D01*
X90824D01*
G01X92341Y208342D02*
X92632Y208133D01*
X92966Y208050D01*
X93299Y208133D01*
X93591Y208383D01*
X93799Y208758D01*
X93882Y209133D01*
Y209592D01*
X93799Y209967D01*
X93591Y210300D01*
X93341Y210467D01*
X93049Y210550D01*
X92716Y210467D01*
X92466Y210300D01*
X92299Y210050D01*
X92216Y209717D01*
X92299Y209425D01*
X92507Y209133D01*
X92757Y208967D01*
X93049Y208925D01*
X93382Y209008D01*
X93632Y209217D01*
X93882Y209592D01*
G01X95441Y208342D02*
X95732Y208133D01*
X96066Y208050D01*
X96399Y208133D01*
X96691Y208383D01*
X96899Y208758D01*
X96982Y209133D01*
Y209592D01*
X96899Y209967D01*
X96691Y210300D01*
X96441Y210467D01*
X96149Y210550D01*
X95816Y210467D01*
X95566Y210300D01*
X95399Y210050D01*
X95316Y209717D01*
X95399Y209425D01*
X95607Y209133D01*
X95857Y208967D01*
X96149Y208925D01*
X96482Y209008D01*
X96732Y209217D01*
X96982Y209592D01*
G01X93500Y416000D02*
X103500D01*
G01Y409000D02*
X93500D01*
G01X98500D02*
Y416000D01*
G01X93500Y405567D02*
X103500D01*
Y402233D01*
X103000Y400900D01*
X102333Y399900D01*
X101333Y399067D01*
X100166Y398400D01*
X98500Y398233D01*
X96833Y398400D01*
X95667Y399067D01*
X94666Y399900D01*
X94000Y400900D01*
X93500Y402233D01*
Y405567D01*
G01Y394967D02*
X103500D01*
Y391633D01*
X103000Y390300D01*
X102333Y389300D01*
X101333Y388467D01*
X100166Y387800D01*
X98500Y387633D01*
X96833Y387800D01*
X95667Y388467D01*
X94666Y389300D01*
X94000Y390300D01*
X93500Y391633D01*
Y394967D01*
G01Y380700D02*
X103500D01*
X101500Y382700D01*
G01X93500D02*
Y378700D01*
G01X95500Y373767D02*
X94333Y372767D01*
X93667Y371434D01*
X93500Y369933D01*
X93667Y368600D01*
X94500Y367267D01*
X95500Y366433D01*
X96500Y366267D01*
X97666Y366600D01*
X98500Y367767D01*
X98833Y368933D01*
Y370433D01*
G01Y368933D02*
X99333Y367933D01*
X100166Y367100D01*
X101167Y366767D01*
X102167Y367100D01*
X103000Y367933D01*
X103500Y369433D01*
X103333Y370933D01*
X102667Y372433D01*
G01X99499Y473400D02*
X101999D01*
G01X99499Y472442D02*
Y474358D01*
G01X101999Y475667D02*
X99499D01*
Y476667D01*
X99624Y477000D01*
X99916Y477250D01*
X100249Y477333D01*
X100582Y477250D01*
X100832Y477042D01*
X100957Y476667D01*
Y475667D01*
G01X101499Y478683D02*
X101791Y478933D01*
X101957Y479267D01*
X101999Y479642D01*
X101957Y479975D01*
X101749Y480308D01*
X101499Y480517D01*
X101249Y480558D01*
X100957Y480475D01*
X100749Y480183D01*
X100666Y479892D01*
Y479517D01*
G01Y479892D02*
X100541Y480142D01*
X100332Y480350D01*
X100082Y480433D01*
X99832Y480350D01*
X99624Y480142D01*
X99499Y479767D01*
X99541Y479392D01*
X99707Y479017D01*
G01X101999Y482700D02*
X101957Y482992D01*
X101832Y483325D01*
X101624Y483533D01*
X101332Y483617D01*
X101041Y483533D01*
X100791Y483283D01*
X100666Y482908D01*
Y482492D01*
X100582Y482242D01*
X100374Y482033D01*
X100082Y481950D01*
X99791Y482075D01*
X99582Y482367D01*
X99499Y482700D01*
X99582Y483033D01*
X99791Y483325D01*
X100082Y483450D01*
X100374Y483367D01*
X100582Y483158D01*
X100666Y482908D01*
Y482492D01*
X100791Y482117D01*
X101041Y481867D01*
X101332Y481783D01*
X101624Y481867D01*
X101832Y482075D01*
X101957Y482408D01*
X101999Y482700D01*
G01X100212Y540780D02*
X99962Y540905D01*
X99670Y540988D01*
X99337D01*
X98962Y540863D01*
X98670Y540655D01*
X98462Y540405D01*
X98295Y539988D01*
X98253Y539613D01*
X98337Y539238D01*
X98462Y538988D01*
X98712Y538738D01*
X99003Y538571D01*
X99295Y538488D01*
X99587D01*
X99878Y538571D01*
X100128Y538696D01*
X100337Y538863D01*
G01X101478Y538988D02*
X101728Y538696D01*
X102062Y538530D01*
X102437Y538488D01*
X102770Y538530D01*
X103103Y538738D01*
X103312Y538988D01*
X103353Y539238D01*
X103270Y539530D01*
X102978Y539738D01*
X102687Y539821D01*
X102312D01*
G01X102687D02*
X102937Y539946D01*
X103145Y540155D01*
X103228Y540405D01*
X103145Y540655D01*
X102937Y540863D01*
X102562Y540988D01*
X102187Y540946D01*
X101812Y540780D01*
G01X105495Y538488D02*
Y540988D01*
X104995Y540488D01*
G01Y538488D02*
X105995D01*
G01X108595D02*
Y540988D01*
X108095Y540488D01*
G01Y538488D02*
X109095D01*
G01X98612Y535280D02*
X98362Y535405D01*
X98070Y535488D01*
X97737D01*
X97362Y535363D01*
X97070Y535155D01*
X96862Y534905D01*
X96695Y534488D01*
X96653Y534113D01*
X96737Y533738D01*
X96862Y533488D01*
X97112Y533238D01*
X97403Y533071D01*
X97695Y532988D01*
X97987D01*
X98278Y533071D01*
X98528Y533196D01*
X98737Y533363D01*
G01X99878Y533488D02*
X100128Y533196D01*
X100462Y533030D01*
X100837Y532988D01*
X101170Y533030D01*
X101503Y533238D01*
X101712Y533488D01*
X101753Y533738D01*
X101670Y534030D01*
X101378Y534238D01*
X101087Y534321D01*
X100712D01*
G01X101087D02*
X101337Y534446D01*
X101545Y534655D01*
X101628Y534905D01*
X101545Y535155D01*
X101337Y535363D01*
X100962Y535488D01*
X100587Y535446D01*
X100212Y535280D01*
G01X103895Y532988D02*
Y535488D01*
X103395Y534988D01*
G01Y532988D02*
X104395D01*
G01X106203Y535071D02*
X106453Y535321D01*
X106745Y535446D01*
X107078Y535488D01*
X107495Y535405D01*
X107787Y535196D01*
X107870Y534946D01*
X107828Y534696D01*
X107662Y534488D01*
X106828Y534071D01*
X106453Y533780D01*
X106203Y533363D01*
X106120Y532988D01*
X107870D01*
G01X98612Y531780D02*
X98362Y531905D01*
X98070Y531988D01*
X97737D01*
X97362Y531863D01*
X97070Y531655D01*
X96862Y531405D01*
X96695Y530988D01*
X96653Y530613D01*
X96737Y530238D01*
X96862Y529988D01*
X97112Y529738D01*
X97403Y529571D01*
X97695Y529488D01*
X97987D01*
X98278Y529571D01*
X98528Y529696D01*
X98737Y529863D01*
G01X99878Y529988D02*
X100128Y529696D01*
X100462Y529530D01*
X100837Y529488D01*
X101170Y529530D01*
X101503Y529738D01*
X101712Y529988D01*
X101753Y530238D01*
X101670Y530530D01*
X101378Y530738D01*
X101087Y530821D01*
X100712D01*
G01X101087D02*
X101337Y530946D01*
X101545Y531155D01*
X101628Y531405D01*
X101545Y531655D01*
X101337Y531863D01*
X100962Y531988D01*
X100587Y531946D01*
X100212Y531780D01*
G01X103895Y529488D02*
Y531988D01*
X103395Y531488D01*
G01Y529488D02*
X104395D01*
G01X106078Y529988D02*
X106328Y529696D01*
X106662Y529530D01*
X107037Y529488D01*
X107370Y529530D01*
X107703Y529738D01*
X107912Y529988D01*
X107953Y530238D01*
X107870Y530530D01*
X107578Y530738D01*
X107287Y530821D01*
X106912D01*
G01X107287D02*
X107537Y530946D01*
X107745Y531155D01*
X107828Y531405D01*
X107745Y531655D01*
X107537Y531863D01*
X107162Y531988D01*
X106787Y531946D01*
X106412Y531780D01*
G01X98665Y649850D02*
X108665D01*
G01Y642850D02*
X98665D01*
G01X103665D02*
Y649850D01*
G01X98665Y639417D02*
X108665D01*
Y636083D01*
X108165Y634750D01*
X107498Y633750D01*
X106498Y632917D01*
X105331Y632250D01*
X103665Y632083D01*
X101998Y632250D01*
X100832Y632917D01*
X99831Y633750D01*
X99165Y634750D01*
X98665Y636083D01*
Y639417D01*
G01Y628817D02*
X108665D01*
Y625483D01*
X108165Y624150D01*
X107498Y623150D01*
X106498Y622317D01*
X105331Y621650D01*
X103665Y621483D01*
X101998Y621650D01*
X100832Y622317D01*
X99831Y623150D01*
X99165Y624150D01*
X98665Y625483D01*
Y628817D01*
G01Y614550D02*
X108665D01*
X106665Y616550D01*
G01X98665D02*
Y612550D01*
G01X100665Y607617D02*
X99498Y606617D01*
X98832Y605284D01*
X98665Y603783D01*
X98832Y602450D01*
X99665Y601117D01*
X100665Y600283D01*
X101665Y600117D01*
X102831Y600450D01*
X103665Y601617D01*
X103998Y602783D01*
Y604283D01*
G01Y602783D02*
X104498Y601783D01*
X105331Y600950D01*
X106332Y600617D01*
X107332Y600950D01*
X108165Y601783D01*
X108665Y603283D01*
X108498Y604783D01*
X107832Y606283D01*
G01X95332Y598350D02*
Y588350D01*
G01X108665Y586083D02*
X98665D01*
Y579417D01*
G01Y568817D02*
Y575483D01*
X108665D01*
Y568817D01*
G01X103832Y571483D02*
Y575483D01*
G01X98665Y565217D02*
X108665D01*
Y561883D01*
X108165Y560550D01*
X107498Y559550D01*
X106498Y558717D01*
X105331Y558050D01*
X103665Y557883D01*
X101998Y558050D01*
X100832Y558717D01*
X99831Y559550D01*
X99165Y560550D01*
X98665Y561883D01*
Y565217D01*
G01X100212Y544280D02*
X99962Y544405D01*
X99670Y544488D01*
X99337D01*
X98962Y544363D01*
X98670Y544155D01*
X98462Y543905D01*
X98295Y543488D01*
X98253Y543113D01*
X98337Y542738D01*
X98462Y542488D01*
X98712Y542238D01*
X99003Y542071D01*
X99295Y541988D01*
X99587D01*
X99878Y542071D01*
X100128Y542196D01*
X100337Y542363D01*
G01X101478Y542488D02*
X101728Y542196D01*
X102062Y542030D01*
X102437Y541988D01*
X102770Y542030D01*
X103103Y542238D01*
X103312Y542488D01*
X103353Y542738D01*
X103270Y543030D01*
X102978Y543238D01*
X102687Y543321D01*
X102312D01*
G01X102687D02*
X102937Y543446D01*
X103145Y543655D01*
X103228Y543905D01*
X103145Y544155D01*
X102937Y544363D01*
X102562Y544488D01*
X102187Y544446D01*
X101812Y544280D01*
G01X105495Y541988D02*
Y544488D01*
X104995Y543988D01*
G01Y541988D02*
X105995D01*
G01X108595Y544488D02*
X108262Y544405D01*
X108012Y544196D01*
X107845Y543946D01*
X107720Y543613D01*
X107678Y543238D01*
X107720Y542863D01*
X107845Y542530D01*
X108012Y542280D01*
X108262Y542071D01*
X108595Y541988D01*
X108928Y542071D01*
X109178Y542280D01*
X109345Y542530D01*
X109470Y542863D01*
X109512Y543238D01*
X109470Y543613D01*
X109345Y543946D01*
X109178Y544196D01*
X108928Y544405D01*
X108595Y544488D01*
G01X83016Y641050D02*
Y643550D01*
X84057D01*
X84391Y643425D01*
X84599Y643258D01*
X84682Y642925D01*
X84599Y642592D01*
X84349Y642383D01*
X84057Y642258D01*
X83016D01*
G01X84057D02*
X84682Y641050D01*
G01X86032Y641425D02*
X86282Y641217D01*
X86574Y641092D01*
X86949Y641050D01*
X87324Y641133D01*
X87616Y641300D01*
X87824Y641592D01*
X87866Y641925D01*
X87782Y642258D01*
X87574Y642467D01*
X87282Y642633D01*
X86991Y642675D01*
X86699Y642633D01*
X86324Y642467D01*
X86449Y643550D01*
X87574D01*
G01X90049D02*
X89716Y643467D01*
X89466Y643258D01*
X89299Y643008D01*
X89174Y642675D01*
X89132Y642300D01*
X89174Y641925D01*
X89299Y641592D01*
X89466Y641342D01*
X89716Y641133D01*
X90049Y641050D01*
X90382Y641133D01*
X90632Y641342D01*
X90799Y641592D01*
X90924Y641925D01*
X90966Y642300D01*
X90924Y642675D01*
X90799Y643008D01*
X90632Y643258D01*
X90382Y643467D01*
X90049Y643550D01*
G01X92232Y641550D02*
X92482Y641258D01*
X92816Y641092D01*
X93191Y641050D01*
X93524Y641092D01*
X93857Y641300D01*
X94066Y641550D01*
X94107Y641800D01*
X94024Y642092D01*
X93732Y642300D01*
X93441Y642383D01*
X93066D01*
G01X93441D02*
X93691Y642508D01*
X93899Y642717D01*
X93982Y642967D01*
X93899Y643217D01*
X93691Y643425D01*
X93316Y643550D01*
X92941Y643508D01*
X92566Y643342D01*
G01X88500Y742517D02*
X86000D01*
Y743558D01*
X86125Y743892D01*
X86292Y744100D01*
X86625Y744183D01*
X86958Y744100D01*
X87167Y743850D01*
X87292Y743558D01*
Y742517D01*
G01Y743558D02*
X88500Y744183D01*
G01X88125Y745533D02*
X88333Y745783D01*
X88458Y746075D01*
X88500Y746450D01*
X88417Y746825D01*
X88250Y747117D01*
X87958Y747325D01*
X87625Y747367D01*
X87292Y747283D01*
X87083Y747075D01*
X86917Y746783D01*
X86875Y746492D01*
X86917Y746200D01*
X87083Y745825D01*
X86000Y745950D01*
Y747075D01*
G01X88500Y750050D02*
X86000D01*
X87792Y748508D01*
Y750592D01*
G01X88000Y751733D02*
X88292Y751983D01*
X88458Y752317D01*
X88500Y752692D01*
X88458Y753025D01*
X88250Y753358D01*
X88000Y753567D01*
X87750Y753608D01*
X87458Y753525D01*
X87250Y753233D01*
X87167Y752942D01*
Y752567D01*
G01Y752942D02*
X87042Y753192D01*
X86833Y753400D01*
X86583Y753483D01*
X86333Y753400D01*
X86125Y753192D01*
X86000Y752817D01*
X86042Y752442D01*
X86208Y752067D01*
G01X83200Y739300D02*
Y756900D01*
G01X86499Y782450D02*
X88999D01*
G01X86499Y781492D02*
Y783408D01*
G01X86707Y786467D02*
X86582Y786217D01*
X86499Y785925D01*
Y785592D01*
X86624Y785217D01*
X86832Y784925D01*
X87082Y784717D01*
X87499Y784550D01*
X87874Y784508D01*
X88249Y784592D01*
X88499Y784717D01*
X88749Y784967D01*
X88916Y785258D01*
X88999Y785550D01*
Y785842D01*
X88916Y786133D01*
X88791Y786383D01*
X88624Y786592D01*
G01X86916Y787858D02*
X86666Y788108D01*
X86541Y788400D01*
X86499Y788733D01*
X86582Y789150D01*
X86791Y789442D01*
X87041Y789525D01*
X87291Y789483D01*
X87499Y789317D01*
X87916Y788483D01*
X88207Y788108D01*
X88624Y787858D01*
X88999Y787775D01*
Y789525D01*
G01X110899Y965850D02*
Y969850D01*
X103499D01*
G01X83517Y1017000D02*
Y1019500D01*
X84558D01*
X84892Y1019375D01*
X85100Y1019208D01*
X85183Y1018875D01*
X85100Y1018542D01*
X84850Y1018333D01*
X84558Y1018208D01*
X83517D01*
G01X84558D02*
X85183Y1017000D01*
G01X86658Y1019083D02*
X86908Y1019333D01*
X87200Y1019458D01*
X87533Y1019500D01*
X87950Y1019417D01*
X88242Y1019208D01*
X88325Y1018958D01*
X88283Y1018708D01*
X88117Y1018500D01*
X87283Y1018083D01*
X86908Y1017792D01*
X86658Y1017375D01*
X86575Y1017000D01*
X88325D01*
G01X89758Y1018042D02*
X90050Y1018333D01*
X90300Y1018500D01*
X90633Y1018583D01*
X90925Y1018500D01*
X91133Y1018333D01*
X91300Y1018083D01*
X91342Y1017792D01*
X91300Y1017542D01*
X91133Y1017292D01*
X90883Y1017083D01*
X90592Y1017000D01*
X90258Y1017083D01*
X89967Y1017333D01*
X89800Y1017708D01*
X89758Y1018125D01*
X89842Y1018667D01*
X89967Y1018958D01*
X90175Y1019250D01*
X90467Y1019458D01*
X90758Y1019500D01*
X91050Y1019417D01*
X91258Y1019208D01*
G01X92942Y1017292D02*
X93233Y1017083D01*
X93567Y1017000D01*
X93900Y1017083D01*
X94192Y1017333D01*
X94400Y1017708D01*
X94483Y1018083D01*
Y1018542D01*
X94400Y1018917D01*
X94192Y1019250D01*
X93942Y1019417D01*
X93650Y1019500D01*
X93317Y1019417D01*
X93067Y1019250D01*
X92900Y1019000D01*
X92817Y1018667D01*
X92900Y1018375D01*
X93108Y1018083D01*
X93358Y1017917D01*
X93650Y1017875D01*
X93983Y1017958D01*
X94233Y1018167D01*
X94483Y1018542D01*
G01X83017Y1022500D02*
Y1025000D01*
X84058D01*
X84392Y1024875D01*
X84600Y1024708D01*
X84683Y1024375D01*
X84600Y1024042D01*
X84350Y1023833D01*
X84058Y1023708D01*
X83017D01*
G01X84058D02*
X84683Y1022500D01*
G01X86158Y1024583D02*
X86408Y1024833D01*
X86700Y1024958D01*
X87033Y1025000D01*
X87450Y1024917D01*
X87742Y1024708D01*
X87825Y1024458D01*
X87783Y1024208D01*
X87617Y1024000D01*
X86783Y1023583D01*
X86408Y1023292D01*
X86158Y1022875D01*
X86075Y1022500D01*
X87825D01*
G01X89967D02*
X90050Y1023042D01*
X90175Y1023500D01*
X90342Y1023917D01*
X90550Y1024375D01*
X90883Y1025000D01*
X89217D01*
G01X93150Y1022500D02*
Y1025000D01*
X92650Y1024500D01*
G01Y1022500D02*
X93650D01*
G01X91616Y1007450D02*
Y1009950D01*
X92657D01*
X92991Y1009825D01*
X93199Y1009658D01*
X93282Y1009325D01*
X93199Y1008992D01*
X92949Y1008783D01*
X92657Y1008658D01*
X91616D01*
G01X92657D02*
X93282Y1007450D01*
G01X94632Y1007950D02*
X94882Y1007658D01*
X95216Y1007492D01*
X95591Y1007450D01*
X95924Y1007492D01*
X96257Y1007700D01*
X96466Y1007950D01*
X96507Y1008200D01*
X96424Y1008492D01*
X96132Y1008700D01*
X95841Y1008783D01*
X95466D01*
G01X95841D02*
X96091Y1008908D01*
X96299Y1009117D01*
X96382Y1009367D01*
X96299Y1009617D01*
X96091Y1009825D01*
X95716Y1009950D01*
X95341Y1009908D01*
X94966Y1009742D01*
G01X98566Y1007450D02*
X98649Y1007992D01*
X98774Y1008450D01*
X98941Y1008867D01*
X99149Y1009325D01*
X99482Y1009950D01*
X97816D01*
G01X101749Y1007450D02*
Y1009950D01*
X101249Y1009450D01*
G01Y1007450D02*
X102249D01*
G01X91616Y1011450D02*
Y1013950D01*
X92657D01*
X92991Y1013825D01*
X93199Y1013658D01*
X93282Y1013325D01*
X93199Y1012992D01*
X92949Y1012783D01*
X92657Y1012658D01*
X91616D01*
G01X92657D02*
X93282Y1011450D01*
G01X94632Y1011950D02*
X94882Y1011658D01*
X95216Y1011492D01*
X95591Y1011450D01*
X95924Y1011492D01*
X96257Y1011700D01*
X96466Y1011950D01*
X96507Y1012200D01*
X96424Y1012492D01*
X96132Y1012700D01*
X95841Y1012783D01*
X95466D01*
G01X95841D02*
X96091Y1012908D01*
X96299Y1013117D01*
X96382Y1013367D01*
X96299Y1013617D01*
X96091Y1013825D01*
X95716Y1013950D01*
X95341Y1013908D01*
X94966Y1013742D01*
G01X98566Y1011450D02*
X98649Y1011992D01*
X98774Y1012450D01*
X98941Y1012867D01*
X99149Y1013325D01*
X99482Y1013950D01*
X97816D01*
G01X100957Y1013533D02*
X101207Y1013783D01*
X101499Y1013908D01*
X101832Y1013950D01*
X102249Y1013867D01*
X102541Y1013658D01*
X102624Y1013408D01*
X102582Y1013158D01*
X102416Y1012950D01*
X101582Y1012533D01*
X101207Y1012242D01*
X100957Y1011825D01*
X100874Y1011450D01*
X102624D01*
G01X92116Y1066400D02*
Y1068900D01*
X93157D01*
X93491Y1068775D01*
X93699Y1068608D01*
X93782Y1068275D01*
X93699Y1067942D01*
X93449Y1067733D01*
X93157Y1067608D01*
X92116D01*
G01X93157D02*
X93782Y1066400D01*
G01X96549D02*
Y1068900D01*
X95007Y1067108D01*
X97091D01*
G01X98441Y1066692D02*
X98732Y1066483D01*
X99066Y1066400D01*
X99399Y1066483D01*
X99691Y1066733D01*
X99899Y1067108D01*
X99982Y1067483D01*
Y1067942D01*
X99899Y1068317D01*
X99691Y1068650D01*
X99441Y1068817D01*
X99149Y1068900D01*
X98816Y1068817D01*
X98566Y1068650D01*
X98399Y1068400D01*
X98316Y1068067D01*
X98399Y1067775D01*
X98607Y1067483D01*
X98857Y1067317D01*
X99149Y1067275D01*
X99482Y1067358D01*
X99732Y1067567D01*
X99982Y1067942D01*
G01X102749Y1066400D02*
Y1068900D01*
X101207Y1067108D01*
X103291D01*
G01X85999Y1075567D02*
X83499D01*
Y1076608D01*
X83624Y1076942D01*
X83791Y1077150D01*
X84124Y1077233D01*
X84457Y1077150D01*
X84666Y1076900D01*
X84791Y1076608D01*
Y1075567D01*
G01Y1076608D02*
X85999Y1077233D01*
G01X83916Y1078708D02*
X83666Y1078958D01*
X83541Y1079250D01*
X83499Y1079583D01*
X83582Y1080000D01*
X83791Y1080292D01*
X84041Y1080375D01*
X84291Y1080333D01*
X84499Y1080167D01*
X84916Y1079333D01*
X85207Y1078958D01*
X85624Y1078708D01*
X85999Y1078625D01*
Y1080375D01*
G01X83499Y1082600D02*
X83582Y1082267D01*
X83791Y1082017D01*
X84041Y1081850D01*
X84374Y1081725D01*
X84749Y1081683D01*
X85124Y1081725D01*
X85457Y1081850D01*
X85707Y1082017D01*
X85916Y1082267D01*
X85999Y1082600D01*
X85916Y1082933D01*
X85707Y1083183D01*
X85457Y1083350D01*
X85124Y1083475D01*
X84749Y1083517D01*
X84374Y1083475D01*
X84041Y1083350D01*
X83791Y1083183D01*
X83582Y1082933D01*
X83499Y1082600D01*
G01X84957Y1084908D02*
X84666Y1085200D01*
X84499Y1085450D01*
X84416Y1085783D01*
X84499Y1086075D01*
X84666Y1086283D01*
X84916Y1086450D01*
X85207Y1086492D01*
X85457Y1086450D01*
X85707Y1086283D01*
X85916Y1086033D01*
X85999Y1085742D01*
X85916Y1085408D01*
X85666Y1085117D01*
X85291Y1084950D01*
X84874Y1084908D01*
X84332Y1084992D01*
X84041Y1085117D01*
X83749Y1085325D01*
X83541Y1085617D01*
X83499Y1085908D01*
X83582Y1086200D01*
X83791Y1086408D01*
G01X99499Y1092250D02*
X95499D01*
Y1084850D01*
G01X89999Y1075567D02*
X87499D01*
Y1076608D01*
X87624Y1076942D01*
X87791Y1077150D01*
X88124Y1077233D01*
X88457Y1077150D01*
X88666Y1076900D01*
X88791Y1076608D01*
Y1075567D01*
G01Y1076608D02*
X89999Y1077233D01*
G01X87916Y1078708D02*
X87666Y1078958D01*
X87541Y1079250D01*
X87499Y1079583D01*
X87582Y1080000D01*
X87791Y1080292D01*
X88041Y1080375D01*
X88291Y1080333D01*
X88499Y1080167D01*
X88916Y1079333D01*
X89207Y1078958D01*
X89624Y1078708D01*
X89999Y1078625D01*
Y1080375D01*
G01Y1082600D02*
X87499D01*
X87999Y1082100D01*
G01X89999D02*
Y1083100D01*
G01Y1085700D02*
X87499D01*
X87999Y1085200D01*
G01X89999D02*
Y1086200D01*
G01X103999Y1092250D02*
X99999D01*
Y1084850D01*
G01X92116Y1070700D02*
Y1073200D01*
X93157D01*
X93491Y1073075D01*
X93699Y1072908D01*
X93782Y1072575D01*
X93699Y1072242D01*
X93449Y1072033D01*
X93157Y1071908D01*
X92116D01*
G01X93157D02*
X93782Y1070700D01*
G01X96549D02*
Y1073200D01*
X95007Y1071408D01*
X97091D01*
G01X98441Y1070992D02*
X98732Y1070783D01*
X99066Y1070700D01*
X99399Y1070783D01*
X99691Y1071033D01*
X99899Y1071408D01*
X99982Y1071783D01*
Y1072242D01*
X99899Y1072617D01*
X99691Y1072950D01*
X99441Y1073117D01*
X99149Y1073200D01*
X98816Y1073117D01*
X98566Y1072950D01*
X98399Y1072700D01*
X98316Y1072367D01*
X98399Y1072075D01*
X98607Y1071783D01*
X98857Y1071617D01*
X99149Y1071575D01*
X99482Y1071658D01*
X99732Y1071867D01*
X99982Y1072242D01*
G01X101332Y1071075D02*
X101582Y1070867D01*
X101874Y1070742D01*
X102249Y1070700D01*
X102624Y1070783D01*
X102916Y1070950D01*
X103124Y1071242D01*
X103166Y1071575D01*
X103082Y1071908D01*
X102874Y1072117D01*
X102582Y1072283D01*
X102291Y1072325D01*
X101999Y1072283D01*
X101624Y1072117D01*
X101749Y1073200D01*
X102874D01*
G01X95899Y1083700D02*
Y1079700D01*
X103299D01*
G01X95899Y1079400D02*
Y1075400D01*
X103299D01*
G01X103099Y1103500D02*
X116499D01*
G01X103099Y1114900D02*
Y1103500D01*
G01X97500Y1095017D02*
X95000D01*
Y1096058D01*
X95125Y1096392D01*
X95292Y1096600D01*
X95625Y1096683D01*
X95958Y1096600D01*
X96167Y1096350D01*
X96292Y1096058D01*
Y1095017D01*
G01Y1096058D02*
X97500Y1096683D01*
G01Y1099450D02*
X95000D01*
X96792Y1097908D01*
Y1099992D01*
G01X97500Y1102050D02*
X95000D01*
X95500Y1101550D01*
G01X97500D02*
Y1102550D01*
G01X97125Y1104233D02*
X97333Y1104483D01*
X97458Y1104775D01*
X97500Y1105150D01*
X97417Y1105525D01*
X97250Y1105817D01*
X96958Y1106025D01*
X96625Y1106067D01*
X96292Y1105983D01*
X96083Y1105775D01*
X95917Y1105483D01*
X95875Y1105192D01*
X95917Y1104900D01*
X96083Y1104525D01*
X95000Y1104650D01*
Y1105775D01*
G01X102700Y1113300D02*
X98700D01*
Y1105900D01*
G01X100499Y1093533D02*
X102291D01*
X102666Y1093700D01*
X102916Y1094033D01*
X102999Y1094450D01*
X102916Y1094867D01*
X102666Y1095200D01*
X102291Y1095367D01*
X100499D01*
G01X100916Y1096758D02*
X100666Y1097008D01*
X100541Y1097300D01*
X100499Y1097633D01*
X100582Y1098050D01*
X100791Y1098342D01*
X101041Y1098425D01*
X101291Y1098383D01*
X101499Y1098217D01*
X101916Y1097383D01*
X102207Y1097008D01*
X102624Y1096758D01*
X102999Y1096675D01*
Y1098425D01*
G01Y1101150D02*
X100499D01*
X102291Y1099608D01*
Y1101692D01*
G01X116499Y1114900D02*
X103099D01*
G01X102700Y1113400D02*
Y1117400D01*
X95300D01*
G01X92999Y1117750D02*
X94999Y1119750D01*
X96999Y1117750D01*
G01X100599D02*
Y1136950D01*
X89399D01*
Y1117750D01*
X100599D01*
G01X97999Y1179950D02*
Y1141150D01*
G01X99100Y1163000D02*
Y1145400D01*
G01D02*
X107100D01*
G01X98999Y1168250D02*
Y1173750D01*
G01X106999Y1168250D02*
X98999D01*
G01X107100Y1163000D02*
X99100D01*
G01X98999Y1185850D02*
X106999D01*
G01X98999Y1180350D02*
Y1185850D01*
G01X97417Y1212065D02*
X94917D01*
Y1213106D01*
X95042Y1213440D01*
X95209Y1213648D01*
X95542Y1213731D01*
X95875Y1213648D01*
X96084Y1213398D01*
X96209Y1213106D01*
Y1212065D01*
G01Y1213106D02*
X97417Y1213731D01*
G01X95334Y1215206D02*
X95084Y1215456D01*
X94959Y1215748D01*
X94917Y1216081D01*
X95000Y1216498D01*
X95209Y1216790D01*
X95459Y1216873D01*
X95709Y1216831D01*
X95917Y1216665D01*
X96334Y1215831D01*
X96625Y1215456D01*
X97042Y1215206D01*
X97417Y1215123D01*
Y1216873D01*
G01X96375Y1218306D02*
X96084Y1218598D01*
X95917Y1218848D01*
X95834Y1219181D01*
X95917Y1219473D01*
X96084Y1219681D01*
X96334Y1219848D01*
X96625Y1219890D01*
X96875Y1219848D01*
X97125Y1219681D01*
X97334Y1219431D01*
X97417Y1219140D01*
X97334Y1218806D01*
X97084Y1218515D01*
X96709Y1218348D01*
X96292Y1218306D01*
X95750Y1218390D01*
X95459Y1218515D01*
X95167Y1218723D01*
X94959Y1219015D01*
X94917Y1219306D01*
X95000Y1219598D01*
X95209Y1219806D01*
G01X95334Y1221406D02*
X95084Y1221656D01*
X94959Y1221948D01*
X94917Y1222281D01*
X95000Y1222698D01*
X95209Y1222990D01*
X95459Y1223073D01*
X95709Y1223031D01*
X95917Y1222865D01*
X96334Y1222031D01*
X96625Y1221656D01*
X97042Y1221406D01*
X97417Y1221323D01*
Y1223073D01*
G01X93917Y1212128D02*
X91417D01*
Y1213169D01*
X91542Y1213503D01*
X91709Y1213711D01*
X92042Y1213794D01*
X92375Y1213711D01*
X92584Y1213461D01*
X92709Y1213169D01*
Y1212128D01*
G01Y1213169D02*
X93917Y1213794D01*
G01X91834Y1215269D02*
X91584Y1215519D01*
X91459Y1215811D01*
X91417Y1216144D01*
X91500Y1216561D01*
X91709Y1216853D01*
X91959Y1216936D01*
X92209Y1216894D01*
X92417Y1216728D01*
X92834Y1215894D01*
X93125Y1215519D01*
X93542Y1215269D01*
X93917Y1215186D01*
Y1216936D01*
G01X92875Y1218369D02*
X92584Y1218661D01*
X92417Y1218911D01*
X92334Y1219244D01*
X92417Y1219536D01*
X92584Y1219744D01*
X92834Y1219911D01*
X93125Y1219953D01*
X93375Y1219911D01*
X93625Y1219744D01*
X93834Y1219494D01*
X93917Y1219203D01*
X93834Y1218869D01*
X93584Y1218578D01*
X93209Y1218411D01*
X92792Y1218369D01*
X92250Y1218453D01*
X91959Y1218578D01*
X91667Y1218786D01*
X91459Y1219078D01*
X91417Y1219369D01*
X91500Y1219661D01*
X91709Y1219869D01*
G01X93417Y1221344D02*
X93709Y1221594D01*
X93875Y1221928D01*
X93917Y1222303D01*
X93875Y1222636D01*
X93667Y1222969D01*
X93417Y1223178D01*
X93167Y1223219D01*
X92875Y1223136D01*
X92667Y1222844D01*
X92584Y1222553D01*
Y1222178D01*
G01Y1222553D02*
X92459Y1222803D01*
X92250Y1223011D01*
X92000Y1223094D01*
X91750Y1223011D01*
X91542Y1222803D01*
X91417Y1222428D01*
X91459Y1222053D01*
X91625Y1221678D01*
G01X90417Y1212128D02*
X87917D01*
Y1213169D01*
X88042Y1213503D01*
X88209Y1213711D01*
X88542Y1213794D01*
X88875Y1213711D01*
X89084Y1213461D01*
X89209Y1213169D01*
Y1212128D01*
G01Y1213169D02*
X90417Y1213794D01*
G01X88334Y1215269D02*
X88084Y1215519D01*
X87959Y1215811D01*
X87917Y1216144D01*
X88000Y1216561D01*
X88209Y1216853D01*
X88459Y1216936D01*
X88709Y1216894D01*
X88917Y1216728D01*
X89334Y1215894D01*
X89625Y1215519D01*
X90042Y1215269D01*
X90417Y1215186D01*
Y1216936D01*
G01X89375Y1218369D02*
X89084Y1218661D01*
X88917Y1218911D01*
X88834Y1219244D01*
X88917Y1219536D01*
X89084Y1219744D01*
X89334Y1219911D01*
X89625Y1219953D01*
X89875Y1219911D01*
X90125Y1219744D01*
X90334Y1219494D01*
X90417Y1219203D01*
X90334Y1218869D01*
X90084Y1218578D01*
X89709Y1218411D01*
X89292Y1218369D01*
X88750Y1218453D01*
X88459Y1218578D01*
X88167Y1218786D01*
X87959Y1219078D01*
X87917Y1219369D01*
X88000Y1219661D01*
X88209Y1219869D01*
G01X89375Y1221469D02*
X89084Y1221761D01*
X88917Y1222011D01*
X88834Y1222344D01*
X88917Y1222636D01*
X89084Y1222844D01*
X89334Y1223011D01*
X89625Y1223053D01*
X89875Y1223011D01*
X90125Y1222844D01*
X90334Y1222594D01*
X90417Y1222303D01*
X90334Y1221969D01*
X90084Y1221678D01*
X89709Y1221511D01*
X89292Y1221469D01*
X88750Y1221553D01*
X88459Y1221678D01*
X88167Y1221886D01*
X87959Y1222178D01*
X87917Y1222469D01*
X88000Y1222761D01*
X88209Y1222969D01*
G01X86917Y1212065D02*
X84417D01*
Y1213106D01*
X84542Y1213440D01*
X84709Y1213648D01*
X85042Y1213731D01*
X85375Y1213648D01*
X85584Y1213398D01*
X85709Y1213106D01*
Y1212065D01*
G01Y1213106D02*
X86917Y1213731D01*
G01X84834Y1215206D02*
X84584Y1215456D01*
X84459Y1215748D01*
X84417Y1216081D01*
X84500Y1216498D01*
X84709Y1216790D01*
X84959Y1216873D01*
X85209Y1216831D01*
X85417Y1216665D01*
X85834Y1215831D01*
X86125Y1215456D01*
X86542Y1215206D01*
X86917Y1215123D01*
Y1216873D01*
G01X85875Y1218306D02*
X85584Y1218598D01*
X85417Y1218848D01*
X85334Y1219181D01*
X85417Y1219473D01*
X85584Y1219681D01*
X85834Y1219848D01*
X86125Y1219890D01*
X86375Y1219848D01*
X86625Y1219681D01*
X86834Y1219431D01*
X86917Y1219140D01*
X86834Y1218806D01*
X86584Y1218515D01*
X86209Y1218348D01*
X85792Y1218306D01*
X85250Y1218390D01*
X84959Y1218515D01*
X84667Y1218723D01*
X84459Y1219015D01*
X84417Y1219306D01*
X84500Y1219598D01*
X84709Y1219806D01*
G01X86917Y1222115D02*
X86375Y1222198D01*
X85917Y1222323D01*
X85500Y1222490D01*
X85042Y1222698D01*
X84417Y1223031D01*
Y1221365D01*
G01X96836Y1196999D02*
X94336D01*
Y1198040D01*
X94461Y1198374D01*
X94628Y1198582D01*
X94961Y1198665D01*
X95294Y1198582D01*
X95503Y1198332D01*
X95628Y1198040D01*
Y1196999D01*
G01Y1198040D02*
X96836Y1198665D01*
G01Y1201432D02*
X94336D01*
X96128Y1199890D01*
Y1201974D01*
G01X95794Y1203240D02*
X95503Y1203532D01*
X95336Y1203782D01*
X95253Y1204115D01*
X95336Y1204407D01*
X95503Y1204615D01*
X95753Y1204782D01*
X96044Y1204824D01*
X96294Y1204782D01*
X96544Y1204615D01*
X96753Y1204365D01*
X96836Y1204074D01*
X96753Y1203740D01*
X96503Y1203449D01*
X96128Y1203282D01*
X95711Y1203240D01*
X95169Y1203324D01*
X94878Y1203449D01*
X94586Y1203657D01*
X94378Y1203949D01*
X94336Y1204240D01*
X94419Y1204532D01*
X94628Y1204740D01*
G01X95794Y1206340D02*
X95503Y1206632D01*
X95336Y1206882D01*
X95253Y1207215D01*
X95336Y1207507D01*
X95503Y1207715D01*
X95753Y1207882D01*
X96044Y1207924D01*
X96294Y1207882D01*
X96544Y1207715D01*
X96753Y1207465D01*
X96836Y1207174D01*
X96753Y1206840D01*
X96503Y1206549D01*
X96128Y1206382D01*
X95711Y1206340D01*
X95169Y1206424D01*
X94878Y1206549D01*
X94586Y1206757D01*
X94378Y1207049D01*
X94336Y1207340D01*
X94419Y1207632D01*
X94628Y1207840D01*
G01X92836Y1196999D02*
X90336D01*
Y1198040D01*
X90461Y1198374D01*
X90628Y1198582D01*
X90961Y1198665D01*
X91294Y1198582D01*
X91503Y1198332D01*
X91628Y1198040D01*
Y1196999D01*
G01Y1198040D02*
X92836Y1198665D01*
G01Y1201432D02*
X90336D01*
X92128Y1199890D01*
Y1201974D01*
G01X91794Y1203240D02*
X91503Y1203532D01*
X91336Y1203782D01*
X91253Y1204115D01*
X91336Y1204407D01*
X91503Y1204615D01*
X91753Y1204782D01*
X92044Y1204824D01*
X92294Y1204782D01*
X92544Y1204615D01*
X92753Y1204365D01*
X92836Y1204074D01*
X92753Y1203740D01*
X92503Y1203449D01*
X92128Y1203282D01*
X91711Y1203240D01*
X91169Y1203324D01*
X90878Y1203449D01*
X90586Y1203657D01*
X90378Y1203949D01*
X90336Y1204240D01*
X90419Y1204532D01*
X90628Y1204740D01*
G01X92836Y1207049D02*
X92294Y1207132D01*
X91836Y1207257D01*
X91419Y1207424D01*
X90961Y1207632D01*
X90336Y1207965D01*
Y1206299D01*
G01X103499Y1196413D02*
X107499D01*
Y1203813D01*
G01X83150Y1227501D02*
X83025Y1227251D01*
X82942Y1226959D01*
Y1226626D01*
X83067Y1226251D01*
X83275Y1225959D01*
X83525Y1225751D01*
X83942Y1225584D01*
X84317Y1225542D01*
X84692Y1225626D01*
X84942Y1225751D01*
X85192Y1226001D01*
X85359Y1226292D01*
X85442Y1226584D01*
Y1226876D01*
X85359Y1227167D01*
X85234Y1227417D01*
X85067Y1227626D01*
G01X83359Y1228892D02*
X83109Y1229142D01*
X82984Y1229434D01*
X82942Y1229767D01*
X83025Y1230184D01*
X83234Y1230476D01*
X83484Y1230559D01*
X83734Y1230517D01*
X83942Y1230351D01*
X84359Y1229517D01*
X84650Y1229142D01*
X85067Y1228892D01*
X85442Y1228809D01*
Y1230559D01*
G01X85150Y1232076D02*
X85359Y1232367D01*
X85442Y1232701D01*
X85359Y1233034D01*
X85109Y1233326D01*
X84734Y1233534D01*
X84359Y1233617D01*
X83900D01*
X83525Y1233534D01*
X83192Y1233326D01*
X83025Y1233076D01*
X82942Y1232784D01*
X83025Y1232451D01*
X83192Y1232201D01*
X83442Y1232034D01*
X83775Y1231951D01*
X84067Y1232034D01*
X84359Y1232242D01*
X84525Y1232492D01*
X84567Y1232784D01*
X84484Y1233117D01*
X84275Y1233367D01*
X83900Y1233617D01*
G01X85442Y1235884D02*
X82942D01*
X83442Y1235384D01*
G01X85442D02*
Y1236384D01*
G01X95208Y1227767D02*
X95083Y1227517D01*
X95000Y1227225D01*
Y1226892D01*
X95125Y1226517D01*
X95333Y1226225D01*
X95583Y1226017D01*
X96000Y1225850D01*
X96375Y1225808D01*
X96750Y1225892D01*
X97000Y1226017D01*
X97250Y1226267D01*
X97417Y1226558D01*
X97500Y1226850D01*
Y1227142D01*
X97417Y1227433D01*
X97292Y1227683D01*
X97125Y1227892D01*
G01X95417Y1229158D02*
X95167Y1229408D01*
X95042Y1229700D01*
X95000Y1230033D01*
X95083Y1230450D01*
X95292Y1230742D01*
X95542Y1230825D01*
X95792Y1230783D01*
X96000Y1230617D01*
X96417Y1229783D01*
X96708Y1229408D01*
X97125Y1229158D01*
X97500Y1229075D01*
Y1230825D01*
G01Y1233050D02*
X97458Y1233342D01*
X97333Y1233675D01*
X97125Y1233883D01*
X96833Y1233967D01*
X96542Y1233883D01*
X96292Y1233633D01*
X96167Y1233258D01*
Y1232842D01*
X96083Y1232592D01*
X95875Y1232383D01*
X95583Y1232300D01*
X95292Y1232425D01*
X95083Y1232717D01*
X95000Y1233050D01*
X95083Y1233383D01*
X95292Y1233675D01*
X95583Y1233800D01*
X95875Y1233717D01*
X96083Y1233508D01*
X96167Y1233258D01*
Y1232842D01*
X96292Y1232467D01*
X96542Y1232217D01*
X96833Y1232133D01*
X97125Y1232217D01*
X97333Y1232425D01*
X97458Y1232758D01*
X97500Y1233050D01*
G01Y1236150D02*
X97458Y1236442D01*
X97333Y1236775D01*
X97125Y1236983D01*
X96833Y1237067D01*
X96542Y1236983D01*
X96292Y1236733D01*
X96167Y1236358D01*
Y1235942D01*
X96083Y1235692D01*
X95875Y1235483D01*
X95583Y1235400D01*
X95292Y1235525D01*
X95083Y1235817D01*
X95000Y1236150D01*
X95083Y1236483D01*
X95292Y1236775D01*
X95583Y1236900D01*
X95875Y1236817D01*
X96083Y1236608D01*
X96167Y1236358D01*
Y1235942D01*
X96292Y1235567D01*
X96542Y1235317D01*
X96833Y1235233D01*
X97125Y1235317D01*
X97333Y1235525D01*
X97458Y1235858D01*
X97500Y1236150D01*
G01X91208Y1227767D02*
X91083Y1227517D01*
X91000Y1227225D01*
Y1226892D01*
X91125Y1226517D01*
X91333Y1226225D01*
X91583Y1226017D01*
X92000Y1225850D01*
X92375Y1225808D01*
X92750Y1225892D01*
X93000Y1226017D01*
X93250Y1226267D01*
X93417Y1226558D01*
X93500Y1226850D01*
Y1227142D01*
X93417Y1227433D01*
X93292Y1227683D01*
X93125Y1227892D01*
G01X91417Y1229158D02*
X91167Y1229408D01*
X91042Y1229700D01*
X91000Y1230033D01*
X91083Y1230450D01*
X91292Y1230742D01*
X91542Y1230825D01*
X91792Y1230783D01*
X92000Y1230617D01*
X92417Y1229783D01*
X92708Y1229408D01*
X93125Y1229158D01*
X93500Y1229075D01*
Y1230825D01*
G01Y1233050D02*
X93458Y1233342D01*
X93333Y1233675D01*
X93125Y1233883D01*
X92833Y1233967D01*
X92542Y1233883D01*
X92292Y1233633D01*
X92167Y1233258D01*
Y1232842D01*
X92083Y1232592D01*
X91875Y1232383D01*
X91583Y1232300D01*
X91292Y1232425D01*
X91083Y1232717D01*
X91000Y1233050D01*
X91083Y1233383D01*
X91292Y1233675D01*
X91583Y1233800D01*
X91875Y1233717D01*
X92083Y1233508D01*
X92167Y1233258D01*
Y1232842D01*
X92292Y1232467D01*
X92542Y1232217D01*
X92833Y1232133D01*
X93125Y1232217D01*
X93333Y1232425D01*
X93458Y1232758D01*
X93500Y1233050D01*
G01X93208Y1235442D02*
X93417Y1235733D01*
X93500Y1236067D01*
X93417Y1236400D01*
X93167Y1236692D01*
X92792Y1236900D01*
X92417Y1236983D01*
X91958D01*
X91583Y1236900D01*
X91250Y1236692D01*
X91083Y1236442D01*
X91000Y1236150D01*
X91083Y1235817D01*
X91250Y1235567D01*
X91500Y1235400D01*
X91833Y1235317D01*
X92125Y1235400D01*
X92417Y1235608D01*
X92583Y1235858D01*
X92625Y1236150D01*
X92542Y1236483D01*
X92333Y1236733D01*
X91958Y1236983D01*
G01X87208Y1227767D02*
X87083Y1227517D01*
X87000Y1227225D01*
Y1226892D01*
X87125Y1226517D01*
X87333Y1226225D01*
X87583Y1226017D01*
X88000Y1225850D01*
X88375Y1225808D01*
X88750Y1225892D01*
X89000Y1226017D01*
X89250Y1226267D01*
X89417Y1226558D01*
X89500Y1226850D01*
Y1227142D01*
X89417Y1227433D01*
X89292Y1227683D01*
X89125Y1227892D01*
G01X87417Y1229158D02*
X87167Y1229408D01*
X87042Y1229700D01*
X87000Y1230033D01*
X87083Y1230450D01*
X87292Y1230742D01*
X87542Y1230825D01*
X87792Y1230783D01*
X88000Y1230617D01*
X88417Y1229783D01*
X88708Y1229408D01*
X89125Y1229158D01*
X89500Y1229075D01*
Y1230825D01*
G01X89208Y1232342D02*
X89417Y1232633D01*
X89500Y1232967D01*
X89417Y1233300D01*
X89167Y1233592D01*
X88792Y1233800D01*
X88417Y1233883D01*
X87958D01*
X87583Y1233800D01*
X87250Y1233592D01*
X87083Y1233342D01*
X87000Y1233050D01*
X87083Y1232717D01*
X87250Y1232467D01*
X87500Y1232300D01*
X87833Y1232217D01*
X88125Y1232300D01*
X88417Y1232508D01*
X88583Y1232758D01*
X88625Y1233050D01*
X88542Y1233383D01*
X88333Y1233633D01*
X87958Y1233883D01*
G01X87000Y1236150D02*
X87083Y1235817D01*
X87292Y1235567D01*
X87542Y1235400D01*
X87875Y1235275D01*
X88250Y1235233D01*
X88625Y1235275D01*
X88958Y1235400D01*
X89208Y1235567D01*
X89417Y1235817D01*
X89500Y1236150D01*
X89417Y1236483D01*
X89208Y1236733D01*
X88958Y1236900D01*
X88625Y1237025D01*
X88250Y1237067D01*
X87875Y1237025D01*
X87542Y1236900D01*
X87292Y1236733D01*
X87083Y1236483D01*
X87000Y1236150D01*
G01X99499Y1250067D02*
X96999D01*
Y1251108D01*
X97124Y1251442D01*
X97291Y1251650D01*
X97624Y1251733D01*
X97957Y1251650D01*
X98166Y1251400D01*
X98291Y1251108D01*
Y1250067D01*
G01Y1251108D02*
X99499Y1251733D01*
G01X97416Y1253208D02*
X97166Y1253458D01*
X97041Y1253750D01*
X96999Y1254083D01*
X97082Y1254500D01*
X97291Y1254792D01*
X97541Y1254875D01*
X97791Y1254833D01*
X97999Y1254667D01*
X98416Y1253833D01*
X98707Y1253458D01*
X99124Y1253208D01*
X99499Y1253125D01*
Y1254875D01*
G01X98457Y1256308D02*
X98166Y1256600D01*
X97999Y1256850D01*
X97916Y1257183D01*
X97999Y1257475D01*
X98166Y1257683D01*
X98416Y1257850D01*
X98707Y1257892D01*
X98957Y1257850D01*
X99207Y1257683D01*
X99416Y1257433D01*
X99499Y1257142D01*
X99416Y1256808D01*
X99166Y1256517D01*
X98791Y1256350D01*
X98374Y1256308D01*
X97832Y1256392D01*
X97541Y1256517D01*
X97249Y1256725D01*
X97041Y1257017D01*
X96999Y1257308D01*
X97082Y1257600D01*
X97291Y1257808D01*
G01X99499Y1260700D02*
X96999D01*
X98791Y1259158D01*
Y1261242D01*
G01X101999Y1248613D02*
X127999D01*
G01X101999Y1261613D02*
Y1248613D01*
G01X94208Y1268767D02*
X94083Y1268517D01*
X94000Y1268225D01*
Y1267892D01*
X94125Y1267517D01*
X94333Y1267225D01*
X94583Y1267017D01*
X95000Y1266850D01*
X95375Y1266808D01*
X95750Y1266892D01*
X96000Y1267017D01*
X96250Y1267267D01*
X96417Y1267558D01*
X96500Y1267850D01*
Y1268142D01*
X96417Y1268433D01*
X96292Y1268683D01*
X96125Y1268892D01*
G01X94417Y1270158D02*
X94167Y1270408D01*
X94042Y1270700D01*
X94000Y1271033D01*
X94083Y1271450D01*
X94292Y1271742D01*
X94542Y1271825D01*
X94792Y1271783D01*
X95000Y1271617D01*
X95417Y1270783D01*
X95708Y1270408D01*
X96125Y1270158D01*
X96500Y1270075D01*
Y1271825D01*
G01Y1274050D02*
X96458Y1274342D01*
X96333Y1274675D01*
X96125Y1274883D01*
X95833Y1274967D01*
X95542Y1274883D01*
X95292Y1274633D01*
X95167Y1274258D01*
Y1273842D01*
X95083Y1273592D01*
X94875Y1273383D01*
X94583Y1273300D01*
X94292Y1273425D01*
X94083Y1273717D01*
X94000Y1274050D01*
X94083Y1274383D01*
X94292Y1274675D01*
X94583Y1274800D01*
X94875Y1274717D01*
X95083Y1274508D01*
X95167Y1274258D01*
Y1273842D01*
X95292Y1273467D01*
X95542Y1273217D01*
X95833Y1273133D01*
X96125Y1273217D01*
X96333Y1273425D01*
X96458Y1273758D01*
X96500Y1274050D01*
G01Y1277650D02*
X94000D01*
X95792Y1276108D01*
Y1278192D01*
G01X127999Y1261613D02*
X101999D01*
G01X98208Y1268767D02*
X98083Y1268517D01*
X98000Y1268225D01*
Y1267892D01*
X98125Y1267517D01*
X98333Y1267225D01*
X98583Y1267017D01*
X99000Y1266850D01*
X99375Y1266808D01*
X99750Y1266892D01*
X100000Y1267017D01*
X100250Y1267267D01*
X100417Y1267558D01*
X100500Y1267850D01*
Y1268142D01*
X100417Y1268433D01*
X100292Y1268683D01*
X100125Y1268892D01*
G01X98417Y1270158D02*
X98167Y1270408D01*
X98042Y1270700D01*
X98000Y1271033D01*
X98083Y1271450D01*
X98292Y1271742D01*
X98542Y1271825D01*
X98792Y1271783D01*
X99000Y1271617D01*
X99417Y1270783D01*
X99708Y1270408D01*
X100125Y1270158D01*
X100500Y1270075D01*
Y1271825D01*
G01Y1274050D02*
X100458Y1274342D01*
X100333Y1274675D01*
X100125Y1274883D01*
X99833Y1274967D01*
X99542Y1274883D01*
X99292Y1274633D01*
X99167Y1274258D01*
Y1273842D01*
X99083Y1273592D01*
X98875Y1273383D01*
X98583Y1273300D01*
X98292Y1273425D01*
X98083Y1273717D01*
X98000Y1274050D01*
X98083Y1274383D01*
X98292Y1274675D01*
X98583Y1274800D01*
X98875Y1274717D01*
X99083Y1274508D01*
X99167Y1274258D01*
Y1273842D01*
X99292Y1273467D01*
X99542Y1273217D01*
X99833Y1273133D01*
X100125Y1273217D01*
X100333Y1273425D01*
X100458Y1273758D01*
X100500Y1274050D01*
G01X100125Y1276233D02*
X100333Y1276483D01*
X100458Y1276775D01*
X100500Y1277150D01*
X100417Y1277525D01*
X100250Y1277817D01*
X99958Y1278025D01*
X99625Y1278067D01*
X99292Y1277983D01*
X99083Y1277775D01*
X98917Y1277483D01*
X98875Y1277192D01*
X98917Y1276900D01*
X99083Y1276525D01*
X98000Y1276650D01*
Y1277775D01*
G01X93707Y1297380D02*
X93582Y1297130D01*
X93499Y1296838D01*
Y1296505D01*
X93624Y1296130D01*
X93832Y1295838D01*
X94082Y1295630D01*
X94499Y1295463D01*
X94874Y1295421D01*
X95249Y1295505D01*
X95499Y1295630D01*
X95749Y1295880D01*
X95916Y1296171D01*
X95999Y1296463D01*
Y1296755D01*
X95916Y1297046D01*
X95791Y1297296D01*
X95624Y1297505D01*
G01X93916Y1298771D02*
X93666Y1299021D01*
X93541Y1299313D01*
X93499Y1299646D01*
X93582Y1300063D01*
X93791Y1300355D01*
X94041Y1300438D01*
X94291Y1300396D01*
X94499Y1300230D01*
X94916Y1299396D01*
X95207Y1299021D01*
X95624Y1298771D01*
X95999Y1298688D01*
Y1300438D01*
G01Y1302663D02*
X95957Y1302955D01*
X95832Y1303288D01*
X95624Y1303496D01*
X95332Y1303580D01*
X95041Y1303496D01*
X94791Y1303246D01*
X94666Y1302871D01*
Y1302455D01*
X94582Y1302205D01*
X94374Y1301996D01*
X94082Y1301913D01*
X93791Y1302038D01*
X93582Y1302330D01*
X93499Y1302663D01*
X93582Y1302996D01*
X93791Y1303288D01*
X94082Y1303413D01*
X94374Y1303330D01*
X94582Y1303121D01*
X94666Y1302871D01*
Y1302455D01*
X94791Y1302080D01*
X95041Y1301830D01*
X95332Y1301746D01*
X95624Y1301830D01*
X95832Y1302038D01*
X95957Y1302371D01*
X95999Y1302663D01*
G01X94957Y1304971D02*
X94666Y1305263D01*
X94499Y1305513D01*
X94416Y1305846D01*
X94499Y1306138D01*
X94666Y1306346D01*
X94916Y1306513D01*
X95207Y1306555D01*
X95457Y1306513D01*
X95707Y1306346D01*
X95916Y1306096D01*
X95999Y1305805D01*
X95916Y1305471D01*
X95666Y1305180D01*
X95291Y1305013D01*
X94874Y1304971D01*
X94332Y1305055D01*
X94041Y1305180D01*
X93749Y1305388D01*
X93541Y1305680D01*
X93499Y1305971D01*
X93582Y1306263D01*
X93791Y1306471D01*
G01X99500Y1282517D02*
X97000D01*
Y1283558D01*
X97125Y1283892D01*
X97292Y1284100D01*
X97625Y1284183D01*
X97958Y1284100D01*
X98167Y1283850D01*
X98292Y1283558D01*
Y1282517D01*
G01Y1283558D02*
X99500Y1284183D01*
G01X97417Y1285658D02*
X97167Y1285908D01*
X97042Y1286200D01*
X97000Y1286533D01*
X97083Y1286950D01*
X97292Y1287242D01*
X97542Y1287325D01*
X97792Y1287283D01*
X98000Y1287117D01*
X98417Y1286283D01*
X98708Y1285908D01*
X99125Y1285658D01*
X99500Y1285575D01*
Y1287325D01*
G01X98458Y1288758D02*
X98167Y1289050D01*
X98000Y1289300D01*
X97917Y1289633D01*
X98000Y1289925D01*
X98167Y1290133D01*
X98417Y1290300D01*
X98708Y1290342D01*
X98958Y1290300D01*
X99208Y1290133D01*
X99417Y1289883D01*
X99500Y1289592D01*
X99417Y1289258D01*
X99167Y1288967D01*
X98792Y1288800D01*
X98375Y1288758D01*
X97833Y1288842D01*
X97542Y1288967D01*
X97250Y1289175D01*
X97042Y1289467D01*
X97000Y1289758D01*
X97083Y1290050D01*
X97292Y1290258D01*
G01X97000Y1292650D02*
X97083Y1292317D01*
X97292Y1292067D01*
X97542Y1291900D01*
X97875Y1291775D01*
X98250Y1291733D01*
X98625Y1291775D01*
X98958Y1291900D01*
X99208Y1292067D01*
X99417Y1292317D01*
X99500Y1292650D01*
X99417Y1292983D01*
X99208Y1293233D01*
X98958Y1293400D01*
X98625Y1293525D01*
X98250Y1293567D01*
X97875Y1293525D01*
X97542Y1293400D01*
X97292Y1293233D01*
X97083Y1292983D01*
X97000Y1292650D01*
G01X101999Y1282113D02*
X127999D01*
G01X101999Y1295113D02*
Y1282113D01*
G01X127999Y1295113D02*
X101999D01*
G01X99999Y1295567D02*
X97499D01*
Y1296608D01*
X97624Y1296942D01*
X97791Y1297150D01*
X98124Y1297233D01*
X98457Y1297150D01*
X98666Y1296900D01*
X98791Y1296608D01*
Y1295567D01*
G01Y1296608D02*
X99999Y1297233D01*
G01X97916Y1298708D02*
X97666Y1298958D01*
X97541Y1299250D01*
X97499Y1299583D01*
X97582Y1300000D01*
X97791Y1300292D01*
X98041Y1300375D01*
X98291Y1300333D01*
X98499Y1300167D01*
X98916Y1299333D01*
X99207Y1298958D01*
X99624Y1298708D01*
X99999Y1298625D01*
Y1300375D01*
G01X98957Y1301808D02*
X98666Y1302100D01*
X98499Y1302350D01*
X98416Y1302683D01*
X98499Y1302975D01*
X98666Y1303183D01*
X98916Y1303350D01*
X99207Y1303392D01*
X99457Y1303350D01*
X99707Y1303183D01*
X99916Y1302933D01*
X99999Y1302642D01*
X99916Y1302308D01*
X99666Y1302017D01*
X99291Y1301850D01*
X98874Y1301808D01*
X98332Y1301892D01*
X98041Y1302017D01*
X97749Y1302225D01*
X97541Y1302517D01*
X97499Y1302808D01*
X97582Y1303100D01*
X97791Y1303308D01*
G01X99624Y1304783D02*
X99832Y1305033D01*
X99957Y1305325D01*
X99999Y1305700D01*
X99916Y1306075D01*
X99749Y1306367D01*
X99457Y1306575D01*
X99124Y1306617D01*
X98791Y1306533D01*
X98582Y1306325D01*
X98416Y1306033D01*
X98374Y1305742D01*
X98416Y1305450D01*
X98582Y1305075D01*
X97499Y1305200D01*
Y1306325D01*
G01X94708Y1319267D02*
X94583Y1319017D01*
X94500Y1318725D01*
Y1318392D01*
X94625Y1318017D01*
X94833Y1317725D01*
X95083Y1317517D01*
X95500Y1317350D01*
X95875Y1317308D01*
X96250Y1317392D01*
X96500Y1317517D01*
X96750Y1317767D01*
X96917Y1318058D01*
X97000Y1318350D01*
Y1318642D01*
X96917Y1318933D01*
X96792Y1319183D01*
X96625Y1319392D01*
G01X94917Y1320658D02*
X94667Y1320908D01*
X94542Y1321200D01*
X94500Y1321533D01*
X94583Y1321950D01*
X94792Y1322242D01*
X95042Y1322325D01*
X95292Y1322283D01*
X95500Y1322117D01*
X95917Y1321283D01*
X96208Y1320908D01*
X96625Y1320658D01*
X97000Y1320575D01*
Y1322325D01*
G01Y1324550D02*
X96958Y1324842D01*
X96833Y1325175D01*
X96625Y1325383D01*
X96333Y1325467D01*
X96042Y1325383D01*
X95792Y1325133D01*
X95667Y1324758D01*
Y1324342D01*
X95583Y1324092D01*
X95375Y1323883D01*
X95083Y1323800D01*
X94792Y1323925D01*
X94583Y1324217D01*
X94500Y1324550D01*
X94583Y1324883D01*
X94792Y1325175D01*
X95083Y1325300D01*
X95375Y1325217D01*
X95583Y1325008D01*
X95667Y1324758D01*
Y1324342D01*
X95792Y1323967D01*
X96042Y1323717D01*
X96333Y1323633D01*
X96625Y1323717D01*
X96833Y1323925D01*
X96958Y1324258D01*
X97000Y1324550D01*
G01X94500Y1327650D02*
X94583Y1327317D01*
X94792Y1327067D01*
X95042Y1326900D01*
X95375Y1326775D01*
X95750Y1326733D01*
X96125Y1326775D01*
X96458Y1326900D01*
X96708Y1327067D01*
X96917Y1327317D01*
X97000Y1327650D01*
X96917Y1327983D01*
X96708Y1328233D01*
X96458Y1328400D01*
X96125Y1328525D01*
X95750Y1328567D01*
X95375Y1328525D01*
X95042Y1328400D01*
X94792Y1328233D01*
X94583Y1327983D01*
X94500Y1327650D01*
G01X98708Y1319267D02*
X98583Y1319017D01*
X98500Y1318725D01*
Y1318392D01*
X98625Y1318017D01*
X98833Y1317725D01*
X99083Y1317517D01*
X99500Y1317350D01*
X99875Y1317308D01*
X100250Y1317392D01*
X100500Y1317517D01*
X100750Y1317767D01*
X100917Y1318058D01*
X101000Y1318350D01*
Y1318642D01*
X100917Y1318933D01*
X100792Y1319183D01*
X100625Y1319392D01*
G01X98917Y1320658D02*
X98667Y1320908D01*
X98542Y1321200D01*
X98500Y1321533D01*
X98583Y1321950D01*
X98792Y1322242D01*
X99042Y1322325D01*
X99292Y1322283D01*
X99500Y1322117D01*
X99917Y1321283D01*
X100208Y1320908D01*
X100625Y1320658D01*
X101000Y1320575D01*
Y1322325D01*
G01Y1324550D02*
X100958Y1324842D01*
X100833Y1325175D01*
X100625Y1325383D01*
X100333Y1325467D01*
X100042Y1325383D01*
X99792Y1325133D01*
X99667Y1324758D01*
Y1324342D01*
X99583Y1324092D01*
X99375Y1323883D01*
X99083Y1323800D01*
X98792Y1323925D01*
X98583Y1324217D01*
X98500Y1324550D01*
X98583Y1324883D01*
X98792Y1325175D01*
X99083Y1325300D01*
X99375Y1325217D01*
X99583Y1325008D01*
X99667Y1324758D01*
Y1324342D01*
X99792Y1323967D01*
X100042Y1323717D01*
X100333Y1323633D01*
X100625Y1323717D01*
X100833Y1323925D01*
X100958Y1324258D01*
X101000Y1324550D01*
G01Y1327650D02*
X98500D01*
X99000Y1327150D01*
G01X101000D02*
Y1328150D01*
G01X95317Y1352292D02*
X95067Y1352417D01*
X94775Y1352500D01*
X94442D01*
X94067Y1352375D01*
X93775Y1352167D01*
X93567Y1351917D01*
X93400Y1351500D01*
X93358Y1351125D01*
X93442Y1350750D01*
X93567Y1350500D01*
X93817Y1350250D01*
X94108Y1350083D01*
X94400Y1350000D01*
X94692D01*
X94983Y1350083D01*
X95233Y1350208D01*
X95442Y1350375D01*
G01X96583Y1350500D02*
X96833Y1350208D01*
X97167Y1350042D01*
X97542Y1350000D01*
X97875Y1350042D01*
X98208Y1350250D01*
X98417Y1350500D01*
X98458Y1350750D01*
X98375Y1351042D01*
X98083Y1351250D01*
X97792Y1351333D01*
X97417D01*
G01X97792D02*
X98042Y1351458D01*
X98250Y1351667D01*
X98333Y1351917D01*
X98250Y1352167D01*
X98042Y1352375D01*
X97667Y1352500D01*
X97292Y1352458D01*
X96917Y1352292D01*
G01X99892Y1350292D02*
X100183Y1350083D01*
X100517Y1350000D01*
X100850Y1350083D01*
X101142Y1350333D01*
X101350Y1350708D01*
X101433Y1351083D01*
Y1351542D01*
X101350Y1351917D01*
X101142Y1352250D01*
X100892Y1352417D01*
X100600Y1352500D01*
X100267Y1352417D01*
X100017Y1352250D01*
X99850Y1352000D01*
X99767Y1351667D01*
X99850Y1351375D01*
X100058Y1351083D01*
X100308Y1350917D01*
X100600Y1350875D01*
X100933Y1350958D01*
X101183Y1351167D01*
X101433Y1351542D01*
G01X95317Y1348292D02*
X95067Y1348417D01*
X94775Y1348500D01*
X94442D01*
X94067Y1348375D01*
X93775Y1348167D01*
X93567Y1347917D01*
X93400Y1347500D01*
X93358Y1347125D01*
X93442Y1346750D01*
X93567Y1346500D01*
X93817Y1346250D01*
X94108Y1346083D01*
X94400Y1346000D01*
X94692D01*
X94983Y1346083D01*
X95233Y1346208D01*
X95442Y1346375D01*
G01X96583Y1346500D02*
X96833Y1346208D01*
X97167Y1346042D01*
X97542Y1346000D01*
X97875Y1346042D01*
X98208Y1346250D01*
X98417Y1346500D01*
X98458Y1346750D01*
X98375Y1347042D01*
X98083Y1347250D01*
X97792Y1347333D01*
X97417D01*
G01X97792D02*
X98042Y1347458D01*
X98250Y1347667D01*
X98333Y1347917D01*
X98250Y1348167D01*
X98042Y1348375D01*
X97667Y1348500D01*
X97292Y1348458D01*
X96917Y1348292D01*
G01X100600Y1346000D02*
X100892Y1346042D01*
X101225Y1346167D01*
X101433Y1346375D01*
X101517Y1346667D01*
X101433Y1346958D01*
X101183Y1347208D01*
X100808Y1347333D01*
X100392D01*
X100142Y1347417D01*
X99933Y1347625D01*
X99850Y1347917D01*
X99975Y1348208D01*
X100267Y1348417D01*
X100600Y1348500D01*
X100933Y1348417D01*
X101225Y1348208D01*
X101350Y1347917D01*
X101267Y1347625D01*
X101058Y1347417D01*
X100808Y1347333D01*
X100392D01*
X100017Y1347208D01*
X99767Y1346958D01*
X99683Y1346667D01*
X99767Y1346375D01*
X99975Y1346167D01*
X100308Y1346042D01*
X100600Y1346000D01*
G01X101865Y1429550D02*
X111865D01*
G01Y1422550D02*
X101865D01*
G01X106865D02*
Y1429550D01*
G01X101865Y1419117D02*
X111865D01*
Y1415783D01*
X111365Y1414450D01*
X110698Y1413450D01*
X109698Y1412617D01*
X108531Y1411950D01*
X106865Y1411783D01*
X105198Y1411950D01*
X104032Y1412617D01*
X103031Y1413450D01*
X102365Y1414450D01*
X101865Y1415783D01*
Y1419117D01*
G01Y1408517D02*
X111865D01*
Y1405183D01*
X111365Y1403850D01*
X110698Y1402850D01*
X109698Y1402017D01*
X108531Y1401350D01*
X106865Y1401183D01*
X105198Y1401350D01*
X104032Y1402017D01*
X103031Y1402850D01*
X102365Y1403850D01*
X101865Y1405183D01*
Y1408517D01*
G01Y1394250D02*
X111865D01*
X109865Y1396250D01*
G01X101865D02*
Y1392250D01*
G01Y1383650D02*
X111865D01*
X109865Y1385650D01*
G01X101865D02*
Y1381650D01*
G01X97266Y1371342D02*
X97016Y1371467D01*
X96724Y1371550D01*
X96391D01*
X96016Y1371425D01*
X95724Y1371217D01*
X95516Y1370967D01*
X95349Y1370550D01*
X95307Y1370175D01*
X95391Y1369800D01*
X95516Y1369550D01*
X95766Y1369300D01*
X96057Y1369133D01*
X96349Y1369050D01*
X96641D01*
X96932Y1369133D01*
X97182Y1369258D01*
X97391Y1369425D01*
G01X98657Y1371133D02*
X98907Y1371383D01*
X99199Y1371508D01*
X99532Y1371550D01*
X99949Y1371467D01*
X100241Y1371258D01*
X100324Y1371008D01*
X100282Y1370758D01*
X100116Y1370550D01*
X99282Y1370133D01*
X98907Y1369842D01*
X98657Y1369425D01*
X98574Y1369050D01*
X100324D01*
G01X102466D02*
X102549Y1369592D01*
X102674Y1370050D01*
X102841Y1370467D01*
X103049Y1370925D01*
X103382Y1371550D01*
X101716D01*
G01X105649Y1369050D02*
X105941Y1369092D01*
X106274Y1369217D01*
X106482Y1369425D01*
X106566Y1369717D01*
X106482Y1370008D01*
X106232Y1370258D01*
X105857Y1370383D01*
X105441D01*
X105191Y1370467D01*
X104982Y1370675D01*
X104899Y1370967D01*
X105024Y1371258D01*
X105316Y1371467D01*
X105649Y1371550D01*
X105982Y1371467D01*
X106274Y1371258D01*
X106399Y1370967D01*
X106316Y1370675D01*
X106107Y1370467D01*
X105857Y1370383D01*
X105441D01*
X105066Y1370258D01*
X104816Y1370008D01*
X104732Y1369717D01*
X104816Y1369425D01*
X105024Y1369217D01*
X105357Y1369092D01*
X105649Y1369050D01*
G01X97595Y1367244D02*
X97345Y1367369D01*
X97053Y1367452D01*
X96720D01*
X96345Y1367327D01*
X96053Y1367119D01*
X95845Y1366869D01*
X95678Y1366452D01*
X95636Y1366077D01*
X95720Y1365702D01*
X95845Y1365452D01*
X96095Y1365202D01*
X96386Y1365035D01*
X96678Y1364952D01*
X96970D01*
X97261Y1365035D01*
X97511Y1365160D01*
X97720Y1365327D01*
G01X98986Y1367035D02*
X99236Y1367285D01*
X99528Y1367410D01*
X99861Y1367452D01*
X100278Y1367369D01*
X100570Y1367160D01*
X100653Y1366910D01*
X100611Y1366660D01*
X100445Y1366452D01*
X99611Y1366035D01*
X99236Y1365744D01*
X98986Y1365327D01*
X98903Y1364952D01*
X100653D01*
G01X102795D02*
X102878Y1365494D01*
X103003Y1365952D01*
X103170Y1366369D01*
X103378Y1366827D01*
X103711Y1367452D01*
X102045D01*
G01X105270Y1365244D02*
X105561Y1365035D01*
X105895Y1364952D01*
X106228Y1365035D01*
X106520Y1365285D01*
X106728Y1365660D01*
X106811Y1366035D01*
Y1366494D01*
X106728Y1366869D01*
X106520Y1367202D01*
X106270Y1367369D01*
X105978Y1367452D01*
X105645Y1367369D01*
X105395Y1367202D01*
X105228Y1366952D01*
X105145Y1366619D01*
X105228Y1366327D01*
X105436Y1366035D01*
X105686Y1365869D01*
X105978Y1365827D01*
X106311Y1365910D01*
X106561Y1366119D01*
X106811Y1366494D01*
G01X104999Y1452317D02*
X102499D01*
Y1453358D01*
X102624Y1453692D01*
X102791Y1453900D01*
X103124Y1453983D01*
X103457Y1453900D01*
X103666Y1453650D01*
X103791Y1453358D01*
Y1452317D01*
G01Y1453358D02*
X104999Y1453983D01*
G01X104499Y1455333D02*
X104791Y1455583D01*
X104957Y1455917D01*
X104999Y1456292D01*
X104957Y1456625D01*
X104749Y1456958D01*
X104499Y1457167D01*
X104249Y1457208D01*
X103957Y1457125D01*
X103749Y1456833D01*
X103666Y1456542D01*
Y1456167D01*
G01Y1456542D02*
X103541Y1456792D01*
X103332Y1457000D01*
X103082Y1457083D01*
X102832Y1457000D01*
X102624Y1456792D01*
X102499Y1456417D01*
X102541Y1456042D01*
X102707Y1455667D01*
G01X104999Y1459350D02*
X102499D01*
X102999Y1458850D01*
G01X104999D02*
Y1459850D01*
G01Y1462450D02*
X102499D01*
X102999Y1461950D01*
G01X104999D02*
Y1462950D01*
G01X101999Y1466600D02*
X105999D01*
Y1474000D01*
G01X93499Y1460067D02*
X90999D01*
Y1461108D01*
X91124Y1461442D01*
X91291Y1461650D01*
X91624Y1461733D01*
X91957Y1461650D01*
X92166Y1461400D01*
X92291Y1461108D01*
Y1460067D01*
G01Y1461108D02*
X93499Y1461733D01*
G01X92999Y1463083D02*
X93291Y1463333D01*
X93457Y1463667D01*
X93499Y1464042D01*
X93457Y1464375D01*
X93249Y1464708D01*
X92999Y1464917D01*
X92749Y1464958D01*
X92457Y1464875D01*
X92249Y1464583D01*
X92166Y1464292D01*
Y1463917D01*
G01Y1464292D02*
X92041Y1464542D01*
X91832Y1464750D01*
X91582Y1464833D01*
X91332Y1464750D01*
X91124Y1464542D01*
X90999Y1464167D01*
X91041Y1463792D01*
X91207Y1463417D01*
G01X91416Y1466308D02*
X91166Y1466558D01*
X91041Y1466850D01*
X90999Y1467183D01*
X91082Y1467600D01*
X91291Y1467892D01*
X91541Y1467975D01*
X91791Y1467933D01*
X91999Y1467767D01*
X92416Y1466933D01*
X92707Y1466558D01*
X93124Y1466308D01*
X93499Y1466225D01*
Y1467975D01*
G01X90999Y1470200D02*
X91082Y1469867D01*
X91291Y1469617D01*
X91541Y1469450D01*
X91874Y1469325D01*
X92249Y1469283D01*
X92624Y1469325D01*
X92957Y1469450D01*
X93207Y1469617D01*
X93416Y1469867D01*
X93499Y1470200D01*
X93416Y1470533D01*
X93207Y1470783D01*
X92957Y1470950D01*
X92624Y1471075D01*
X92249Y1471117D01*
X91874Y1471075D01*
X91541Y1470950D01*
X91291Y1470783D01*
X91082Y1470533D01*
X90999Y1470200D01*
G01X97499Y1460067D02*
X94999D01*
Y1461108D01*
X95124Y1461442D01*
X95291Y1461650D01*
X95624Y1461733D01*
X95957Y1461650D01*
X96166Y1461400D01*
X96291Y1461108D01*
Y1460067D01*
G01Y1461108D02*
X97499Y1461733D01*
G01X96999Y1463083D02*
X97291Y1463333D01*
X97457Y1463667D01*
X97499Y1464042D01*
X97457Y1464375D01*
X97249Y1464708D01*
X96999Y1464917D01*
X96749Y1464958D01*
X96457Y1464875D01*
X96249Y1464583D01*
X96166Y1464292D01*
Y1463917D01*
G01Y1464292D02*
X96041Y1464542D01*
X95832Y1464750D01*
X95582Y1464833D01*
X95332Y1464750D01*
X95124Y1464542D01*
X94999Y1464167D01*
X95041Y1463792D01*
X95207Y1463417D01*
G01X95416Y1466308D02*
X95166Y1466558D01*
X95041Y1466850D01*
X94999Y1467183D01*
X95082Y1467600D01*
X95291Y1467892D01*
X95541Y1467975D01*
X95791Y1467933D01*
X95999Y1467767D01*
X96416Y1466933D01*
X96707Y1466558D01*
X97124Y1466308D01*
X97499Y1466225D01*
Y1467975D01*
G01Y1470200D02*
X94999D01*
X95499Y1469700D01*
G01X97499D02*
Y1470700D01*
G01X105949Y1474050D02*
Y1478050D01*
X98549D01*
G01X92883Y1507063D02*
Y1505271D01*
X93050Y1504896D01*
X93383Y1504646D01*
X93800Y1504563D01*
X94217Y1504646D01*
X94550Y1504896D01*
X94717Y1505271D01*
Y1507063D01*
G01X97400Y1504563D02*
Y1507063D01*
X95858Y1505271D01*
X97942D01*
G01X99208Y1505605D02*
X99500Y1505896D01*
X99750Y1506063D01*
X100083Y1506146D01*
X100375Y1506063D01*
X100583Y1505896D01*
X100750Y1505646D01*
X100792Y1505355D01*
X100750Y1505105D01*
X100583Y1504855D01*
X100333Y1504646D01*
X100042Y1504563D01*
X99708Y1504646D01*
X99417Y1504896D01*
X99250Y1505271D01*
X99208Y1505688D01*
X99292Y1506230D01*
X99417Y1506521D01*
X99625Y1506813D01*
X99917Y1507021D01*
X100208Y1507063D01*
X100500Y1506980D01*
X100708Y1506771D01*
G01X98399Y1516350D02*
Y1513850D01*
G01X97441Y1516350D02*
X99357D01*
G01X100666Y1513850D02*
Y1516350D01*
X101666D01*
X101999Y1516225D01*
X102249Y1515933D01*
X102332Y1515600D01*
X102249Y1515267D01*
X102041Y1515017D01*
X101666Y1514892D01*
X100666D01*
G01X104599Y1513850D02*
Y1516350D01*
X104099Y1515850D01*
G01Y1513850D02*
X105099D01*
G01X97017Y1552000D02*
Y1554500D01*
X98058D01*
X98392Y1554375D01*
X98600Y1554208D01*
X98683Y1553875D01*
X98600Y1553542D01*
X98350Y1553333D01*
X98058Y1553208D01*
X97017D01*
G01X98058D02*
X98683Y1552000D01*
G01X100033Y1552375D02*
X100283Y1552167D01*
X100575Y1552042D01*
X100950Y1552000D01*
X101325Y1552083D01*
X101617Y1552250D01*
X101825Y1552542D01*
X101867Y1552875D01*
X101783Y1553208D01*
X101575Y1553417D01*
X101283Y1553583D01*
X100992Y1553625D01*
X100700Y1553583D01*
X100325Y1553417D01*
X100450Y1554500D01*
X101575D01*
G01X104050Y1552000D02*
Y1554500D01*
X103550Y1554000D01*
G01Y1552000D02*
X104550D01*
G01X107150Y1554500D02*
X106817Y1554417D01*
X106567Y1554208D01*
X106400Y1553958D01*
X106275Y1553625D01*
X106233Y1553250D01*
X106275Y1552875D01*
X106400Y1552542D01*
X106567Y1552292D01*
X106817Y1552083D01*
X107150Y1552000D01*
X107483Y1552083D01*
X107733Y1552292D01*
X107900Y1552542D01*
X108025Y1552875D01*
X108067Y1553250D01*
X108025Y1553625D01*
X107900Y1553958D01*
X107733Y1554208D01*
X107483Y1554417D01*
X107150Y1554500D01*
G01X87300Y1555500D02*
Y1551500D01*
X94700D01*
G01X85000Y1533517D02*
X82500D01*
Y1534558D01*
X82625Y1534892D01*
X82792Y1535100D01*
X83125Y1535183D01*
X83458Y1535100D01*
X83667Y1534850D01*
X83792Y1534558D01*
Y1533517D01*
G01Y1534558D02*
X85000Y1535183D01*
G01X84625Y1536533D02*
X84833Y1536783D01*
X84958Y1537075D01*
X85000Y1537450D01*
X84917Y1537825D01*
X84750Y1538117D01*
X84458Y1538325D01*
X84125Y1538367D01*
X83792Y1538283D01*
X83583Y1538075D01*
X83417Y1537783D01*
X83375Y1537492D01*
X83417Y1537200D01*
X83583Y1536825D01*
X82500Y1536950D01*
Y1538075D01*
G01Y1540550D02*
X82583Y1540217D01*
X82792Y1539967D01*
X83042Y1539800D01*
X83375Y1539675D01*
X83750Y1539633D01*
X84125Y1539675D01*
X84458Y1539800D01*
X84708Y1539967D01*
X84917Y1540217D01*
X85000Y1540550D01*
X84917Y1540883D01*
X84708Y1541133D01*
X84458Y1541300D01*
X84125Y1541425D01*
X83750Y1541467D01*
X83375Y1541425D01*
X83042Y1541300D01*
X82792Y1541133D01*
X82583Y1540883D01*
X82500Y1540550D01*
G01X84708Y1542942D02*
X84917Y1543233D01*
X85000Y1543567D01*
X84917Y1543900D01*
X84667Y1544192D01*
X84292Y1544400D01*
X83917Y1544483D01*
X83458D01*
X83083Y1544400D01*
X82750Y1544192D01*
X82583Y1543942D01*
X82500Y1543650D01*
X82583Y1543317D01*
X82750Y1543067D01*
X83000Y1542900D01*
X83333Y1542817D01*
X83625Y1542900D01*
X83917Y1543108D01*
X84083Y1543358D01*
X84125Y1543650D01*
X84042Y1543983D01*
X83833Y1544233D01*
X83458Y1544483D01*
G01X97017Y1556000D02*
Y1558500D01*
X98058D01*
X98392Y1558375D01*
X98600Y1558208D01*
X98683Y1557875D01*
X98600Y1557542D01*
X98350Y1557333D01*
X98058Y1557208D01*
X97017D01*
G01X98058D02*
X98683Y1556000D01*
G01X100033Y1556375D02*
X100283Y1556167D01*
X100575Y1556042D01*
X100950Y1556000D01*
X101325Y1556083D01*
X101617Y1556250D01*
X101825Y1556542D01*
X101867Y1556875D01*
X101783Y1557208D01*
X101575Y1557417D01*
X101283Y1557583D01*
X100992Y1557625D01*
X100700Y1557583D01*
X100325Y1557417D01*
X100450Y1558500D01*
X101575D01*
G01X104050Y1556000D02*
Y1558500D01*
X103550Y1558000D01*
G01Y1556000D02*
X104550D01*
G01X107150D02*
Y1558500D01*
X106650Y1558000D01*
G01Y1556000D02*
X107650D01*
G01X87300Y1559500D02*
Y1555500D01*
X94700D01*
G01X92500Y1565600D02*
Y1604400D01*
G01X115500Y1565600D02*
X92500D01*
G01X83300Y1587000D02*
Y1569400D01*
G01X91300D02*
Y1587000D01*
G01X83300Y1569400D02*
X91300D01*
G01X88500Y1590017D02*
X86000D01*
Y1591058D01*
X86125Y1591392D01*
X86292Y1591600D01*
X86625Y1591683D01*
X86958Y1591600D01*
X87167Y1591350D01*
X87292Y1591058D01*
Y1590017D01*
G01Y1591058D02*
X88500Y1591683D01*
G01X88125Y1593033D02*
X88333Y1593283D01*
X88458Y1593575D01*
X88500Y1593950D01*
X88417Y1594325D01*
X88250Y1594617D01*
X87958Y1594825D01*
X87625Y1594867D01*
X87292Y1594783D01*
X87083Y1594575D01*
X86917Y1594283D01*
X86875Y1593992D01*
X86917Y1593700D01*
X87083Y1593325D01*
X86000Y1593450D01*
Y1594575D01*
G01X88500Y1597550D02*
X86000D01*
X87792Y1596008D01*
Y1598092D01*
G01X86417Y1599358D02*
X86167Y1599608D01*
X86042Y1599900D01*
X86000Y1600233D01*
X86083Y1600650D01*
X86292Y1600942D01*
X86542Y1601025D01*
X86792Y1600983D01*
X87000Y1600817D01*
X87417Y1599983D01*
X87708Y1599608D01*
X88125Y1599358D01*
X88500Y1599275D01*
Y1601025D01*
G01X91300Y1587000D02*
X83300D01*
G01X95999Y1617900D02*
X98499D01*
G01X95999Y1616942D02*
Y1618858D01*
G01X98499Y1620167D02*
X95999D01*
Y1621167D01*
X96124Y1621500D01*
X96416Y1621750D01*
X96749Y1621833D01*
X97082Y1621750D01*
X97332Y1621542D01*
X97457Y1621167D01*
Y1620167D01*
G01X97999Y1623183D02*
X98291Y1623433D01*
X98457Y1623767D01*
X98499Y1624142D01*
X98457Y1624475D01*
X98249Y1624808D01*
X97999Y1625017D01*
X97749Y1625058D01*
X97457Y1624975D01*
X97249Y1624683D01*
X97166Y1624392D01*
Y1624017D01*
G01Y1624392D02*
X97041Y1624642D01*
X96832Y1624850D01*
X96582Y1624933D01*
X96332Y1624850D01*
X96124Y1624642D01*
X95999Y1624267D01*
X96041Y1623892D01*
X96207Y1623517D01*
G01X98124Y1626283D02*
X98332Y1626533D01*
X98457Y1626825D01*
X98499Y1627200D01*
X98416Y1627575D01*
X98249Y1627867D01*
X97957Y1628075D01*
X97624Y1628117D01*
X97291Y1628033D01*
X97082Y1627825D01*
X96916Y1627533D01*
X96874Y1627242D01*
X96916Y1626950D01*
X97082Y1626575D01*
X95999Y1626700D01*
Y1627825D01*
G01X100608Y1606500D02*
Y1609000D01*
X102192D01*
G01X101608Y1607792D02*
X100608D01*
G01X103583Y1607000D02*
X103833Y1606708D01*
X104167Y1606542D01*
X104542Y1606500D01*
X104875Y1606542D01*
X105208Y1606750D01*
X105417Y1607000D01*
X105458Y1607250D01*
X105375Y1607542D01*
X105083Y1607750D01*
X104792Y1607833D01*
X104417D01*
G01X104792D02*
X105042Y1607958D01*
X105250Y1608167D01*
X105333Y1608417D01*
X105250Y1608667D01*
X105042Y1608875D01*
X104667Y1609000D01*
X104292Y1608958D01*
X103917Y1608792D01*
G01X107600Y1606500D02*
Y1609000D01*
X107100Y1608500D01*
G01Y1606500D02*
X108100D01*
G01X92500Y1604400D02*
X115500D01*
G01X95308Y1638204D02*
X95183Y1637954D01*
X95100Y1637662D01*
Y1637329D01*
X95225Y1636954D01*
X95433Y1636662D01*
X95683Y1636454D01*
X96100Y1636287D01*
X96475Y1636245D01*
X96850Y1636329D01*
X97100Y1636454D01*
X97350Y1636704D01*
X97517Y1636995D01*
X97600Y1637287D01*
Y1637579D01*
X97517Y1637870D01*
X97392Y1638120D01*
X97225Y1638329D01*
G01X95517Y1639595D02*
X95267Y1639845D01*
X95142Y1640137D01*
X95100Y1640470D01*
X95183Y1640887D01*
X95392Y1641179D01*
X95642Y1641262D01*
X95892Y1641220D01*
X96100Y1641054D01*
X96517Y1640220D01*
X96808Y1639845D01*
X97225Y1639595D01*
X97600Y1639512D01*
Y1641262D01*
G01Y1643404D02*
X97058Y1643487D01*
X96600Y1643612D01*
X96183Y1643779D01*
X95725Y1643987D01*
X95100Y1644320D01*
Y1642654D01*
G01X95517Y1645795D02*
X95267Y1646045D01*
X95142Y1646337D01*
X95100Y1646670D01*
X95183Y1647087D01*
X95392Y1647379D01*
X95642Y1647462D01*
X95892Y1647420D01*
X96100Y1647254D01*
X96517Y1646420D01*
X96808Y1646045D01*
X97225Y1645795D01*
X97600Y1645712D01*
Y1647462D01*
G01X100499Y1654067D02*
X97999D01*
Y1655108D01*
X98124Y1655442D01*
X98291Y1655650D01*
X98624Y1655733D01*
X98957Y1655650D01*
X99166Y1655400D01*
X99291Y1655108D01*
Y1654067D01*
G01Y1655108D02*
X100499Y1655733D01*
G01X98416Y1657208D02*
X98166Y1657458D01*
X98041Y1657750D01*
X97999Y1658083D01*
X98082Y1658500D01*
X98291Y1658792D01*
X98541Y1658875D01*
X98791Y1658833D01*
X98999Y1658667D01*
X99416Y1657833D01*
X99707Y1657458D01*
X100124Y1657208D01*
X100499Y1657125D01*
Y1658875D01*
G01X100124Y1660183D02*
X100332Y1660433D01*
X100457Y1660725D01*
X100499Y1661100D01*
X100416Y1661475D01*
X100249Y1661767D01*
X99957Y1661975D01*
X99624Y1662017D01*
X99291Y1661933D01*
X99082Y1661725D01*
X98916Y1661433D01*
X98874Y1661142D01*
X98916Y1660850D01*
X99082Y1660475D01*
X97999Y1660600D01*
Y1661725D01*
G01Y1664200D02*
X98082Y1663867D01*
X98291Y1663617D01*
X98541Y1663450D01*
X98874Y1663325D01*
X99249Y1663283D01*
X99624Y1663325D01*
X99957Y1663450D01*
X100207Y1663617D01*
X100416Y1663867D01*
X100499Y1664200D01*
X100416Y1664533D01*
X100207Y1664783D01*
X99957Y1664950D01*
X99624Y1665075D01*
X99249Y1665117D01*
X98874Y1665075D01*
X98541Y1664950D01*
X98291Y1664783D01*
X98082Y1664533D01*
X97999Y1664200D01*
G01X102999Y1653113D02*
X128999D01*
G01X102999Y1666113D02*
Y1653113D01*
G01X94207Y1670380D02*
X94082Y1670130D01*
X93999Y1669838D01*
Y1669505D01*
X94124Y1669130D01*
X94332Y1668838D01*
X94582Y1668630D01*
X94999Y1668463D01*
X95374Y1668421D01*
X95749Y1668505D01*
X95999Y1668630D01*
X96249Y1668880D01*
X96416Y1669171D01*
X96499Y1669463D01*
Y1669755D01*
X96416Y1670046D01*
X96291Y1670296D01*
X96124Y1670505D01*
G01X94416Y1671771D02*
X94166Y1672021D01*
X94041Y1672313D01*
X93999Y1672646D01*
X94082Y1673063D01*
X94291Y1673355D01*
X94541Y1673438D01*
X94791Y1673396D01*
X94999Y1673230D01*
X95416Y1672396D01*
X95707Y1672021D01*
X96124Y1671771D01*
X96499Y1671688D01*
Y1673438D01*
G01X95457Y1674871D02*
X95166Y1675163D01*
X94999Y1675413D01*
X94916Y1675746D01*
X94999Y1676038D01*
X95166Y1676246D01*
X95416Y1676413D01*
X95707Y1676455D01*
X95957Y1676413D01*
X96207Y1676246D01*
X96416Y1675996D01*
X96499Y1675705D01*
X96416Y1675371D01*
X96166Y1675080D01*
X95791Y1674913D01*
X95374Y1674871D01*
X94832Y1674955D01*
X94541Y1675080D01*
X94249Y1675288D01*
X94041Y1675580D01*
X93999Y1675871D01*
X94082Y1676163D01*
X94291Y1676371D01*
G01X95457Y1677971D02*
X95166Y1678263D01*
X94999Y1678513D01*
X94916Y1678846D01*
X94999Y1679138D01*
X95166Y1679346D01*
X95416Y1679513D01*
X95707Y1679555D01*
X95957Y1679513D01*
X96207Y1679346D01*
X96416Y1679096D01*
X96499Y1678805D01*
X96416Y1678471D01*
X96166Y1678180D01*
X95791Y1678013D01*
X95374Y1677971D01*
X94832Y1678055D01*
X94541Y1678180D01*
X94249Y1678388D01*
X94041Y1678680D01*
X93999Y1678971D01*
X94082Y1679263D01*
X94291Y1679471D01*
G01X128999Y1666113D02*
X102999D01*
G01X98708Y1670767D02*
X98583Y1670517D01*
X98500Y1670225D01*
Y1669892D01*
X98625Y1669517D01*
X98833Y1669225D01*
X99083Y1669017D01*
X99500Y1668850D01*
X99875Y1668808D01*
X100250Y1668892D01*
X100500Y1669017D01*
X100750Y1669267D01*
X100917Y1669558D01*
X101000Y1669850D01*
Y1670142D01*
X100917Y1670433D01*
X100792Y1670683D01*
X100625Y1670892D01*
G01X98917Y1672158D02*
X98667Y1672408D01*
X98542Y1672700D01*
X98500Y1673033D01*
X98583Y1673450D01*
X98792Y1673742D01*
X99042Y1673825D01*
X99292Y1673783D01*
X99500Y1673617D01*
X99917Y1672783D01*
X100208Y1672408D01*
X100625Y1672158D01*
X101000Y1672075D01*
Y1673825D01*
G01X99958Y1675258D02*
X99667Y1675550D01*
X99500Y1675800D01*
X99417Y1676133D01*
X99500Y1676425D01*
X99667Y1676633D01*
X99917Y1676800D01*
X100208Y1676842D01*
X100458Y1676800D01*
X100708Y1676633D01*
X100917Y1676383D01*
X101000Y1676092D01*
X100917Y1675758D01*
X100667Y1675467D01*
X100292Y1675300D01*
X99875Y1675258D01*
X99333Y1675342D01*
X99042Y1675467D01*
X98750Y1675675D01*
X98542Y1675967D01*
X98500Y1676258D01*
X98583Y1676550D01*
X98792Y1676758D01*
G01X101000Y1679067D02*
X100458Y1679150D01*
X100000Y1679275D01*
X99583Y1679442D01*
X99125Y1679650D01*
X98500Y1679983D01*
Y1678317D01*
G01X94938Y1697445D02*
X94813Y1697195D01*
X94730Y1696903D01*
Y1696570D01*
X94855Y1696195D01*
X95063Y1695903D01*
X95313Y1695695D01*
X95730Y1695528D01*
X96105Y1695486D01*
X96480Y1695570D01*
X96730Y1695695D01*
X96980Y1695945D01*
X97147Y1696236D01*
X97230Y1696528D01*
Y1696820D01*
X97147Y1697111D01*
X97022Y1697361D01*
X96855Y1697570D01*
G01X95147Y1698836D02*
X94897Y1699086D01*
X94772Y1699378D01*
X94730Y1699711D01*
X94813Y1700128D01*
X95022Y1700420D01*
X95272Y1700503D01*
X95522Y1700461D01*
X95730Y1700295D01*
X96147Y1699461D01*
X96438Y1699086D01*
X96855Y1698836D01*
X97230Y1698753D01*
Y1700503D01*
G01Y1702645D02*
X96688Y1702728D01*
X96230Y1702853D01*
X95813Y1703020D01*
X95355Y1703228D01*
X94730Y1703561D01*
Y1701895D01*
G01Y1705828D02*
X94813Y1705495D01*
X95022Y1705245D01*
X95272Y1705078D01*
X95605Y1704953D01*
X95980Y1704911D01*
X96355Y1704953D01*
X96688Y1705078D01*
X96938Y1705245D01*
X97147Y1705495D01*
X97230Y1705828D01*
X97147Y1706161D01*
X96938Y1706411D01*
X96688Y1706578D01*
X96355Y1706703D01*
X95980Y1706745D01*
X95605Y1706703D01*
X95272Y1706578D01*
X95022Y1706411D01*
X94813Y1706161D01*
X94730Y1705828D01*
G01X99000Y1682517D02*
X96500D01*
Y1683558D01*
X96625Y1683892D01*
X96792Y1684100D01*
X97125Y1684183D01*
X97458Y1684100D01*
X97667Y1683850D01*
X97792Y1683558D01*
Y1682517D01*
G01Y1683558D02*
X99000Y1684183D01*
G01X96917Y1685658D02*
X96667Y1685908D01*
X96542Y1686200D01*
X96500Y1686533D01*
X96583Y1686950D01*
X96792Y1687242D01*
X97042Y1687325D01*
X97292Y1687283D01*
X97500Y1687117D01*
X97917Y1686283D01*
X98208Y1685908D01*
X98625Y1685658D01*
X99000Y1685575D01*
Y1687325D01*
G01Y1690050D02*
X96500D01*
X98292Y1688508D01*
Y1690592D01*
G01X98625Y1691733D02*
X98833Y1691983D01*
X98958Y1692275D01*
X99000Y1692650D01*
X98917Y1693025D01*
X98750Y1693317D01*
X98458Y1693525D01*
X98125Y1693567D01*
X97792Y1693483D01*
X97583Y1693275D01*
X97417Y1692983D01*
X97375Y1692692D01*
X97417Y1692400D01*
X97583Y1692025D01*
X96500Y1692150D01*
Y1693275D01*
G01X103499Y1686613D02*
X129499D01*
G01X103499Y1699613D02*
Y1686613D01*
G01X129499Y1699613D02*
X103499D01*
G01X101230Y1695758D02*
X98730D01*
Y1696799D01*
X98855Y1697133D01*
X99022Y1697341D01*
X99355Y1697424D01*
X99688Y1697341D01*
X99897Y1697091D01*
X100022Y1696799D01*
Y1695758D01*
G01Y1696799D02*
X101230Y1697424D01*
G01X99147Y1698899D02*
X98897Y1699149D01*
X98772Y1699441D01*
X98730Y1699774D01*
X98813Y1700191D01*
X99022Y1700483D01*
X99272Y1700566D01*
X99522Y1700524D01*
X99730Y1700358D01*
X100147Y1699524D01*
X100438Y1699149D01*
X100855Y1698899D01*
X101230Y1698816D01*
Y1700566D01*
G01X100855Y1701874D02*
X101063Y1702124D01*
X101188Y1702416D01*
X101230Y1702791D01*
X101147Y1703166D01*
X100980Y1703458D01*
X100688Y1703666D01*
X100355Y1703708D01*
X100022Y1703624D01*
X99813Y1703416D01*
X99647Y1703124D01*
X99605Y1702833D01*
X99647Y1702541D01*
X99813Y1702166D01*
X98730Y1702291D01*
Y1703416D01*
G01X101230Y1705891D02*
X98730D01*
X99230Y1705391D01*
G01X101230D02*
Y1706391D01*
G01X94443Y1709154D02*
Y1711654D01*
X95484D01*
X95818Y1711529D01*
X96026Y1711362D01*
X96109Y1711029D01*
X96026Y1710696D01*
X95776Y1710487D01*
X95484Y1710362D01*
X94443D01*
G01X95484D02*
X96109Y1709154D01*
G01X97584Y1711237D02*
X97834Y1711487D01*
X98126Y1711612D01*
X98459Y1711654D01*
X98876Y1711571D01*
X99168Y1711362D01*
X99251Y1711112D01*
X99209Y1710862D01*
X99043Y1710654D01*
X98209Y1710237D01*
X97834Y1709946D01*
X97584Y1709529D01*
X97501Y1709154D01*
X99251D01*
G01X101976D02*
Y1711654D01*
X100434Y1709862D01*
X102518D01*
G01X103784Y1710196D02*
X104076Y1710487D01*
X104326Y1710654D01*
X104659Y1710737D01*
X104951Y1710654D01*
X105159Y1710487D01*
X105326Y1710237D01*
X105368Y1709946D01*
X105326Y1709696D01*
X105159Y1709446D01*
X104909Y1709237D01*
X104618Y1709154D01*
X104284Y1709237D01*
X103993Y1709487D01*
X103826Y1709862D01*
X103784Y1710279D01*
X103868Y1710821D01*
X103993Y1711112D01*
X104201Y1711404D01*
X104493Y1711612D01*
X104784Y1711654D01*
X105076Y1711571D01*
X105284Y1711362D01*
G01X95379Y1725641D02*
Y1728141D01*
X96420D01*
X96754Y1728016D01*
X96962Y1727849D01*
X97045Y1727516D01*
X96962Y1727183D01*
X96712Y1726974D01*
X96420Y1726849D01*
X95379D01*
G01X96420D02*
X97045Y1725641D01*
G01X99812D02*
Y1728141D01*
X98270Y1726349D01*
X100354D01*
G01X101620Y1726683D02*
X101912Y1726974D01*
X102162Y1727141D01*
X102495Y1727224D01*
X102787Y1727141D01*
X102995Y1726974D01*
X103162Y1726724D01*
X103204Y1726433D01*
X103162Y1726183D01*
X102995Y1725933D01*
X102745Y1725724D01*
X102454Y1725641D01*
X102120Y1725724D01*
X101829Y1725974D01*
X101662Y1726349D01*
X101620Y1726766D01*
X101704Y1727308D01*
X101829Y1727599D01*
X102037Y1727891D01*
X102329Y1728099D01*
X102620Y1728141D01*
X102912Y1728058D01*
X103120Y1727849D01*
G01X105512Y1728141D02*
X105179Y1728058D01*
X104929Y1727849D01*
X104762Y1727599D01*
X104637Y1727266D01*
X104595Y1726891D01*
X104637Y1726516D01*
X104762Y1726183D01*
X104929Y1725933D01*
X105179Y1725724D01*
X105512Y1725641D01*
X105845Y1725724D01*
X106095Y1725933D01*
X106262Y1726183D01*
X106387Y1726516D01*
X106429Y1726891D01*
X106387Y1727266D01*
X106262Y1727599D01*
X106095Y1727849D01*
X105845Y1728058D01*
X105512Y1728141D01*
G01X95379Y1729641D02*
Y1732141D01*
X96420D01*
X96754Y1732016D01*
X96962Y1731849D01*
X97045Y1731516D01*
X96962Y1731183D01*
X96712Y1730974D01*
X96420Y1730849D01*
X95379D01*
G01X96420D02*
X97045Y1729641D01*
G01X99812D02*
Y1732141D01*
X98270Y1730349D01*
X100354D01*
G01X101620Y1730683D02*
X101912Y1730974D01*
X102162Y1731141D01*
X102495Y1731224D01*
X102787Y1731141D01*
X102995Y1730974D01*
X103162Y1730724D01*
X103204Y1730433D01*
X103162Y1730183D01*
X102995Y1729933D01*
X102745Y1729724D01*
X102454Y1729641D01*
X102120Y1729724D01*
X101829Y1729974D01*
X101662Y1730349D01*
X101620Y1730766D01*
X101704Y1731308D01*
X101829Y1731599D01*
X102037Y1731891D01*
X102329Y1732099D01*
X102620Y1732141D01*
X102912Y1732058D01*
X103120Y1731849D01*
G01X105512Y1729641D02*
Y1732141D01*
X105012Y1731641D01*
G01Y1729641D02*
X106012D01*
G01X102766Y1760842D02*
X102516Y1760967D01*
X102224Y1761050D01*
X101891D01*
X101516Y1760925D01*
X101224Y1760717D01*
X101016Y1760467D01*
X100849Y1760050D01*
X100807Y1759675D01*
X100891Y1759300D01*
X101016Y1759050D01*
X101266Y1758800D01*
X101557Y1758633D01*
X101849Y1758550D01*
X102141D01*
X102432Y1758633D01*
X102682Y1758758D01*
X102891Y1758925D01*
G01X104157Y1760633D02*
X104407Y1760883D01*
X104699Y1761008D01*
X105032Y1761050D01*
X105449Y1760967D01*
X105741Y1760758D01*
X105824Y1760508D01*
X105782Y1760258D01*
X105616Y1760050D01*
X104782Y1759633D01*
X104407Y1759342D01*
X104157Y1758925D01*
X104074Y1758550D01*
X105824D01*
G01X107257Y1759592D02*
X107549Y1759883D01*
X107799Y1760050D01*
X108132Y1760133D01*
X108424Y1760050D01*
X108632Y1759883D01*
X108799Y1759633D01*
X108841Y1759342D01*
X108799Y1759092D01*
X108632Y1758842D01*
X108382Y1758633D01*
X108091Y1758550D01*
X107757Y1758633D01*
X107466Y1758883D01*
X107299Y1759258D01*
X107257Y1759675D01*
X107341Y1760217D01*
X107466Y1760508D01*
X107674Y1760800D01*
X107966Y1761008D01*
X108257Y1761050D01*
X108549Y1760967D01*
X108757Y1760758D01*
G01X110357Y1760633D02*
X110607Y1760883D01*
X110899Y1761008D01*
X111232Y1761050D01*
X111649Y1760967D01*
X111941Y1760758D01*
X112024Y1760508D01*
X111982Y1760258D01*
X111816Y1760050D01*
X110982Y1759633D01*
X110607Y1759342D01*
X110357Y1758925D01*
X110274Y1758550D01*
X112024D01*
G01X102266Y1756842D02*
X102016Y1756967D01*
X101724Y1757050D01*
X101391D01*
X101016Y1756925D01*
X100724Y1756717D01*
X100516Y1756467D01*
X100349Y1756050D01*
X100307Y1755675D01*
X100391Y1755300D01*
X100516Y1755050D01*
X100766Y1754800D01*
X101057Y1754633D01*
X101349Y1754550D01*
X101641D01*
X101932Y1754633D01*
X102182Y1754758D01*
X102391Y1754925D01*
G01X103657Y1756633D02*
X103907Y1756883D01*
X104199Y1757008D01*
X104532Y1757050D01*
X104949Y1756967D01*
X105241Y1756758D01*
X105324Y1756508D01*
X105282Y1756258D01*
X105116Y1756050D01*
X104282Y1755633D01*
X103907Y1755342D01*
X103657Y1754925D01*
X103574Y1754550D01*
X105324D01*
G01X106757Y1755592D02*
X107049Y1755883D01*
X107299Y1756050D01*
X107632Y1756133D01*
X107924Y1756050D01*
X108132Y1755883D01*
X108299Y1755633D01*
X108341Y1755342D01*
X108299Y1755092D01*
X108132Y1754842D01*
X107882Y1754633D01*
X107591Y1754550D01*
X107257Y1754633D01*
X106966Y1754883D01*
X106799Y1755258D01*
X106757Y1755675D01*
X106841Y1756217D01*
X106966Y1756508D01*
X107174Y1756800D01*
X107466Y1757008D01*
X107757Y1757050D01*
X108049Y1756967D01*
X108257Y1756758D01*
G01X109732Y1755050D02*
X109982Y1754758D01*
X110316Y1754592D01*
X110691Y1754550D01*
X111024Y1754592D01*
X111357Y1754800D01*
X111566Y1755050D01*
X111607Y1755300D01*
X111524Y1755592D01*
X111232Y1755800D01*
X110941Y1755883D01*
X110566D01*
G01X110941D02*
X111191Y1756008D01*
X111399Y1756217D01*
X111482Y1756467D01*
X111399Y1756717D01*
X111191Y1756925D01*
X110816Y1757050D01*
X110441Y1757008D01*
X110066Y1756842D01*
G01X98766Y1751342D02*
X98516Y1751467D01*
X98224Y1751550D01*
X97891D01*
X97516Y1751425D01*
X97224Y1751217D01*
X97016Y1750967D01*
X96849Y1750550D01*
X96807Y1750175D01*
X96891Y1749800D01*
X97016Y1749550D01*
X97266Y1749300D01*
X97557Y1749133D01*
X97849Y1749050D01*
X98141D01*
X98432Y1749133D01*
X98682Y1749258D01*
X98891Y1749425D01*
G01X100157Y1751133D02*
X100407Y1751383D01*
X100699Y1751508D01*
X101032Y1751550D01*
X101449Y1751467D01*
X101741Y1751258D01*
X101824Y1751008D01*
X101782Y1750758D01*
X101616Y1750550D01*
X100782Y1750133D01*
X100407Y1749842D01*
X100157Y1749425D01*
X100074Y1749050D01*
X101824D01*
G01X103257Y1750092D02*
X103549Y1750383D01*
X103799Y1750550D01*
X104132Y1750633D01*
X104424Y1750550D01*
X104632Y1750383D01*
X104799Y1750133D01*
X104841Y1749842D01*
X104799Y1749592D01*
X104632Y1749342D01*
X104382Y1749133D01*
X104091Y1749050D01*
X103757Y1749133D01*
X103466Y1749383D01*
X103299Y1749758D01*
X103257Y1750175D01*
X103341Y1750717D01*
X103466Y1751008D01*
X103674Y1751300D01*
X103966Y1751508D01*
X104257Y1751550D01*
X104549Y1751467D01*
X104757Y1751258D01*
G01X107649Y1749050D02*
Y1751550D01*
X106107Y1749758D01*
X108191D01*
G01X98766Y1747842D02*
X98516Y1747967D01*
X98224Y1748050D01*
X97891D01*
X97516Y1747925D01*
X97224Y1747717D01*
X97016Y1747467D01*
X96849Y1747050D01*
X96807Y1746675D01*
X96891Y1746300D01*
X97016Y1746050D01*
X97266Y1745800D01*
X97557Y1745633D01*
X97849Y1745550D01*
X98141D01*
X98432Y1745633D01*
X98682Y1745758D01*
X98891Y1745925D01*
G01X100157Y1747633D02*
X100407Y1747883D01*
X100699Y1748008D01*
X101032Y1748050D01*
X101449Y1747967D01*
X101741Y1747758D01*
X101824Y1747508D01*
X101782Y1747258D01*
X101616Y1747050D01*
X100782Y1746633D01*
X100407Y1746342D01*
X100157Y1745925D01*
X100074Y1745550D01*
X101824D01*
G01X103257Y1746592D02*
X103549Y1746883D01*
X103799Y1747050D01*
X104132Y1747133D01*
X104424Y1747050D01*
X104632Y1746883D01*
X104799Y1746633D01*
X104841Y1746342D01*
X104799Y1746092D01*
X104632Y1745842D01*
X104382Y1745633D01*
X104091Y1745550D01*
X103757Y1745633D01*
X103466Y1745883D01*
X103299Y1746258D01*
X103257Y1746675D01*
X103341Y1747217D01*
X103466Y1747508D01*
X103674Y1747800D01*
X103966Y1748008D01*
X104257Y1748050D01*
X104549Y1747967D01*
X104757Y1747758D01*
G01X106232Y1745925D02*
X106482Y1745717D01*
X106774Y1745592D01*
X107149Y1745550D01*
X107524Y1745633D01*
X107816Y1745800D01*
X108024Y1746092D01*
X108066Y1746425D01*
X107982Y1746758D01*
X107774Y1746967D01*
X107482Y1747133D01*
X107191Y1747175D01*
X106899Y1747133D01*
X106524Y1746967D01*
X106649Y1748050D01*
X107774D01*
G01X98299Y1822450D02*
X108299D01*
G01Y1815450D02*
X98299D01*
G01X103299D02*
Y1822450D01*
G01X98299Y1812017D02*
X108299D01*
Y1808683D01*
X107799Y1807350D01*
X107132Y1806350D01*
X106132Y1805517D01*
X104965Y1804850D01*
X103299Y1804683D01*
X101632Y1804850D01*
X100466Y1805517D01*
X99465Y1806350D01*
X98799Y1807350D01*
X98299Y1808683D01*
Y1812017D01*
G01Y1801417D02*
X108299D01*
Y1798083D01*
X107799Y1796750D01*
X107132Y1795750D01*
X106132Y1794917D01*
X104965Y1794250D01*
X103299Y1794083D01*
X101632Y1794250D01*
X100466Y1794917D01*
X99465Y1795750D01*
X98799Y1796750D01*
X98299Y1798083D01*
Y1801417D01*
G01Y1787150D02*
X108299D01*
X106299Y1789150D01*
G01X98299D02*
Y1785150D01*
G01X108299Y1776550D02*
X107966Y1777884D01*
X107132Y1778883D01*
X106132Y1779550D01*
X104799Y1780050D01*
X103299Y1780217D01*
X101799Y1780050D01*
X100466Y1779550D01*
X99465Y1778883D01*
X98632Y1777884D01*
X98299Y1776550D01*
X98632Y1775217D01*
X99465Y1774217D01*
X100466Y1773550D01*
X101799Y1773050D01*
X103299Y1772883D01*
X104799Y1773050D01*
X106132Y1773550D01*
X107132Y1774217D01*
X107966Y1775217D01*
X108299Y1776550D01*
G01X94266Y1827113D02*
Y1829613D01*
X95307D01*
X95641Y1829488D01*
X95849Y1829321D01*
X95932Y1828988D01*
X95849Y1828655D01*
X95599Y1828446D01*
X95307Y1828321D01*
X94266D01*
G01X95307D02*
X95932Y1827113D01*
G01X97407Y1829196D02*
X97657Y1829446D01*
X97949Y1829571D01*
X98282Y1829613D01*
X98699Y1829530D01*
X98991Y1829321D01*
X99074Y1829071D01*
X99032Y1828821D01*
X98866Y1828613D01*
X98032Y1828196D01*
X97657Y1827905D01*
X97407Y1827488D01*
X97324Y1827113D01*
X99074D01*
G01X101799D02*
Y1829613D01*
X100257Y1827821D01*
X102341D01*
G01X104399Y1827113D02*
Y1829613D01*
X103899Y1829113D01*
G01Y1827113D02*
X104899D01*
G01X93173Y1839449D02*
Y1841949D01*
X94214D01*
X94548Y1841824D01*
X94756Y1841657D01*
X94839Y1841324D01*
X94756Y1840991D01*
X94506Y1840782D01*
X94214Y1840657D01*
X93173D01*
G01X94214D02*
X94839Y1839449D01*
G01X96314Y1841532D02*
X96564Y1841782D01*
X96856Y1841907D01*
X97189Y1841949D01*
X97606Y1841866D01*
X97898Y1841657D01*
X97981Y1841407D01*
X97939Y1841157D01*
X97773Y1840949D01*
X96939Y1840532D01*
X96564Y1840241D01*
X96314Y1839824D01*
X96231Y1839449D01*
X97981D01*
G01X100706D02*
Y1841949D01*
X99164Y1840157D01*
X101248D01*
G01X103306Y1841949D02*
X102973Y1841866D01*
X102723Y1841657D01*
X102556Y1841407D01*
X102431Y1841074D01*
X102389Y1840699D01*
X102431Y1840324D01*
X102556Y1839991D01*
X102723Y1839741D01*
X102973Y1839532D01*
X103306Y1839449D01*
X103639Y1839532D01*
X103889Y1839741D01*
X104056Y1839991D01*
X104181Y1840324D01*
X104223Y1840699D01*
X104181Y1841074D01*
X104056Y1841407D01*
X103889Y1841657D01*
X103639Y1841866D01*
X103306Y1841949D01*
G01X88376Y1846973D02*
Y1849473D01*
X89417D01*
X89751Y1849348D01*
X89959Y1849181D01*
X90042Y1848848D01*
X89959Y1848515D01*
X89709Y1848306D01*
X89417Y1848181D01*
X88376D01*
G01X89417D02*
X90042Y1846973D01*
G01X91517Y1849056D02*
X91767Y1849306D01*
X92059Y1849431D01*
X92392Y1849473D01*
X92809Y1849390D01*
X93101Y1849181D01*
X93184Y1848931D01*
X93142Y1848681D01*
X92976Y1848473D01*
X92142Y1848056D01*
X91767Y1847765D01*
X91517Y1847348D01*
X91434Y1846973D01*
X93184D01*
G01X95909D02*
Y1849473D01*
X94367Y1847681D01*
X96451D01*
G01X97717Y1849056D02*
X97967Y1849306D01*
X98259Y1849431D01*
X98592Y1849473D01*
X99009Y1849390D01*
X99301Y1849181D01*
X99384Y1848931D01*
X99342Y1848681D01*
X99176Y1848473D01*
X98342Y1848056D01*
X97967Y1847765D01*
X97717Y1847348D01*
X97634Y1846973D01*
X99384D01*
G01X94266Y1831113D02*
Y1833613D01*
X95307D01*
X95641Y1833488D01*
X95849Y1833321D01*
X95932Y1832988D01*
X95849Y1832655D01*
X95599Y1832446D01*
X95307Y1832321D01*
X94266D01*
G01X95307D02*
X95932Y1831113D01*
G01X97407Y1833196D02*
X97657Y1833446D01*
X97949Y1833571D01*
X98282Y1833613D01*
X98699Y1833530D01*
X98991Y1833321D01*
X99074Y1833071D01*
X99032Y1832821D01*
X98866Y1832613D01*
X98032Y1832196D01*
X97657Y1831905D01*
X97407Y1831488D01*
X97324Y1831113D01*
X99074D01*
G01X101799D02*
Y1833613D01*
X100257Y1831821D01*
X102341D01*
G01X103482Y1831613D02*
X103732Y1831321D01*
X104066Y1831155D01*
X104441Y1831113D01*
X104774Y1831155D01*
X105107Y1831363D01*
X105316Y1831613D01*
X105357Y1831863D01*
X105274Y1832155D01*
X104982Y1832363D01*
X104691Y1832446D01*
X104316D01*
G01X104691D02*
X104941Y1832571D01*
X105149Y1832780D01*
X105232Y1833030D01*
X105149Y1833280D01*
X104941Y1833488D01*
X104566Y1833613D01*
X104191Y1833571D01*
X103816Y1833405D01*
G01X88126Y1850910D02*
Y1853410D01*
X89167D01*
X89501Y1853285D01*
X89709Y1853118D01*
X89792Y1852785D01*
X89709Y1852452D01*
X89459Y1852243D01*
X89167Y1852118D01*
X88126D01*
G01X89167D02*
X89792Y1850910D01*
G01X91267Y1852993D02*
X91517Y1853243D01*
X91809Y1853368D01*
X92142Y1853410D01*
X92559Y1853327D01*
X92851Y1853118D01*
X92934Y1852868D01*
X92892Y1852618D01*
X92726Y1852410D01*
X91892Y1851993D01*
X91517Y1851702D01*
X91267Y1851285D01*
X91184Y1850910D01*
X92934D01*
G01X95659D02*
Y1853410D01*
X94117Y1851618D01*
X96201D01*
G01X98759Y1850910D02*
Y1853410D01*
X97217Y1851618D01*
X99301D01*
G01X84299Y1861050D02*
X95499D01*
G01X84299Y1879050D02*
Y1861050D01*
G01X95499Y1879050D02*
X84299D01*
G01Y1881550D02*
X95499D01*
G01X84299Y1899550D02*
Y1881550D01*
G01X95499Y1899550D02*
X84299D01*
G01X124799Y1969150D02*
X102199D01*
G01Y1958950D02*
X124799D01*
G01X102199Y1969150D02*
Y1958950D01*
G01X124799Y1969150D02*
X102199D01*
G01Y1958950D02*
X124799D01*
G01X102199Y1969150D02*
Y1958950D01*
G01X94000Y1978017D02*
X91500D01*
Y1979017D01*
X91625Y1979350D01*
X91917Y1979600D01*
X92250Y1979683D01*
X92583Y1979600D01*
X92833Y1979392D01*
X92958Y1979017D01*
Y1978017D01*
G01X91708Y1982867D02*
X91583Y1982617D01*
X91500Y1982325D01*
Y1981992D01*
X91625Y1981617D01*
X91833Y1981325D01*
X92083Y1981117D01*
X92500Y1980950D01*
X92875Y1980908D01*
X93250Y1980992D01*
X93500Y1981117D01*
X93750Y1981367D01*
X93917Y1981658D01*
X94000Y1981950D01*
Y1982242D01*
X93917Y1982533D01*
X93792Y1982783D01*
X93625Y1982992D01*
G01X91917Y1984258D02*
X91667Y1984508D01*
X91542Y1984800D01*
X91500Y1985133D01*
X91583Y1985550D01*
X91792Y1985842D01*
X92042Y1985925D01*
X92292Y1985883D01*
X92500Y1985717D01*
X92917Y1984883D01*
X93208Y1984508D01*
X93625Y1984258D01*
X94000Y1984175D01*
Y1985925D01*
G01Y1988067D02*
X93458Y1988150D01*
X93000Y1988275D01*
X92583Y1988442D01*
X92125Y1988650D01*
X91500Y1988983D01*
Y1987317D01*
G01X164699Y96650D02*
X123299D01*
Y46450D01*
X164699D01*
Y96650D01*
G01X110748Y87339D02*
Y89839D01*
X111748D01*
X112081Y89714D01*
X112331Y89422D01*
X112414Y89089D01*
X112331Y88756D01*
X112123Y88506D01*
X111748Y88381D01*
X110748D01*
G01X113848Y89839D02*
Y87339D01*
X115514D01*
G01X118281D02*
Y89839D01*
X116739Y88047D01*
X118823D01*
G01X124521Y100877D02*
X142521D01*
G01X124521Y112077D02*
Y100877D01*
G01Y128077D02*
Y139277D01*
G01D02*
X142521D01*
G01X115266Y225342D02*
X115016Y225467D01*
X114724Y225550D01*
X114391D01*
X114016Y225425D01*
X113724Y225217D01*
X113516Y224967D01*
X113349Y224550D01*
X113307Y224175D01*
X113391Y223800D01*
X113516Y223550D01*
X113766Y223300D01*
X114057Y223133D01*
X114349Y223050D01*
X114641D01*
X114932Y223133D01*
X115182Y223258D01*
X115391Y223425D01*
G01X116657Y225133D02*
X116907Y225383D01*
X117199Y225508D01*
X117532Y225550D01*
X117949Y225467D01*
X118241Y225258D01*
X118324Y225008D01*
X118282Y224758D01*
X118116Y224550D01*
X117282Y224133D01*
X116907Y223842D01*
X116657Y223425D01*
X116574Y223050D01*
X118324D01*
G01X121049D02*
Y225550D01*
X119507Y223758D01*
X121591D01*
G01X122857Y224092D02*
X123149Y224383D01*
X123399Y224550D01*
X123732Y224633D01*
X124024Y224550D01*
X124232Y224383D01*
X124399Y224133D01*
X124441Y223842D01*
X124399Y223592D01*
X124232Y223342D01*
X123982Y223133D01*
X123691Y223050D01*
X123357Y223133D01*
X123066Y223383D01*
X122899Y223758D01*
X122857Y224175D01*
X122941Y224717D01*
X123066Y225008D01*
X123274Y225300D01*
X123566Y225508D01*
X123857Y225550D01*
X124149Y225467D01*
X124357Y225258D01*
G01X115266Y228842D02*
X115016Y228967D01*
X114724Y229050D01*
X114391D01*
X114016Y228925D01*
X113724Y228717D01*
X113516Y228467D01*
X113349Y228050D01*
X113307Y227675D01*
X113391Y227300D01*
X113516Y227050D01*
X113766Y226800D01*
X114057Y226633D01*
X114349Y226550D01*
X114641D01*
X114932Y226633D01*
X115182Y226758D01*
X115391Y226925D01*
G01X116657Y228633D02*
X116907Y228883D01*
X117199Y229008D01*
X117532Y229050D01*
X117949Y228967D01*
X118241Y228758D01*
X118324Y228508D01*
X118282Y228258D01*
X118116Y228050D01*
X117282Y227633D01*
X116907Y227342D01*
X116657Y226925D01*
X116574Y226550D01*
X118324D01*
G01X121049D02*
Y229050D01*
X119507Y227258D01*
X121591D01*
G01X123566Y226550D02*
X123649Y227092D01*
X123774Y227550D01*
X123941Y227967D01*
X124149Y228425D01*
X124482Y229050D01*
X122816D01*
G01X115266Y250842D02*
X115016Y250967D01*
X114724Y251050D01*
X114391D01*
X114016Y250925D01*
X113724Y250717D01*
X113516Y250467D01*
X113349Y250050D01*
X113307Y249675D01*
X113391Y249300D01*
X113516Y249050D01*
X113766Y248800D01*
X114057Y248633D01*
X114349Y248550D01*
X114641D01*
X114932Y248633D01*
X115182Y248758D01*
X115391Y248925D01*
G01X116657Y250633D02*
X116907Y250883D01*
X117199Y251008D01*
X117532Y251050D01*
X117949Y250967D01*
X118241Y250758D01*
X118324Y250508D01*
X118282Y250258D01*
X118116Y250050D01*
X117282Y249633D01*
X116907Y249342D01*
X116657Y248925D01*
X116574Y248550D01*
X118324D01*
G01X121049D02*
Y251050D01*
X119507Y249258D01*
X121591D01*
G01X123649Y248550D02*
X123941Y248592D01*
X124274Y248717D01*
X124482Y248925D01*
X124566Y249217D01*
X124482Y249508D01*
X124232Y249758D01*
X123857Y249883D01*
X123441D01*
X123191Y249967D01*
X122982Y250175D01*
X122899Y250467D01*
X123024Y250758D01*
X123316Y250967D01*
X123649Y251050D01*
X123982Y250967D01*
X124274Y250758D01*
X124399Y250467D01*
X124316Y250175D01*
X124107Y249967D01*
X123857Y249883D01*
X123441D01*
X123066Y249758D01*
X122816Y249508D01*
X122732Y249217D01*
X122816Y248925D01*
X123024Y248717D01*
X123357Y248592D01*
X123649Y248550D01*
G01X115266Y254342D02*
X115016Y254467D01*
X114724Y254550D01*
X114391D01*
X114016Y254425D01*
X113724Y254217D01*
X113516Y253967D01*
X113349Y253550D01*
X113307Y253175D01*
X113391Y252800D01*
X113516Y252550D01*
X113766Y252300D01*
X114057Y252133D01*
X114349Y252050D01*
X114641D01*
X114932Y252133D01*
X115182Y252258D01*
X115391Y252425D01*
G01X116657Y254133D02*
X116907Y254383D01*
X117199Y254508D01*
X117532Y254550D01*
X117949Y254467D01*
X118241Y254258D01*
X118324Y254008D01*
X118282Y253758D01*
X118116Y253550D01*
X117282Y253133D01*
X116907Y252842D01*
X116657Y252425D01*
X116574Y252050D01*
X118324D01*
G01X121049D02*
Y254550D01*
X119507Y252758D01*
X121591D01*
G01X122941Y252342D02*
X123232Y252133D01*
X123566Y252050D01*
X123899Y252133D01*
X124191Y252383D01*
X124399Y252758D01*
X124482Y253133D01*
Y253592D01*
X124399Y253967D01*
X124191Y254300D01*
X123941Y254467D01*
X123649Y254550D01*
X123316Y254467D01*
X123066Y254300D01*
X122899Y254050D01*
X122816Y253717D01*
X122899Y253425D01*
X123107Y253133D01*
X123357Y252967D01*
X123649Y252925D01*
X123982Y253008D01*
X124232Y253217D01*
X124482Y253592D01*
G01X118516Y420613D02*
Y423113D01*
X119557D01*
X119891Y422988D01*
X120099Y422821D01*
X120182Y422488D01*
X120099Y422155D01*
X119849Y421946D01*
X119557Y421821D01*
X118516D01*
G01X119557D02*
X120182Y420613D01*
G01X122949D02*
Y423113D01*
X121407Y421321D01*
X123491D01*
G01X125466Y420613D02*
X125549Y421155D01*
X125674Y421613D01*
X125841Y422030D01*
X126049Y422488D01*
X126382Y423113D01*
X124716D01*
G01X127857Y422696D02*
X128107Y422946D01*
X128399Y423071D01*
X128732Y423113D01*
X129149Y423030D01*
X129441Y422821D01*
X129524Y422571D01*
X129482Y422321D01*
X129316Y422113D01*
X128482Y421696D01*
X128107Y421405D01*
X127857Y420988D01*
X127774Y420613D01*
X129524D01*
G01X118516Y424613D02*
Y427113D01*
X119557D01*
X119891Y426988D01*
X120099Y426821D01*
X120182Y426488D01*
X120099Y426155D01*
X119849Y425946D01*
X119557Y425821D01*
X118516D01*
G01X119557D02*
X120182Y424613D01*
G01X122949D02*
Y427113D01*
X121407Y425321D01*
X123491D01*
G01X125466Y424613D02*
X125549Y425155D01*
X125674Y425613D01*
X125841Y426030D01*
X126049Y426488D01*
X126382Y427113D01*
X124716D01*
G01X127732Y425113D02*
X127982Y424821D01*
X128316Y424655D01*
X128691Y424613D01*
X129024Y424655D01*
X129357Y424863D01*
X129566Y425113D01*
X129607Y425363D01*
X129524Y425655D01*
X129232Y425863D01*
X128941Y425946D01*
X128566D01*
G01X128941D02*
X129191Y426071D01*
X129399Y426280D01*
X129482Y426530D01*
X129399Y426780D01*
X129191Y426988D01*
X128816Y427113D01*
X128441Y427071D01*
X128066Y426905D01*
G01X120767Y439292D02*
X120517Y439417D01*
X120225Y439500D01*
X119892D01*
X119517Y439375D01*
X119225Y439167D01*
X119017Y438917D01*
X118850Y438500D01*
X118808Y438125D01*
X118892Y437750D01*
X119017Y437500D01*
X119267Y437250D01*
X119558Y437083D01*
X119850Y437000D01*
X120142D01*
X120433Y437083D01*
X120683Y437208D01*
X120892Y437375D01*
G01X122033Y437500D02*
X122283Y437208D01*
X122617Y437042D01*
X122992Y437000D01*
X123325Y437042D01*
X123658Y437250D01*
X123867Y437500D01*
X123908Y437750D01*
X123825Y438042D01*
X123533Y438250D01*
X123242Y438333D01*
X122867D01*
G01X123242D02*
X123492Y438458D01*
X123700Y438667D01*
X123783Y438917D01*
X123700Y439167D01*
X123492Y439375D01*
X123117Y439500D01*
X122742Y439458D01*
X122367Y439292D01*
G01X126050Y437000D02*
Y439500D01*
X125550Y439000D01*
G01Y437000D02*
X126550D01*
G01X128233Y437375D02*
X128483Y437167D01*
X128775Y437042D01*
X129150Y437000D01*
X129525Y437083D01*
X129817Y437250D01*
X130025Y437542D01*
X130067Y437875D01*
X129983Y438208D01*
X129775Y438417D01*
X129483Y438583D01*
X129192Y438625D01*
X128900Y438583D01*
X128525Y438417D01*
X128650Y439500D01*
X129775D01*
G01X110708Y453767D02*
X110583Y453517D01*
X110500Y453225D01*
Y452892D01*
X110625Y452517D01*
X110833Y452225D01*
X111083Y452017D01*
X111500Y451850D01*
X111875Y451808D01*
X112250Y451892D01*
X112500Y452017D01*
X112750Y452267D01*
X112917Y452558D01*
X113000Y452850D01*
Y453142D01*
X112917Y453433D01*
X112792Y453683D01*
X112625Y453892D01*
G01X112500Y455033D02*
X112792Y455283D01*
X112958Y455617D01*
X113000Y455992D01*
X112958Y456325D01*
X112750Y456658D01*
X112500Y456867D01*
X112250Y456908D01*
X111958Y456825D01*
X111750Y456533D01*
X111667Y456242D01*
Y455867D01*
G01Y456242D02*
X111542Y456492D01*
X111333Y456700D01*
X111083Y456783D01*
X110833Y456700D01*
X110625Y456492D01*
X110500Y456117D01*
X110542Y455742D01*
X110708Y455367D01*
G01X110917Y458258D02*
X110667Y458508D01*
X110542Y458800D01*
X110500Y459133D01*
X110583Y459550D01*
X110792Y459842D01*
X111042Y459925D01*
X111292Y459883D01*
X111500Y459717D01*
X111917Y458883D01*
X112208Y458508D01*
X112625Y458258D01*
X113000Y458175D01*
Y459925D01*
G01X110917Y461358D02*
X110667Y461608D01*
X110542Y461900D01*
X110500Y462233D01*
X110583Y462650D01*
X110792Y462942D01*
X111042Y463025D01*
X111292Y462983D01*
X111500Y462817D01*
X111917Y461983D01*
X112208Y461608D01*
X112625Y461358D01*
X113000Y461275D01*
Y463025D01*
G01X124208Y453767D02*
X124083Y453517D01*
X124000Y453225D01*
Y452892D01*
X124125Y452517D01*
X124333Y452225D01*
X124583Y452017D01*
X125000Y451850D01*
X125375Y451808D01*
X125750Y451892D01*
X126000Y452017D01*
X126250Y452267D01*
X126417Y452558D01*
X126500Y452850D01*
Y453142D01*
X126417Y453433D01*
X126292Y453683D01*
X126125Y453892D01*
G01X126000Y455033D02*
X126292Y455283D01*
X126458Y455617D01*
X126500Y455992D01*
X126458Y456325D01*
X126250Y456658D01*
X126000Y456867D01*
X125750Y456908D01*
X125458Y456825D01*
X125250Y456533D01*
X125167Y456242D01*
Y455867D01*
G01Y456242D02*
X125042Y456492D01*
X124833Y456700D01*
X124583Y456783D01*
X124333Y456700D01*
X124125Y456492D01*
X124000Y456117D01*
X124042Y455742D01*
X124208Y455367D01*
G01X126500Y459050D02*
X124000D01*
X124500Y458550D01*
G01X126500D02*
Y459550D01*
G01Y462150D02*
X126458Y462442D01*
X126333Y462775D01*
X126125Y462983D01*
X125833Y463067D01*
X125542Y462983D01*
X125292Y462733D01*
X125167Y462358D01*
Y461942D01*
X125083Y461692D01*
X124875Y461483D01*
X124583Y461400D01*
X124292Y461525D01*
X124083Y461817D01*
X124000Y462150D01*
X124083Y462483D01*
X124292Y462775D01*
X124583Y462900D01*
X124875Y462817D01*
X125083Y462608D01*
X125167Y462358D01*
Y461942D01*
X125292Y461567D01*
X125542Y461317D01*
X125833Y461233D01*
X126125Y461317D01*
X126333Y461525D01*
X126458Y461858D01*
X126500Y462150D01*
G01X119708Y453767D02*
X119583Y453517D01*
X119500Y453225D01*
Y452892D01*
X119625Y452517D01*
X119833Y452225D01*
X120083Y452017D01*
X120500Y451850D01*
X120875Y451808D01*
X121250Y451892D01*
X121500Y452017D01*
X121750Y452267D01*
X121917Y452558D01*
X122000Y452850D01*
Y453142D01*
X121917Y453433D01*
X121792Y453683D01*
X121625Y453892D01*
G01X121500Y455033D02*
X121792Y455283D01*
X121958Y455617D01*
X122000Y455992D01*
X121958Y456325D01*
X121750Y456658D01*
X121500Y456867D01*
X121250Y456908D01*
X120958Y456825D01*
X120750Y456533D01*
X120667Y456242D01*
Y455867D01*
G01Y456242D02*
X120542Y456492D01*
X120333Y456700D01*
X120083Y456783D01*
X119833Y456700D01*
X119625Y456492D01*
X119500Y456117D01*
X119542Y455742D01*
X119708Y455367D01*
G01X122000Y459050D02*
X119500D01*
X120000Y458550D01*
G01X122000D02*
Y459550D01*
G01X121708Y461442D02*
X121917Y461733D01*
X122000Y462067D01*
X121917Y462400D01*
X121667Y462692D01*
X121292Y462900D01*
X120917Y462983D01*
X120458D01*
X120083Y462900D01*
X119750Y462692D01*
X119583Y462442D01*
X119500Y462150D01*
X119583Y461817D01*
X119750Y461567D01*
X120000Y461400D01*
X120333Y461317D01*
X120625Y461400D01*
X120917Y461608D01*
X121083Y461858D01*
X121125Y462150D01*
X121042Y462483D01*
X120833Y462733D01*
X120458Y462983D01*
G01X115208Y453767D02*
X115083Y453517D01*
X115000Y453225D01*
Y452892D01*
X115125Y452517D01*
X115333Y452225D01*
X115583Y452017D01*
X116000Y451850D01*
X116375Y451808D01*
X116750Y451892D01*
X117000Y452017D01*
X117250Y452267D01*
X117417Y452558D01*
X117500Y452850D01*
Y453142D01*
X117417Y453433D01*
X117292Y453683D01*
X117125Y453892D01*
G01X117000Y455033D02*
X117292Y455283D01*
X117458Y455617D01*
X117500Y455992D01*
X117458Y456325D01*
X117250Y456658D01*
X117000Y456867D01*
X116750Y456908D01*
X116458Y456825D01*
X116250Y456533D01*
X116167Y456242D01*
Y455867D01*
G01Y456242D02*
X116042Y456492D01*
X115833Y456700D01*
X115583Y456783D01*
X115333Y456700D01*
X115125Y456492D01*
X115000Y456117D01*
X115042Y455742D01*
X115208Y455367D01*
G01X115417Y458258D02*
X115167Y458508D01*
X115042Y458800D01*
X115000Y459133D01*
X115083Y459550D01*
X115292Y459842D01*
X115542Y459925D01*
X115792Y459883D01*
X116000Y459717D01*
X116417Y458883D01*
X116708Y458508D01*
X117125Y458258D01*
X117500Y458175D01*
Y459925D01*
G01X115000Y462150D02*
X115083Y461817D01*
X115292Y461567D01*
X115542Y461400D01*
X115875Y461275D01*
X116250Y461233D01*
X116625Y461275D01*
X116958Y461400D01*
X117208Y461567D01*
X117417Y461817D01*
X117500Y462150D01*
X117417Y462483D01*
X117208Y462733D01*
X116958Y462900D01*
X116625Y463025D01*
X116250Y463067D01*
X115875Y463025D01*
X115542Y462900D01*
X115292Y462733D01*
X115083Y462483D01*
X115000Y462150D01*
G01X124017Y469500D02*
Y472000D01*
X125058D01*
X125392Y471875D01*
X125600Y471708D01*
X125683Y471375D01*
X125600Y471042D01*
X125350Y470833D01*
X125058Y470708D01*
X124017D01*
G01X125058D02*
X125683Y469500D01*
G01X127158Y471583D02*
X127408Y471833D01*
X127700Y471958D01*
X128033Y472000D01*
X128450Y471917D01*
X128742Y471708D01*
X128825Y471458D01*
X128783Y471208D01*
X128617Y471000D01*
X127783Y470583D01*
X127408Y470292D01*
X127158Y469875D01*
X127075Y469500D01*
X128825D01*
G01X130342Y469792D02*
X130633Y469583D01*
X130967Y469500D01*
X131300Y469583D01*
X131592Y469833D01*
X131800Y470208D01*
X131883Y470583D01*
Y471042D01*
X131800Y471417D01*
X131592Y471750D01*
X131342Y471917D01*
X131050Y472000D01*
X130717Y471917D01*
X130467Y471750D01*
X130300Y471500D01*
X130217Y471167D01*
X130300Y470875D01*
X130508Y470583D01*
X130758Y470417D01*
X131050Y470375D01*
X131383Y470458D01*
X131633Y470667D01*
X131883Y471042D01*
G01X133358Y471583D02*
X133608Y471833D01*
X133900Y471958D01*
X134233Y472000D01*
X134650Y471917D01*
X134942Y471708D01*
X135025Y471458D01*
X134983Y471208D01*
X134817Y471000D01*
X133983Y470583D01*
X133608Y470292D01*
X133358Y469875D01*
X133275Y469500D01*
X135025D01*
G01X113107Y516317D02*
X112982Y516067D01*
X112899Y515775D01*
Y515442D01*
X113024Y515067D01*
X113232Y514775D01*
X113482Y514567D01*
X113899Y514400D01*
X114274Y514358D01*
X114649Y514442D01*
X114899Y514567D01*
X115149Y514817D01*
X115316Y515108D01*
X115399Y515400D01*
Y515692D01*
X115316Y515983D01*
X115191Y516233D01*
X115024Y516442D01*
G01X114899Y517583D02*
X115191Y517833D01*
X115357Y518167D01*
X115399Y518542D01*
X115357Y518875D01*
X115149Y519208D01*
X114899Y519417D01*
X114649Y519458D01*
X114357Y519375D01*
X114149Y519083D01*
X114066Y518792D01*
Y518417D01*
G01Y518792D02*
X113941Y519042D01*
X113732Y519250D01*
X113482Y519333D01*
X113232Y519250D01*
X113024Y519042D01*
X112899Y518667D01*
X112941Y518292D01*
X113107Y517917D01*
G01X113316Y520808D02*
X113066Y521058D01*
X112941Y521350D01*
X112899Y521683D01*
X112982Y522100D01*
X113191Y522392D01*
X113441Y522475D01*
X113691Y522433D01*
X113899Y522267D01*
X114316Y521433D01*
X114607Y521058D01*
X115024Y520808D01*
X115399Y520725D01*
Y522475D01*
G01X114899Y523783D02*
X115191Y524033D01*
X115357Y524367D01*
X115399Y524742D01*
X115357Y525075D01*
X115149Y525408D01*
X114899Y525617D01*
X114649Y525658D01*
X114357Y525575D01*
X114149Y525283D01*
X114066Y524992D01*
Y524617D01*
G01Y524992D02*
X113941Y525242D01*
X113732Y525450D01*
X113482Y525533D01*
X113232Y525450D01*
X113024Y525242D01*
X112899Y524867D01*
X112941Y524492D01*
X113107Y524117D01*
G01X123516Y507550D02*
Y510050D01*
X124557D01*
X124891Y509925D01*
X125099Y509758D01*
X125182Y509425D01*
X125099Y509092D01*
X124849Y508883D01*
X124557Y508758D01*
X123516D01*
G01X124557D02*
X125182Y507550D01*
G01X126657Y509633D02*
X126907Y509883D01*
X127199Y510008D01*
X127532Y510050D01*
X127949Y509967D01*
X128241Y509758D01*
X128324Y509508D01*
X128282Y509258D01*
X128116Y509050D01*
X127282Y508633D01*
X126907Y508342D01*
X126657Y507925D01*
X126574Y507550D01*
X128324D01*
G01X130549D02*
X130841Y507592D01*
X131174Y507717D01*
X131382Y507925D01*
X131466Y508217D01*
X131382Y508508D01*
X131132Y508758D01*
X130757Y508883D01*
X130341D01*
X130091Y508967D01*
X129882Y509175D01*
X129799Y509467D01*
X129924Y509758D01*
X130216Y509967D01*
X130549Y510050D01*
X130882Y509967D01*
X131174Y509758D01*
X131299Y509467D01*
X131216Y509175D01*
X131007Y508967D01*
X130757Y508883D01*
X130341D01*
X129966Y508758D01*
X129716Y508508D01*
X129632Y508217D01*
X129716Y507925D01*
X129924Y507717D01*
X130257Y507592D01*
X130549Y507550D01*
G01X132941Y507842D02*
X133232Y507633D01*
X133566Y507550D01*
X133899Y507633D01*
X134191Y507883D01*
X134399Y508258D01*
X134482Y508633D01*
Y509092D01*
X134399Y509467D01*
X134191Y509800D01*
X133941Y509967D01*
X133649Y510050D01*
X133316Y509967D01*
X133066Y509800D01*
X132899Y509550D01*
X132816Y509217D01*
X132899Y508925D01*
X133107Y508633D01*
X133357Y508467D01*
X133649Y508425D01*
X133982Y508508D01*
X134232Y508717D01*
X134482Y509092D01*
G01X123017Y515500D02*
Y518000D01*
X124058D01*
X124392Y517875D01*
X124600Y517708D01*
X124683Y517375D01*
X124600Y517042D01*
X124350Y516833D01*
X124058Y516708D01*
X123017D01*
G01X124058D02*
X124683Y515500D01*
G01X126158Y517583D02*
X126408Y517833D01*
X126700Y517958D01*
X127033Y518000D01*
X127450Y517917D01*
X127742Y517708D01*
X127825Y517458D01*
X127783Y517208D01*
X127617Y517000D01*
X126783Y516583D01*
X126408Y516292D01*
X126158Y515875D01*
X126075Y515500D01*
X127825D01*
G01X129342Y515792D02*
X129633Y515583D01*
X129967Y515500D01*
X130300Y515583D01*
X130592Y515833D01*
X130800Y516208D01*
X130883Y516583D01*
Y517042D01*
X130800Y517417D01*
X130592Y517750D01*
X130342Y517917D01*
X130050Y518000D01*
X129717Y517917D01*
X129467Y517750D01*
X129300Y517500D01*
X129217Y517167D01*
X129300Y516875D01*
X129508Y516583D01*
X129758Y516417D01*
X130050Y516375D01*
X130383Y516458D01*
X130633Y516667D01*
X130883Y517042D01*
G01X133150Y515500D02*
Y518000D01*
X132650Y517500D01*
G01Y515500D02*
X133650D01*
G01X119699Y514967D02*
X117199D01*
Y516008D01*
X117324Y516342D01*
X117491Y516550D01*
X117824Y516633D01*
X118157Y516550D01*
X118366Y516300D01*
X118491Y516008D01*
Y514967D01*
G01Y516008D02*
X119699Y516633D01*
G01X117616Y518108D02*
X117366Y518358D01*
X117241Y518650D01*
X117199Y518983D01*
X117282Y519400D01*
X117491Y519692D01*
X117741Y519775D01*
X117991Y519733D01*
X118199Y519567D01*
X118616Y518733D01*
X118907Y518358D01*
X119324Y518108D01*
X119699Y518025D01*
Y519775D01*
G01X119407Y521292D02*
X119616Y521583D01*
X119699Y521917D01*
X119616Y522250D01*
X119366Y522542D01*
X118991Y522750D01*
X118616Y522833D01*
X118157D01*
X117782Y522750D01*
X117449Y522542D01*
X117282Y522292D01*
X117199Y522000D01*
X117282Y521667D01*
X117449Y521417D01*
X117699Y521250D01*
X118032Y521167D01*
X118324Y521250D01*
X118616Y521458D01*
X118782Y521708D01*
X118824Y522000D01*
X118741Y522333D01*
X118532Y522583D01*
X118157Y522833D01*
G01X119199Y524183D02*
X119491Y524433D01*
X119657Y524767D01*
X119699Y525142D01*
X119657Y525475D01*
X119449Y525808D01*
X119199Y526017D01*
X118949Y526058D01*
X118657Y525975D01*
X118449Y525683D01*
X118366Y525392D01*
Y525017D01*
G01Y525392D02*
X118241Y525642D01*
X118032Y525850D01*
X117782Y525933D01*
X117532Y525850D01*
X117324Y525642D01*
X117199Y525267D01*
X117241Y524892D01*
X117407Y524517D01*
G01X119517Y542000D02*
Y544500D01*
X120558D01*
X120892Y544375D01*
X121100Y544208D01*
X121183Y543875D01*
X121100Y543542D01*
X120850Y543333D01*
X120558Y543208D01*
X119517D01*
G01X120558D02*
X121183Y542000D01*
G01X122533Y542500D02*
X122783Y542208D01*
X123117Y542042D01*
X123492Y542000D01*
X123825Y542042D01*
X124158Y542250D01*
X124367Y542500D01*
X124408Y542750D01*
X124325Y543042D01*
X124033Y543250D01*
X123742Y543333D01*
X123367D01*
G01X123742D02*
X123992Y543458D01*
X124200Y543667D01*
X124283Y543917D01*
X124200Y544167D01*
X123992Y544375D01*
X123617Y544500D01*
X123242Y544458D01*
X122867Y544292D01*
G01X126550Y542000D02*
Y544500D01*
X126050Y544000D01*
G01Y542000D02*
X127050D01*
G01X130150D02*
Y544500D01*
X128608Y542708D01*
X130692D01*
G01X119517Y550500D02*
Y553000D01*
X120558D01*
X120892Y552875D01*
X121100Y552708D01*
X121183Y552375D01*
X121100Y552042D01*
X120850Y551833D01*
X120558Y551708D01*
X119517D01*
G01X120558D02*
X121183Y550500D01*
G01X122533Y551000D02*
X122783Y550708D01*
X123117Y550542D01*
X123492Y550500D01*
X123825Y550542D01*
X124158Y550750D01*
X124367Y551000D01*
X124408Y551250D01*
X124325Y551542D01*
X124033Y551750D01*
X123742Y551833D01*
X123367D01*
G01X123742D02*
X123992Y551958D01*
X124200Y552167D01*
X124283Y552417D01*
X124200Y552667D01*
X123992Y552875D01*
X123617Y553000D01*
X123242Y552958D01*
X122867Y552792D01*
G01X126550Y550500D02*
Y553000D01*
X126050Y552500D01*
G01Y550500D02*
X127050D01*
G01X128942Y550792D02*
X129233Y550583D01*
X129567Y550500D01*
X129900Y550583D01*
X130192Y550833D01*
X130400Y551208D01*
X130483Y551583D01*
Y552042D01*
X130400Y552417D01*
X130192Y552750D01*
X129942Y552917D01*
X129650Y553000D01*
X129317Y552917D01*
X129067Y552750D01*
X128900Y552500D01*
X128817Y552167D01*
X128900Y551875D01*
X129108Y551583D01*
X129358Y551417D01*
X129650Y551375D01*
X129983Y551458D01*
X130233Y551667D01*
X130483Y552042D01*
G01X119517Y546500D02*
Y549000D01*
X120558D01*
X120892Y548875D01*
X121100Y548708D01*
X121183Y548375D01*
X121100Y548042D01*
X120850Y547833D01*
X120558Y547708D01*
X119517D01*
G01X120558D02*
X121183Y546500D01*
G01X123950D02*
Y549000D01*
X122408Y547208D01*
X124492D01*
G01X126550Y549000D02*
X126217Y548917D01*
X125967Y548708D01*
X125800Y548458D01*
X125675Y548125D01*
X125633Y547750D01*
X125675Y547375D01*
X125800Y547042D01*
X125967Y546792D01*
X126217Y546583D01*
X126550Y546500D01*
X126883Y546583D01*
X127133Y546792D01*
X127300Y547042D01*
X127425Y547375D01*
X127467Y547750D01*
X127425Y548125D01*
X127300Y548458D01*
X127133Y548708D01*
X126883Y548917D01*
X126550Y549000D01*
G01X128733Y547000D02*
X128983Y546708D01*
X129317Y546542D01*
X129692Y546500D01*
X130025Y546542D01*
X130358Y546750D01*
X130567Y547000D01*
X130608Y547250D01*
X130525Y547542D01*
X130233Y547750D01*
X129942Y547833D01*
X129567D01*
G01X129942D02*
X130192Y547958D01*
X130400Y548167D01*
X130483Y548417D01*
X130400Y548667D01*
X130192Y548875D01*
X129817Y549000D01*
X129442Y548958D01*
X129067Y548792D01*
G01X118705Y631357D02*
X118455Y631482D01*
X118163Y631565D01*
X117830D01*
X117455Y631440D01*
X117163Y631232D01*
X116955Y630982D01*
X116788Y630565D01*
X116746Y630190D01*
X116830Y629815D01*
X116955Y629565D01*
X117205Y629315D01*
X117496Y629148D01*
X117788Y629065D01*
X118080D01*
X118371Y629148D01*
X118621Y629273D01*
X118830Y629440D01*
G01X120096Y631148D02*
X120346Y631398D01*
X120638Y631523D01*
X120971Y631565D01*
X121388Y631482D01*
X121680Y631273D01*
X121763Y631023D01*
X121721Y630773D01*
X121555Y630565D01*
X120721Y630148D01*
X120346Y629857D01*
X120096Y629440D01*
X120013Y629065D01*
X121763D01*
G01X123071Y629565D02*
X123321Y629273D01*
X123655Y629107D01*
X124030Y629065D01*
X124363Y629107D01*
X124696Y629315D01*
X124905Y629565D01*
X124946Y629815D01*
X124863Y630107D01*
X124571Y630315D01*
X124280Y630398D01*
X123905D01*
G01X124280D02*
X124530Y630523D01*
X124738Y630732D01*
X124821Y630982D01*
X124738Y631232D01*
X124530Y631440D01*
X124155Y631565D01*
X123780Y631523D01*
X123405Y631357D01*
G01X127088Y631565D02*
X126755Y631482D01*
X126505Y631273D01*
X126338Y631023D01*
X126213Y630690D01*
X126171Y630315D01*
X126213Y629940D01*
X126338Y629607D01*
X126505Y629357D01*
X126755Y629148D01*
X127088Y629065D01*
X127421Y629148D01*
X127671Y629357D01*
X127838Y629607D01*
X127963Y629940D01*
X128005Y630315D01*
X127963Y630690D01*
X127838Y631023D01*
X127671Y631273D01*
X127421Y631482D01*
X127088Y631565D01*
G01X118766Y635342D02*
X118516Y635467D01*
X118224Y635550D01*
X117891D01*
X117516Y635425D01*
X117224Y635217D01*
X117016Y634967D01*
X116849Y634550D01*
X116807Y634175D01*
X116891Y633800D01*
X117016Y633550D01*
X117266Y633300D01*
X117557Y633133D01*
X117849Y633050D01*
X118141D01*
X118432Y633133D01*
X118682Y633258D01*
X118891Y633425D01*
G01X120157Y635133D02*
X120407Y635383D01*
X120699Y635508D01*
X121032Y635550D01*
X121449Y635467D01*
X121741Y635258D01*
X121824Y635008D01*
X121782Y634758D01*
X121616Y634550D01*
X120782Y634133D01*
X120407Y633842D01*
X120157Y633425D01*
X120074Y633050D01*
X121824D01*
G01X123132Y633550D02*
X123382Y633258D01*
X123716Y633092D01*
X124091Y633050D01*
X124424Y633092D01*
X124757Y633300D01*
X124966Y633550D01*
X125007Y633800D01*
X124924Y634092D01*
X124632Y634300D01*
X124341Y634383D01*
X123966D01*
G01X124341D02*
X124591Y634508D01*
X124799Y634717D01*
X124882Y634967D01*
X124799Y635217D01*
X124591Y635425D01*
X124216Y635550D01*
X123841Y635508D01*
X123466Y635342D01*
G01X127149Y633050D02*
Y635550D01*
X126649Y635050D01*
G01Y633050D02*
X127649D01*
G01X118205Y655357D02*
X117955Y655482D01*
X117663Y655565D01*
X117330D01*
X116955Y655440D01*
X116663Y655232D01*
X116455Y654982D01*
X116288Y654565D01*
X116246Y654190D01*
X116330Y653815D01*
X116455Y653565D01*
X116705Y653315D01*
X116996Y653148D01*
X117288Y653065D01*
X117580D01*
X117871Y653148D01*
X118121Y653273D01*
X118330Y653440D01*
G01X119596Y655148D02*
X119846Y655398D01*
X120138Y655523D01*
X120471Y655565D01*
X120888Y655482D01*
X121180Y655273D01*
X121263Y655023D01*
X121221Y654773D01*
X121055Y654565D01*
X120221Y654148D01*
X119846Y653857D01*
X119596Y653440D01*
X119513Y653065D01*
X121263D01*
G01X122571Y653565D02*
X122821Y653273D01*
X123155Y653107D01*
X123530Y653065D01*
X123863Y653107D01*
X124196Y653315D01*
X124405Y653565D01*
X124446Y653815D01*
X124363Y654107D01*
X124071Y654315D01*
X123780Y654398D01*
X123405D01*
G01X123780D02*
X124030Y654523D01*
X124238Y654732D01*
X124321Y654982D01*
X124238Y655232D01*
X124030Y655440D01*
X123655Y655565D01*
X123280Y655523D01*
X122905Y655357D01*
G01X125796Y655148D02*
X126046Y655398D01*
X126338Y655523D01*
X126671Y655565D01*
X127088Y655482D01*
X127380Y655273D01*
X127463Y655023D01*
X127421Y654773D01*
X127255Y654565D01*
X126421Y654148D01*
X126046Y653857D01*
X125796Y653440D01*
X125713Y653065D01*
X127463D01*
G01X118266Y659342D02*
X118016Y659467D01*
X117724Y659550D01*
X117391D01*
X117016Y659425D01*
X116724Y659217D01*
X116516Y658967D01*
X116349Y658550D01*
X116307Y658175D01*
X116391Y657800D01*
X116516Y657550D01*
X116766Y657300D01*
X117057Y657133D01*
X117349Y657050D01*
X117641D01*
X117932Y657133D01*
X118182Y657258D01*
X118391Y657425D01*
G01X119657Y659133D02*
X119907Y659383D01*
X120199Y659508D01*
X120532Y659550D01*
X120949Y659467D01*
X121241Y659258D01*
X121324Y659008D01*
X121282Y658758D01*
X121116Y658550D01*
X120282Y658133D01*
X119907Y657842D01*
X119657Y657425D01*
X119574Y657050D01*
X121324D01*
G01X122632Y657550D02*
X122882Y657258D01*
X123216Y657092D01*
X123591Y657050D01*
X123924Y657092D01*
X124257Y657300D01*
X124466Y657550D01*
X124507Y657800D01*
X124424Y658092D01*
X124132Y658300D01*
X123841Y658383D01*
X123466D01*
G01X123841D02*
X124091Y658508D01*
X124299Y658717D01*
X124382Y658967D01*
X124299Y659217D01*
X124091Y659425D01*
X123716Y659550D01*
X123341Y659508D01*
X122966Y659342D01*
G01X125732Y657550D02*
X125982Y657258D01*
X126316Y657092D01*
X126691Y657050D01*
X127024Y657092D01*
X127357Y657300D01*
X127566Y657550D01*
X127607Y657800D01*
X127524Y658092D01*
X127232Y658300D01*
X126941Y658383D01*
X126566D01*
G01X126941D02*
X127191Y658508D01*
X127399Y658717D01*
X127482Y658967D01*
X127399Y659217D01*
X127191Y659425D01*
X126816Y659550D01*
X126441Y659508D01*
X126066Y659342D01*
G01X109999Y864050D02*
X119999D01*
G01Y857050D02*
X109999D01*
G01X114999D02*
Y864050D01*
G01X109999Y853617D02*
X119999D01*
Y850283D01*
X119499Y848950D01*
X118832Y847950D01*
X117832Y847117D01*
X116665Y846450D01*
X114999Y846283D01*
X113332Y846450D01*
X112166Y847117D01*
X111165Y847950D01*
X110499Y848950D01*
X109999Y850283D01*
Y853617D01*
G01Y843017D02*
X119999D01*
Y839683D01*
X119499Y838350D01*
X118832Y837350D01*
X117832Y836517D01*
X116665Y835850D01*
X114999Y835683D01*
X113332Y835850D01*
X112166Y836517D01*
X111165Y837350D01*
X110499Y838350D01*
X109999Y839683D01*
Y843017D01*
G01Y828750D02*
X119999D01*
X117999Y830750D01*
G01X109999D02*
Y826750D01*
G01X118332Y821317D02*
X119332Y820317D01*
X119832Y819150D01*
X119999Y817817D01*
X119666Y816150D01*
X118832Y814983D01*
X117832Y814650D01*
X116832Y814817D01*
X115999Y815483D01*
X114332Y818817D01*
X113166Y820317D01*
X111499Y821317D01*
X109999Y821650D01*
Y814650D01*
G01X115349Y873550D02*
Y871050D01*
G01X114391Y873550D02*
X116307D01*
G01X117616Y871050D02*
Y873550D01*
X118616D01*
X118949Y873425D01*
X119199Y873133D01*
X119282Y872800D01*
X119199Y872467D01*
X118991Y872217D01*
X118616Y872092D01*
X117616D01*
G01X120632Y871550D02*
X120882Y871258D01*
X121216Y871092D01*
X121591Y871050D01*
X121924Y871092D01*
X122257Y871300D01*
X122466Y871550D01*
X122507Y871800D01*
X122424Y872092D01*
X122132Y872300D01*
X121841Y872383D01*
X121466D01*
G01X121841D02*
X122091Y872508D01*
X122299Y872717D01*
X122382Y872967D01*
X122299Y873217D01*
X122091Y873425D01*
X121716Y873550D01*
X121341Y873508D01*
X120966Y873342D01*
G01X124566Y871050D02*
X124649Y871592D01*
X124774Y872050D01*
X124941Y872467D01*
X125149Y872925D01*
X125482Y873550D01*
X123816D01*
G01X109312Y932281D02*
X109062Y932406D01*
X108770Y932489D01*
X108437D01*
X108062Y932364D01*
X107770Y932156D01*
X107562Y931906D01*
X107395Y931489D01*
X107353Y931114D01*
X107437Y930739D01*
X107562Y930489D01*
X107812Y930239D01*
X108103Y930072D01*
X108395Y929989D01*
X108687D01*
X108978Y930072D01*
X109228Y930197D01*
X109437Y930364D01*
G01X110703Y932072D02*
X110953Y932322D01*
X111245Y932447D01*
X111578Y932489D01*
X111995Y932406D01*
X112287Y932197D01*
X112370Y931947D01*
X112328Y931697D01*
X112162Y931489D01*
X111328Y931072D01*
X110953Y930781D01*
X110703Y930364D01*
X110620Y929989D01*
X112370D01*
G01X113887Y930281D02*
X114178Y930072D01*
X114512Y929989D01*
X114845Y930072D01*
X115137Y930322D01*
X115345Y930697D01*
X115428Y931072D01*
Y931531D01*
X115345Y931906D01*
X115137Y932239D01*
X114887Y932406D01*
X114595Y932489D01*
X114262Y932406D01*
X114012Y932239D01*
X113845Y931989D01*
X113762Y931656D01*
X113845Y931364D01*
X114053Y931072D01*
X114303Y930906D01*
X114595Y930864D01*
X114928Y930947D01*
X115178Y931156D01*
X115428Y931531D01*
G01X116903Y931031D02*
X117195Y931322D01*
X117445Y931489D01*
X117778Y931572D01*
X118070Y931489D01*
X118278Y931322D01*
X118445Y931072D01*
X118487Y930781D01*
X118445Y930531D01*
X118278Y930281D01*
X118028Y930072D01*
X117737Y929989D01*
X117403Y930072D01*
X117112Y930322D01*
X116945Y930697D01*
X116903Y931114D01*
X116987Y931656D01*
X117112Y931947D01*
X117320Y932239D01*
X117612Y932447D01*
X117903Y932489D01*
X118195Y932406D01*
X118403Y932197D01*
G01X109312Y928781D02*
X109062Y928906D01*
X108770Y928989D01*
X108437D01*
X108062Y928864D01*
X107770Y928656D01*
X107562Y928406D01*
X107395Y927989D01*
X107353Y927614D01*
X107437Y927239D01*
X107562Y926989D01*
X107812Y926739D01*
X108103Y926572D01*
X108395Y926489D01*
X108687D01*
X108978Y926572D01*
X109228Y926697D01*
X109437Y926864D01*
G01X110703Y928572D02*
X110953Y928822D01*
X111245Y928947D01*
X111578Y928989D01*
X111995Y928906D01*
X112287Y928697D01*
X112370Y928447D01*
X112328Y928197D01*
X112162Y927989D01*
X111328Y927572D01*
X110953Y927281D01*
X110703Y926864D01*
X110620Y926489D01*
X112370D01*
G01X113887Y926781D02*
X114178Y926572D01*
X114512Y926489D01*
X114845Y926572D01*
X115137Y926822D01*
X115345Y927197D01*
X115428Y927572D01*
Y928031D01*
X115345Y928406D01*
X115137Y928739D01*
X114887Y928906D01*
X114595Y928989D01*
X114262Y928906D01*
X114012Y928739D01*
X113845Y928489D01*
X113762Y928156D01*
X113845Y927864D01*
X114053Y927572D01*
X114303Y927406D01*
X114595Y927364D01*
X114928Y927447D01*
X115178Y927656D01*
X115428Y928031D01*
G01X117612Y926489D02*
X117695Y927031D01*
X117820Y927489D01*
X117987Y927906D01*
X118195Y928364D01*
X118528Y928989D01*
X116862D01*
G01X114812Y957781D02*
X114562Y957906D01*
X114270Y957989D01*
X113937D01*
X113562Y957864D01*
X113270Y957656D01*
X113062Y957406D01*
X112895Y956989D01*
X112853Y956614D01*
X112937Y956239D01*
X113062Y955989D01*
X113312Y955739D01*
X113603Y955572D01*
X113895Y955489D01*
X114187D01*
X114478Y955572D01*
X114728Y955697D01*
X114937Y955864D01*
G01X116203Y957572D02*
X116453Y957822D01*
X116745Y957947D01*
X117078Y957989D01*
X117495Y957906D01*
X117787Y957697D01*
X117870Y957447D01*
X117828Y957197D01*
X117662Y956989D01*
X116828Y956572D01*
X116453Y956281D01*
X116203Y955864D01*
X116120Y955489D01*
X117870D01*
G01X119387Y955781D02*
X119678Y955572D01*
X120012Y955489D01*
X120345Y955572D01*
X120637Y955822D01*
X120845Y956197D01*
X120928Y956572D01*
Y957031D01*
X120845Y957406D01*
X120637Y957739D01*
X120387Y957906D01*
X120095Y957989D01*
X119762Y957906D01*
X119512Y957739D01*
X119345Y957489D01*
X119262Y957156D01*
X119345Y956864D01*
X119553Y956572D01*
X119803Y956406D01*
X120095Y956364D01*
X120428Y956447D01*
X120678Y956656D01*
X120928Y957031D01*
G01X123695Y955489D02*
Y957989D01*
X122153Y956197D01*
X124237D01*
G01X114812Y954281D02*
X114562Y954406D01*
X114270Y954489D01*
X113937D01*
X113562Y954364D01*
X113270Y954156D01*
X113062Y953906D01*
X112895Y953489D01*
X112853Y953114D01*
X112937Y952739D01*
X113062Y952489D01*
X113312Y952239D01*
X113603Y952072D01*
X113895Y951989D01*
X114187D01*
X114478Y952072D01*
X114728Y952197D01*
X114937Y952364D01*
G01X116203Y954072D02*
X116453Y954322D01*
X116745Y954447D01*
X117078Y954489D01*
X117495Y954406D01*
X117787Y954197D01*
X117870Y953947D01*
X117828Y953697D01*
X117662Y953489D01*
X116828Y953072D01*
X116453Y952781D01*
X116203Y952364D01*
X116120Y951989D01*
X117870D01*
G01X119387Y952281D02*
X119678Y952072D01*
X120012Y951989D01*
X120345Y952072D01*
X120637Y952322D01*
X120845Y952697D01*
X120928Y953072D01*
Y953531D01*
X120845Y953906D01*
X120637Y954239D01*
X120387Y954406D01*
X120095Y954489D01*
X119762Y954406D01*
X119512Y954239D01*
X119345Y953989D01*
X119262Y953656D01*
X119345Y953364D01*
X119553Y953072D01*
X119803Y952906D01*
X120095Y952864D01*
X120428Y952947D01*
X120678Y953156D01*
X120928Y953531D01*
G01X122278Y952364D02*
X122528Y952156D01*
X122820Y952031D01*
X123195Y951989D01*
X123570Y952072D01*
X123862Y952239D01*
X124070Y952531D01*
X124112Y952864D01*
X124028Y953197D01*
X123820Y953406D01*
X123528Y953572D01*
X123237Y953614D01*
X122945Y953572D01*
X122570Y953406D01*
X122695Y954489D01*
X123820D01*
G01X112767Y970000D02*
Y972500D01*
X113808D01*
X114142Y972375D01*
X114350Y972208D01*
X114433Y971875D01*
X114350Y971542D01*
X114100Y971333D01*
X113808Y971208D01*
X112767D01*
G01X113808D02*
X114433Y970000D01*
G01X115783Y970500D02*
X116033Y970208D01*
X116367Y970042D01*
X116742Y970000D01*
X117075Y970042D01*
X117408Y970250D01*
X117617Y970500D01*
X117658Y970750D01*
X117575Y971042D01*
X117283Y971250D01*
X116992Y971333D01*
X116617D01*
G01X116992D02*
X117242Y971458D01*
X117450Y971667D01*
X117533Y971917D01*
X117450Y972167D01*
X117242Y972375D01*
X116867Y972500D01*
X116492Y972458D01*
X116117Y972292D01*
G01X119008Y971042D02*
X119300Y971333D01*
X119550Y971500D01*
X119883Y971583D01*
X120175Y971500D01*
X120383Y971333D01*
X120550Y971083D01*
X120592Y970792D01*
X120550Y970542D01*
X120383Y970292D01*
X120133Y970083D01*
X119842Y970000D01*
X119508Y970083D01*
X119217Y970333D01*
X119050Y970708D01*
X119008Y971125D01*
X119092Y971667D01*
X119217Y971958D01*
X119425Y972250D01*
X119717Y972458D01*
X120008Y972500D01*
X120300Y972417D01*
X120508Y972208D01*
G01X122817Y970000D02*
X122900Y970542D01*
X123025Y971000D01*
X123192Y971417D01*
X123400Y971875D01*
X123733Y972500D01*
X122067D01*
G01X110950Y970000D02*
Y974000D01*
X103550D01*
G01X112716Y965850D02*
Y968350D01*
X113757D01*
X114091Y968225D01*
X114299Y968058D01*
X114382Y967725D01*
X114299Y967392D01*
X114049Y967183D01*
X113757Y967058D01*
X112716D01*
G01X113757D02*
X114382Y965850D01*
G01X115732Y966350D02*
X115982Y966058D01*
X116316Y965892D01*
X116691Y965850D01*
X117024Y965892D01*
X117357Y966100D01*
X117566Y966350D01*
X117607Y966600D01*
X117524Y966892D01*
X117232Y967100D01*
X116941Y967183D01*
X116566D01*
G01X116941D02*
X117191Y967308D01*
X117399Y967517D01*
X117482Y967767D01*
X117399Y968017D01*
X117191Y968225D01*
X116816Y968350D01*
X116441Y968308D01*
X116066Y968142D01*
G01X118957Y966892D02*
X119249Y967183D01*
X119499Y967350D01*
X119832Y967433D01*
X120124Y967350D01*
X120332Y967183D01*
X120499Y966933D01*
X120541Y966642D01*
X120499Y966392D01*
X120332Y966142D01*
X120082Y965933D01*
X119791Y965850D01*
X119457Y965933D01*
X119166Y966183D01*
X118999Y966558D01*
X118957Y966975D01*
X119041Y967517D01*
X119166Y967808D01*
X119374Y968100D01*
X119666Y968308D01*
X119957Y968350D01*
X120249Y968267D01*
X120457Y968058D01*
G01X122849Y965850D02*
X123141Y965892D01*
X123474Y966017D01*
X123682Y966225D01*
X123766Y966517D01*
X123682Y966808D01*
X123432Y967058D01*
X123057Y967183D01*
X122641D01*
X122391Y967267D01*
X122182Y967475D01*
X122099Y967767D01*
X122224Y968058D01*
X122516Y968267D01*
X122849Y968350D01*
X123182Y968267D01*
X123474Y968058D01*
X123599Y967767D01*
X123516Y967475D01*
X123307Y967267D01*
X123057Y967183D01*
X122641D01*
X122266Y967058D01*
X122016Y966808D01*
X121932Y966517D01*
X122016Y966225D01*
X122224Y966017D01*
X122557Y965892D01*
X122849Y965850D01*
G01X126466Y1027842D02*
X126216Y1027967D01*
X125924Y1028050D01*
X125591D01*
X125216Y1027925D01*
X124924Y1027717D01*
X124716Y1027467D01*
X124549Y1027050D01*
X124507Y1026675D01*
X124591Y1026300D01*
X124716Y1026050D01*
X124966Y1025800D01*
X125257Y1025633D01*
X125549Y1025550D01*
X125841D01*
X126132Y1025633D01*
X126382Y1025758D01*
X126591Y1025925D01*
G01X127857Y1027633D02*
X128107Y1027883D01*
X128399Y1028008D01*
X128732Y1028050D01*
X129149Y1027967D01*
X129441Y1027758D01*
X129524Y1027508D01*
X129482Y1027258D01*
X129316Y1027050D01*
X128482Y1026633D01*
X128107Y1026342D01*
X127857Y1025925D01*
X127774Y1025550D01*
X129524D01*
G01X131749D02*
Y1028050D01*
X131249Y1027550D01*
G01Y1025550D02*
X132249D01*
G01X135349D02*
Y1028050D01*
X133807Y1026258D01*
X135891D01*
G01X126466Y1031342D02*
X126216Y1031467D01*
X125924Y1031550D01*
X125591D01*
X125216Y1031425D01*
X124924Y1031217D01*
X124716Y1030967D01*
X124549Y1030550D01*
X124507Y1030175D01*
X124591Y1029800D01*
X124716Y1029550D01*
X124966Y1029300D01*
X125257Y1029133D01*
X125549Y1029050D01*
X125841D01*
X126132Y1029133D01*
X126382Y1029258D01*
X126591Y1029425D01*
G01X127857Y1031133D02*
X128107Y1031383D01*
X128399Y1031508D01*
X128732Y1031550D01*
X129149Y1031467D01*
X129441Y1031258D01*
X129524Y1031008D01*
X129482Y1030758D01*
X129316Y1030550D01*
X128482Y1030133D01*
X128107Y1029842D01*
X127857Y1029425D01*
X127774Y1029050D01*
X129524D01*
G01X131749D02*
Y1031550D01*
X131249Y1031050D01*
G01Y1029050D02*
X132249D01*
G01X133932Y1029425D02*
X134182Y1029217D01*
X134474Y1029092D01*
X134849Y1029050D01*
X135224Y1029133D01*
X135516Y1029300D01*
X135724Y1029592D01*
X135766Y1029925D01*
X135682Y1030258D01*
X135474Y1030467D01*
X135182Y1030633D01*
X134891Y1030675D01*
X134599Y1030633D01*
X134224Y1030467D01*
X134349Y1031550D01*
X135474D01*
G01X117317Y1067792D02*
X117067Y1067917D01*
X116775Y1068000D01*
X116442D01*
X116067Y1067875D01*
X115775Y1067667D01*
X115567Y1067417D01*
X115400Y1067000D01*
X115358Y1066625D01*
X115442Y1066250D01*
X115567Y1066000D01*
X115817Y1065750D01*
X116108Y1065583D01*
X116400Y1065500D01*
X116692D01*
X116983Y1065583D01*
X117233Y1065708D01*
X117442Y1065875D01*
G01X118583Y1066000D02*
X118833Y1065708D01*
X119167Y1065542D01*
X119542Y1065500D01*
X119875Y1065542D01*
X120208Y1065750D01*
X120417Y1066000D01*
X120458Y1066250D01*
X120375Y1066542D01*
X120083Y1066750D01*
X119792Y1066833D01*
X119417D01*
G01X119792D02*
X120042Y1066958D01*
X120250Y1067167D01*
X120333Y1067417D01*
X120250Y1067667D01*
X120042Y1067875D01*
X119667Y1068000D01*
X119292Y1067958D01*
X118917Y1067792D01*
G01X121808Y1066542D02*
X122100Y1066833D01*
X122350Y1067000D01*
X122683Y1067083D01*
X122975Y1067000D01*
X123183Y1066833D01*
X123350Y1066583D01*
X123392Y1066292D01*
X123350Y1066042D01*
X123183Y1065792D01*
X122933Y1065583D01*
X122642Y1065500D01*
X122308Y1065583D01*
X122017Y1065833D01*
X121850Y1066208D01*
X121808Y1066625D01*
X121892Y1067167D01*
X122017Y1067458D01*
X122225Y1067750D01*
X122517Y1067958D01*
X122808Y1068000D01*
X123100Y1067917D01*
X123308Y1067708D01*
G01X117317Y1071792D02*
X117067Y1071917D01*
X116775Y1072000D01*
X116442D01*
X116067Y1071875D01*
X115775Y1071667D01*
X115567Y1071417D01*
X115400Y1071000D01*
X115358Y1070625D01*
X115442Y1070250D01*
X115567Y1070000D01*
X115817Y1069750D01*
X116108Y1069583D01*
X116400Y1069500D01*
X116692D01*
X116983Y1069583D01*
X117233Y1069708D01*
X117442Y1069875D01*
G01X118583Y1070000D02*
X118833Y1069708D01*
X119167Y1069542D01*
X119542Y1069500D01*
X119875Y1069542D01*
X120208Y1069750D01*
X120417Y1070000D01*
X120458Y1070250D01*
X120375Y1070542D01*
X120083Y1070750D01*
X119792Y1070833D01*
X119417D01*
G01X119792D02*
X120042Y1070958D01*
X120250Y1071167D01*
X120333Y1071417D01*
X120250Y1071667D01*
X120042Y1071875D01*
X119667Y1072000D01*
X119292Y1071958D01*
X118917Y1071792D01*
G01X122517Y1069500D02*
X122600Y1070042D01*
X122725Y1070500D01*
X122892Y1070917D01*
X123100Y1071375D01*
X123433Y1072000D01*
X121767D01*
G01X119499Y1078033D02*
X121291D01*
X121666Y1078200D01*
X121916Y1078533D01*
X121999Y1078950D01*
X121916Y1079367D01*
X121666Y1079700D01*
X121291Y1079867D01*
X119499D01*
G01X119916Y1081258D02*
X119666Y1081508D01*
X119541Y1081800D01*
X119499Y1082133D01*
X119582Y1082550D01*
X119791Y1082842D01*
X120041Y1082925D01*
X120291Y1082883D01*
X120499Y1082717D01*
X120916Y1081883D01*
X121207Y1081508D01*
X121624Y1081258D01*
X121999Y1081175D01*
Y1082925D01*
G01X119916Y1084358D02*
X119666Y1084608D01*
X119541Y1084900D01*
X119499Y1085233D01*
X119582Y1085650D01*
X119791Y1085942D01*
X120041Y1086025D01*
X120291Y1085983D01*
X120499Y1085817D01*
X120916Y1084983D01*
X121207Y1084608D01*
X121624Y1084358D01*
X121999Y1084275D01*
Y1086025D01*
G01X116999Y1089250D02*
Y1075850D01*
G01X106999D02*
Y1089250D01*
G01X116999Y1075850D02*
X106999D01*
G01X116499Y1103500D02*
Y1114900D01*
G01X123740Y1104764D02*
Y1107264D01*
X124781D01*
X125115Y1107139D01*
X125323Y1106972D01*
X125406Y1106639D01*
X125323Y1106306D01*
X125073Y1106097D01*
X124781Y1105972D01*
X123740D01*
G01X124781D02*
X125406Y1104764D01*
G01X126881Y1106847D02*
X127131Y1107097D01*
X127423Y1107222D01*
X127756Y1107264D01*
X128173Y1107181D01*
X128465Y1106972D01*
X128548Y1106722D01*
X128506Y1106472D01*
X128340Y1106264D01*
X127506Y1105847D01*
X127131Y1105556D01*
X126881Y1105139D01*
X126798Y1104764D01*
X128548D01*
G01X130773D02*
Y1107264D01*
X130273Y1106764D01*
G01Y1104764D02*
X131273D01*
G01X133873Y1107264D02*
X133540Y1107181D01*
X133290Y1106972D01*
X133123Y1106722D01*
X132998Y1106389D01*
X132956Y1106014D01*
X132998Y1105639D01*
X133123Y1105306D01*
X133290Y1105056D01*
X133540Y1104847D01*
X133873Y1104764D01*
X134206Y1104847D01*
X134456Y1105056D01*
X134623Y1105306D01*
X134748Y1105639D01*
X134790Y1106014D01*
X134748Y1106389D01*
X134623Y1106722D01*
X134456Y1106972D01*
X134206Y1107181D01*
X133873Y1107264D01*
G01X117499Y1104350D02*
X121499D01*
Y1111750D01*
G01X130180Y1096482D02*
Y1100482D01*
X122780D01*
G01X130180Y1092482D02*
Y1096482D01*
X122780D01*
G01X106999Y1089250D02*
X116999D01*
G01X106299Y1101550D02*
X119699D01*
G01X106299Y1091550D02*
Y1101550D01*
G01X119699Y1091550D02*
X106299D01*
G01X119699Y1101550D02*
Y1091550D01*
G01X111399Y1116550D02*
X111066Y1116592D01*
X110774Y1116758D01*
X110524Y1117008D01*
X110357Y1117300D01*
X110274Y1117633D01*
Y1117967D01*
X110357Y1118300D01*
X110524Y1118592D01*
X110774Y1118842D01*
X111066Y1119008D01*
X111399Y1119050D01*
X111732Y1119008D01*
X112024Y1118842D01*
X112274Y1118592D01*
X112441Y1118300D01*
X112524Y1117967D01*
Y1117633D01*
X112441Y1117300D01*
X112274Y1117008D01*
X112024Y1116758D01*
X111732Y1116592D01*
X111399Y1116550D01*
G01X111732Y1117217D02*
X112232Y1116550D01*
G01X114499D02*
Y1119050D01*
X113999Y1118550D01*
G01Y1116550D02*
X114999D01*
G01X116807Y1117592D02*
X117099Y1117883D01*
X117349Y1118050D01*
X117682Y1118133D01*
X117974Y1118050D01*
X118182Y1117883D01*
X118349Y1117633D01*
X118391Y1117342D01*
X118349Y1117092D01*
X118182Y1116842D01*
X117932Y1116633D01*
X117641Y1116550D01*
X117307Y1116633D01*
X117016Y1116883D01*
X116849Y1117258D01*
X116807Y1117675D01*
X116891Y1118217D01*
X117016Y1118508D01*
X117224Y1118800D01*
X117516Y1119008D01*
X117807Y1119050D01*
X118099Y1118967D01*
X118307Y1118758D01*
G01X116016Y1128550D02*
Y1131050D01*
X117057D01*
X117391Y1130925D01*
X117599Y1130758D01*
X117682Y1130425D01*
X117599Y1130092D01*
X117349Y1129883D01*
X117057Y1129758D01*
X116016D01*
G01X117057D02*
X117682Y1128550D01*
G01X119157Y1130633D02*
X119407Y1130883D01*
X119699Y1131008D01*
X120032Y1131050D01*
X120449Y1130967D01*
X120741Y1130758D01*
X120824Y1130508D01*
X120782Y1130258D01*
X120616Y1130050D01*
X119782Y1129633D01*
X119407Y1129342D01*
X119157Y1128925D01*
X119074Y1128550D01*
X120824D01*
G01X123049Y1131050D02*
X122716Y1130967D01*
X122466Y1130758D01*
X122299Y1130508D01*
X122174Y1130175D01*
X122132Y1129800D01*
X122174Y1129425D01*
X122299Y1129092D01*
X122466Y1128842D01*
X122716Y1128633D01*
X123049Y1128550D01*
X123382Y1128633D01*
X123632Y1128842D01*
X123799Y1129092D01*
X123924Y1129425D01*
X123966Y1129800D01*
X123924Y1130175D01*
X123799Y1130508D01*
X123632Y1130758D01*
X123382Y1130967D01*
X123049Y1131050D01*
G01X126066Y1128550D02*
X126149Y1129092D01*
X126274Y1129550D01*
X126441Y1129967D01*
X126649Y1130425D01*
X126982Y1131050D01*
X125316D01*
G01X116799Y1127050D02*
Y1123050D01*
X124199D01*
G01X124499Y1139800D02*
Y1165800D01*
G01X111499Y1139800D02*
X124499D01*
G01X111499Y1165800D02*
Y1139800D01*
G01X107100Y1145400D02*
Y1163000D01*
G01X124499Y1165800D02*
X111499D01*
G01X106999Y1173750D02*
Y1168250D01*
G01X107999D02*
Y1173750D01*
G01X115999Y1168250D02*
X107999D01*
G01X115999Y1173750D02*
Y1168250D01*
G01X116999D02*
Y1173750D01*
G01X124999Y1168250D02*
X116999D01*
G01X106999Y1185850D02*
Y1180350D01*
G01X115999Y1185850D02*
Y1180350D01*
G01X107999Y1185850D02*
X115999D01*
G01X107999Y1180350D02*
Y1185850D01*
G01X116999D02*
X124999D01*
G01X116999Y1180350D02*
Y1185850D01*
G01X120299Y1221813D02*
Y1210413D01*
G01D02*
X133699D01*
G01X107499Y1196413D02*
X111499D01*
Y1203813D01*
G01X114482Y1204550D02*
Y1202758D01*
X114649Y1202383D01*
X114982Y1202133D01*
X115399Y1202050D01*
X115816Y1202133D01*
X116149Y1202383D01*
X116316Y1202758D01*
Y1204550D01*
G01X117582Y1202550D02*
X117832Y1202258D01*
X118166Y1202092D01*
X118541Y1202050D01*
X118874Y1202092D01*
X119207Y1202300D01*
X119416Y1202550D01*
X119457Y1202800D01*
X119374Y1203092D01*
X119082Y1203300D01*
X118791Y1203383D01*
X118416D01*
G01X118791D02*
X119041Y1203508D01*
X119249Y1203717D01*
X119332Y1203967D01*
X119249Y1204217D01*
X119041Y1204425D01*
X118666Y1204550D01*
X118291Y1204508D01*
X117916Y1204342D01*
G01X120807Y1203092D02*
X121099Y1203383D01*
X121349Y1203550D01*
X121682Y1203633D01*
X121974Y1203550D01*
X122182Y1203383D01*
X122349Y1203133D01*
X122391Y1202842D01*
X122349Y1202592D01*
X122182Y1202342D01*
X121932Y1202133D01*
X121641Y1202050D01*
X121307Y1202133D01*
X121016Y1202383D01*
X120849Y1202758D01*
X120807Y1203175D01*
X120891Y1203717D01*
X121016Y1204008D01*
X121224Y1204300D01*
X121516Y1204508D01*
X121807Y1204550D01*
X122099Y1204467D01*
X122307Y1204258D01*
G01X114499Y1220313D02*
Y1206913D01*
G01X104499D02*
Y1220313D01*
G01X114499Y1206913D02*
X104499D01*
G01X133699Y1221813D02*
X120299D01*
G01X104999Y1221913D02*
X108999D01*
Y1229313D01*
G01X118499D02*
X114499D01*
Y1221913D01*
G01X109999D02*
X113999D01*
Y1229313D01*
G01X104499Y1220313D02*
X114499D01*
G01X116499Y1230313D02*
Y1235813D01*
G01X124499Y1230313D02*
X116499D01*
G01X124499Y1235813D02*
Y1230313D01*
G01X107499D02*
Y1235813D01*
G01X115499Y1230313D02*
X107499D01*
G01X115499Y1235813D02*
Y1230313D01*
G01X124499Y1247913D02*
Y1242413D01*
G01X116499Y1247913D02*
X124499D01*
G01X116499Y1242413D02*
Y1247913D01*
G01X115499D02*
Y1242413D01*
G01X107499Y1247913D02*
X115499D01*
G01X107499Y1242413D02*
Y1247913D01*
G01X118367Y1266592D02*
X118117Y1266717D01*
X117825Y1266800D01*
X117492D01*
X117117Y1266675D01*
X116825Y1266467D01*
X116617Y1266217D01*
X116450Y1265800D01*
X116408Y1265425D01*
X116492Y1265050D01*
X116617Y1264800D01*
X116867Y1264550D01*
X117158Y1264383D01*
X117450Y1264300D01*
X117742D01*
X118033Y1264383D01*
X118283Y1264508D01*
X118492Y1264675D01*
G01X119758Y1266383D02*
X120008Y1266633D01*
X120300Y1266758D01*
X120633Y1266800D01*
X121050Y1266717D01*
X121342Y1266508D01*
X121425Y1266258D01*
X121383Y1266008D01*
X121217Y1265800D01*
X120383Y1265383D01*
X120008Y1265092D01*
X119758Y1264675D01*
X119675Y1264300D01*
X121425D01*
G01X123650D02*
X123942Y1264342D01*
X124275Y1264467D01*
X124483Y1264675D01*
X124567Y1264967D01*
X124483Y1265258D01*
X124233Y1265508D01*
X123858Y1265633D01*
X123442D01*
X123192Y1265717D01*
X122983Y1265925D01*
X122900Y1266217D01*
X123025Y1266508D01*
X123317Y1266717D01*
X123650Y1266800D01*
X123983Y1266717D01*
X124275Y1266508D01*
X124400Y1266217D01*
X124317Y1265925D01*
X124108Y1265717D01*
X123858Y1265633D01*
X123442D01*
X123067Y1265508D01*
X122817Y1265258D01*
X122733Y1264967D01*
X122817Y1264675D01*
X123025Y1264467D01*
X123358Y1264342D01*
X123650Y1264300D01*
G01X126667D02*
X126750Y1264842D01*
X126875Y1265300D01*
X127042Y1265717D01*
X127250Y1266175D01*
X127583Y1266800D01*
X125917D01*
G01X115499Y1280913D02*
Y1275413D01*
G01X107499D02*
Y1280913D01*
G01Y1263313D02*
Y1268813D01*
G01X115499Y1263313D02*
X107499D01*
G01X115499Y1268813D02*
Y1263313D01*
G01X117149Y1280363D02*
Y1270863D01*
X134849D01*
Y1280363D01*
X117149D01*
G01X119516Y1296050D02*
Y1298550D01*
X120557D01*
X120891Y1298425D01*
X121099Y1298258D01*
X121182Y1297925D01*
X121099Y1297592D01*
X120849Y1297383D01*
X120557Y1297258D01*
X119516D01*
G01X120557D02*
X121182Y1296050D01*
G01X122657Y1298133D02*
X122907Y1298383D01*
X123199Y1298508D01*
X123532Y1298550D01*
X123949Y1298467D01*
X124241Y1298258D01*
X124324Y1298008D01*
X124282Y1297758D01*
X124116Y1297550D01*
X123282Y1297133D01*
X122907Y1296842D01*
X122657Y1296425D01*
X122574Y1296050D01*
X124324D01*
G01X125757Y1297092D02*
X126049Y1297383D01*
X126299Y1297550D01*
X126632Y1297633D01*
X126924Y1297550D01*
X127132Y1297383D01*
X127299Y1297133D01*
X127341Y1296842D01*
X127299Y1296592D01*
X127132Y1296342D01*
X126882Y1296133D01*
X126591Y1296050D01*
X126257Y1296133D01*
X125966Y1296383D01*
X125799Y1296758D01*
X125757Y1297175D01*
X125841Y1297717D01*
X125966Y1298008D01*
X126174Y1298300D01*
X126466Y1298508D01*
X126757Y1298550D01*
X127049Y1298467D01*
X127257Y1298258D01*
G01X129649Y1296050D02*
Y1298550D01*
X129149Y1298050D01*
G01Y1296050D02*
X130149D01*
G01X118199Y1296113D02*
Y1300113D01*
X110799D01*
G01X107499Y1280913D02*
X115499D01*
G01X122600Y1321900D02*
Y1317900D01*
X130000D01*
G01X106213Y1316383D02*
X103713D01*
Y1317424D01*
X103838Y1317758D01*
X104005Y1317966D01*
X104338Y1318049D01*
X104671Y1317966D01*
X104880Y1317716D01*
X105005Y1317424D01*
Y1316383D01*
G01Y1317424D02*
X106213Y1318049D01*
G01Y1320816D02*
X103713D01*
X105505Y1319274D01*
Y1321358D01*
G01X105171Y1322624D02*
X104880Y1322916D01*
X104713Y1323166D01*
X104630Y1323499D01*
X104713Y1323791D01*
X104880Y1323999D01*
X105130Y1324166D01*
X105421Y1324208D01*
X105671Y1324166D01*
X105921Y1323999D01*
X106130Y1323749D01*
X106213Y1323458D01*
X106130Y1323124D01*
X105880Y1322833D01*
X105505Y1322666D01*
X105088Y1322624D01*
X104546Y1322708D01*
X104255Y1322833D01*
X103963Y1323041D01*
X103755Y1323333D01*
X103713Y1323624D01*
X103796Y1323916D01*
X104005Y1324124D01*
G01X106213Y1327016D02*
X103713D01*
X105505Y1325474D01*
Y1327558D01*
G01X118499Y1326813D02*
X114499D01*
Y1319413D01*
G01X110213Y1316383D02*
X107713D01*
Y1317424D01*
X107838Y1317758D01*
X108005Y1317966D01*
X108338Y1318049D01*
X108671Y1317966D01*
X108880Y1317716D01*
X109005Y1317424D01*
Y1316383D01*
G01Y1317424D02*
X110213Y1318049D01*
G01Y1320816D02*
X107713D01*
X109505Y1319274D01*
Y1321358D01*
G01X109171Y1322624D02*
X108880Y1322916D01*
X108713Y1323166D01*
X108630Y1323499D01*
X108713Y1323791D01*
X108880Y1323999D01*
X109130Y1324166D01*
X109421Y1324208D01*
X109671Y1324166D01*
X109921Y1323999D01*
X110130Y1323749D01*
X110213Y1323458D01*
X110130Y1323124D01*
X109880Y1322833D01*
X109505Y1322666D01*
X109088Y1322624D01*
X108546Y1322708D01*
X108255Y1322833D01*
X107963Y1323041D01*
X107755Y1323333D01*
X107713Y1323624D01*
X107796Y1323916D01*
X108005Y1324124D01*
G01X109838Y1325599D02*
X110046Y1325849D01*
X110171Y1326141D01*
X110213Y1326516D01*
X110130Y1326891D01*
X109963Y1327183D01*
X109671Y1327391D01*
X109338Y1327433D01*
X109005Y1327349D01*
X108796Y1327141D01*
X108630Y1326849D01*
X108588Y1326558D01*
X108630Y1326266D01*
X108796Y1325891D01*
X107713Y1326016D01*
Y1327141D01*
G01X122507Y1326896D02*
X118507D01*
Y1319496D01*
G01X112499Y1301850D02*
Y1315250D01*
G01X122499Y1301850D02*
X112499D01*
G01X122499Y1315250D02*
Y1301850D01*
G01X112499Y1315250D02*
X122499D01*
G01X116000Y1338517D02*
X113500D01*
Y1339558D01*
X113625Y1339892D01*
X113792Y1340100D01*
X114125Y1340183D01*
X114458Y1340100D01*
X114667Y1339850D01*
X114792Y1339558D01*
Y1338517D01*
G01Y1339558D02*
X116000Y1340183D01*
G01X113917Y1341658D02*
X113667Y1341908D01*
X113542Y1342200D01*
X113500Y1342533D01*
X113583Y1342950D01*
X113792Y1343242D01*
X114042Y1343325D01*
X114292Y1343283D01*
X114500Y1343117D01*
X114917Y1342283D01*
X115208Y1341908D01*
X115625Y1341658D01*
X116000Y1341575D01*
Y1343325D01*
G01X115625Y1344633D02*
X115833Y1344883D01*
X115958Y1345175D01*
X116000Y1345550D01*
X115917Y1345925D01*
X115750Y1346217D01*
X115458Y1346425D01*
X115125Y1346467D01*
X114792Y1346383D01*
X114583Y1346175D01*
X114417Y1345883D01*
X114375Y1345592D01*
X114417Y1345300D01*
X114583Y1344925D01*
X113500Y1345050D01*
Y1346175D01*
G01X116000Y1348650D02*
X115958Y1348942D01*
X115833Y1349275D01*
X115625Y1349483D01*
X115333Y1349567D01*
X115042Y1349483D01*
X114792Y1349233D01*
X114667Y1348858D01*
Y1348442D01*
X114583Y1348192D01*
X114375Y1347983D01*
X114083Y1347900D01*
X113792Y1348025D01*
X113583Y1348317D01*
X113500Y1348650D01*
X113583Y1348983D01*
X113792Y1349275D01*
X114083Y1349400D01*
X114375Y1349317D01*
X114583Y1349108D01*
X114667Y1348858D01*
Y1348442D01*
X114792Y1348067D01*
X115042Y1347817D01*
X115333Y1347733D01*
X115625Y1347817D01*
X115833Y1348025D01*
X115958Y1348358D01*
X116000Y1348650D01*
G01X118299Y1345050D02*
Y1341050D01*
X125699D01*
G01X121500Y1329900D02*
X121458Y1329567D01*
X121292Y1329275D01*
X121042Y1329025D01*
X120750Y1328858D01*
X120417Y1328775D01*
X120083D01*
X119750Y1328858D01*
X119458Y1329025D01*
X119208Y1329275D01*
X119042Y1329567D01*
X119000Y1329900D01*
X119042Y1330233D01*
X119208Y1330525D01*
X119458Y1330775D01*
X119750Y1330942D01*
X120083Y1331025D01*
X120417D01*
X120750Y1330942D01*
X121042Y1330775D01*
X121292Y1330525D01*
X121458Y1330233D01*
X121500Y1329900D01*
G01X120833Y1330233D02*
X121500Y1330733D01*
G01X120458Y1332208D02*
X120167Y1332500D01*
X120000Y1332750D01*
X119917Y1333083D01*
X120000Y1333375D01*
X120167Y1333583D01*
X120417Y1333750D01*
X120708Y1333792D01*
X120958Y1333750D01*
X121208Y1333583D01*
X121417Y1333333D01*
X121500Y1333042D01*
X121417Y1332708D01*
X121167Y1332417D01*
X120792Y1332250D01*
X120375Y1332208D01*
X119833Y1332292D01*
X119542Y1332417D01*
X119250Y1332625D01*
X119042Y1332917D01*
X119000Y1333208D01*
X119083Y1333500D01*
X119292Y1333708D01*
G01X121208Y1335392D02*
X121417Y1335683D01*
X121500Y1336017D01*
X121417Y1336350D01*
X121167Y1336642D01*
X120792Y1336850D01*
X120417Y1336933D01*
X119958D01*
X119583Y1336850D01*
X119250Y1336642D01*
X119083Y1336392D01*
X119000Y1336100D01*
X119083Y1335767D01*
X119250Y1335517D01*
X119500Y1335350D01*
X119833Y1335267D01*
X120125Y1335350D01*
X120417Y1335558D01*
X120583Y1335808D01*
X120625Y1336100D01*
X120542Y1336433D01*
X120333Y1336683D01*
X119958Y1336933D01*
G01X123100Y1337500D02*
Y1323500D01*
G01X136100Y1337500D02*
X123100D01*
G01Y1323500D02*
X136100D01*
G01X117799Y1358050D02*
Y1354050D01*
X125199D01*
G01X117799D02*
Y1350050D01*
X125199D01*
G01X114657Y1442533D02*
X114407Y1442658D01*
X114115Y1442741D01*
X113782D01*
X113407Y1442616D01*
X113115Y1442408D01*
X112907Y1442158D01*
X112740Y1441741D01*
X112698Y1441366D01*
X112782Y1440991D01*
X112907Y1440741D01*
X113157Y1440491D01*
X113448Y1440324D01*
X113740Y1440241D01*
X114032D01*
X114323Y1440324D01*
X114573Y1440449D01*
X114782Y1440616D01*
G01X116840Y1440241D02*
Y1442741D01*
X116340Y1442241D01*
G01Y1440241D02*
X117340D01*
G01X119232Y1440533D02*
X119523Y1440324D01*
X119857Y1440241D01*
X120190Y1440324D01*
X120482Y1440574D01*
X120690Y1440949D01*
X120773Y1441324D01*
Y1441783D01*
X120690Y1442158D01*
X120482Y1442491D01*
X120232Y1442658D01*
X119940Y1442741D01*
X119607Y1442658D01*
X119357Y1442491D01*
X119190Y1442241D01*
X119107Y1441908D01*
X119190Y1441616D01*
X119398Y1441324D01*
X119648Y1441158D01*
X119940Y1441116D01*
X120273Y1441199D01*
X120523Y1441408D01*
X120773Y1441783D01*
G01X123040Y1440241D02*
X123332Y1440283D01*
X123665Y1440408D01*
X123873Y1440616D01*
X123957Y1440908D01*
X123873Y1441199D01*
X123623Y1441449D01*
X123248Y1441574D01*
X122832D01*
X122582Y1441658D01*
X122373Y1441866D01*
X122290Y1442158D01*
X122415Y1442449D01*
X122707Y1442658D01*
X123040Y1442741D01*
X123373Y1442658D01*
X123665Y1442449D01*
X123790Y1442158D01*
X123707Y1441866D01*
X123498Y1441658D01*
X123248Y1441574D01*
X122832D01*
X122457Y1441449D01*
X122207Y1441199D01*
X122123Y1440908D01*
X122207Y1440616D01*
X122415Y1440408D01*
X122748Y1440283D01*
X123040Y1440241D01*
G01X114766Y1446342D02*
X114516Y1446467D01*
X114224Y1446550D01*
X113891D01*
X113516Y1446425D01*
X113224Y1446217D01*
X113016Y1445967D01*
X112849Y1445550D01*
X112807Y1445175D01*
X112891Y1444800D01*
X113016Y1444550D01*
X113266Y1444300D01*
X113557Y1444133D01*
X113849Y1444050D01*
X114141D01*
X114432Y1444133D01*
X114682Y1444258D01*
X114891Y1444425D01*
G01X116949Y1444050D02*
Y1446550D01*
X116449Y1446050D01*
G01Y1444050D02*
X117449D01*
G01X119341Y1444342D02*
X119632Y1444133D01*
X119966Y1444050D01*
X120299Y1444133D01*
X120591Y1444383D01*
X120799Y1444758D01*
X120882Y1445133D01*
Y1445592D01*
X120799Y1445967D01*
X120591Y1446300D01*
X120341Y1446467D01*
X120049Y1446550D01*
X119716Y1446467D01*
X119466Y1446300D01*
X119299Y1446050D01*
X119216Y1445717D01*
X119299Y1445425D01*
X119507Y1445133D01*
X119757Y1444967D01*
X120049Y1444925D01*
X120382Y1445008D01*
X120632Y1445217D01*
X120882Y1445592D01*
G01X122441Y1444342D02*
X122732Y1444133D01*
X123066Y1444050D01*
X123399Y1444133D01*
X123691Y1444383D01*
X123899Y1444758D01*
X123982Y1445133D01*
Y1445592D01*
X123899Y1445967D01*
X123691Y1446300D01*
X123441Y1446467D01*
X123149Y1446550D01*
X122816Y1446467D01*
X122566Y1446300D01*
X122399Y1446050D01*
X122316Y1445717D01*
X122399Y1445425D01*
X122607Y1445133D01*
X122857Y1444967D01*
X123149Y1444925D01*
X123482Y1445008D01*
X123732Y1445217D01*
X123982Y1445592D01*
G01X112499Y1452317D02*
X109999D01*
Y1453358D01*
X110124Y1453692D01*
X110291Y1453900D01*
X110624Y1453983D01*
X110957Y1453900D01*
X111166Y1453650D01*
X111291Y1453358D01*
Y1452317D01*
G01Y1453358D02*
X112499Y1453983D01*
G01X111999Y1455333D02*
X112291Y1455583D01*
X112457Y1455917D01*
X112499Y1456292D01*
X112457Y1456625D01*
X112249Y1456958D01*
X111999Y1457167D01*
X111749Y1457208D01*
X111457Y1457125D01*
X111249Y1456833D01*
X111166Y1456542D01*
Y1456167D01*
G01Y1456542D02*
X111041Y1456792D01*
X110832Y1457000D01*
X110582Y1457083D01*
X110332Y1457000D01*
X110124Y1456792D01*
X109999Y1456417D01*
X110041Y1456042D01*
X110207Y1455667D01*
G01X112499Y1459350D02*
X109999D01*
X110499Y1458850D01*
G01X112499D02*
Y1459850D01*
G01X110416Y1461658D02*
X110166Y1461908D01*
X110041Y1462200D01*
X109999Y1462533D01*
X110082Y1462950D01*
X110291Y1463242D01*
X110541Y1463325D01*
X110791Y1463283D01*
X110999Y1463117D01*
X111416Y1462283D01*
X111707Y1461908D01*
X112124Y1461658D01*
X112499Y1461575D01*
Y1463325D01*
G01X109499Y1466600D02*
X113499D01*
Y1474000D01*
G01X116599Y1452267D02*
X114099D01*
Y1453308D01*
X114224Y1453642D01*
X114391Y1453850D01*
X114724Y1453933D01*
X115057Y1453850D01*
X115266Y1453600D01*
X115391Y1453308D01*
Y1452267D01*
G01Y1453308D02*
X116599Y1453933D01*
G01X116099Y1455283D02*
X116391Y1455533D01*
X116557Y1455867D01*
X116599Y1456242D01*
X116557Y1456575D01*
X116349Y1456908D01*
X116099Y1457117D01*
X115849Y1457158D01*
X115557Y1457075D01*
X115349Y1456783D01*
X115266Y1456492D01*
Y1456117D01*
G01Y1456492D02*
X115141Y1456742D01*
X114932Y1456950D01*
X114682Y1457033D01*
X114432Y1456950D01*
X114224Y1456742D01*
X114099Y1456367D01*
X114141Y1455992D01*
X114307Y1455617D01*
G01X116599Y1459300D02*
X114099D01*
X114599Y1458800D01*
G01X116599D02*
Y1459800D01*
G01X116099Y1461483D02*
X116391Y1461733D01*
X116557Y1462067D01*
X116599Y1462442D01*
X116557Y1462775D01*
X116349Y1463108D01*
X116099Y1463317D01*
X115849Y1463358D01*
X115557Y1463275D01*
X115349Y1462983D01*
X115266Y1462692D01*
Y1462317D01*
G01Y1462692D02*
X115141Y1462942D01*
X114932Y1463150D01*
X114682Y1463233D01*
X114432Y1463150D01*
X114224Y1462942D01*
X114099Y1462567D01*
X114141Y1462192D01*
X114307Y1461817D01*
G01X113599Y1466550D02*
X117599D01*
Y1473950D01*
G01X113449Y1474050D02*
Y1478050D01*
X106049D01*
G01X123516Y1474850D02*
Y1477350D01*
X124557D01*
X124891Y1477225D01*
X125099Y1477058D01*
X125182Y1476725D01*
X125099Y1476392D01*
X124849Y1476183D01*
X124557Y1476058D01*
X123516D01*
G01X124557D02*
X125182Y1474850D01*
G01X126532Y1475350D02*
X126782Y1475058D01*
X127116Y1474892D01*
X127491Y1474850D01*
X127824Y1474892D01*
X128157Y1475100D01*
X128366Y1475350D01*
X128407Y1475600D01*
X128324Y1475892D01*
X128032Y1476100D01*
X127741Y1476183D01*
X127366D01*
G01X127741D02*
X127991Y1476308D01*
X128199Y1476517D01*
X128282Y1476767D01*
X128199Y1477017D01*
X127991Y1477225D01*
X127616Y1477350D01*
X127241Y1477308D01*
X126866Y1477142D01*
G01X129757Y1476933D02*
X130007Y1477183D01*
X130299Y1477308D01*
X130632Y1477350D01*
X131049Y1477267D01*
X131341Y1477058D01*
X131424Y1476808D01*
X131382Y1476558D01*
X131216Y1476350D01*
X130382Y1475933D01*
X130007Y1475642D01*
X129757Y1475225D01*
X129674Y1474850D01*
X131424D01*
G01X132857Y1476933D02*
X133107Y1477183D01*
X133399Y1477308D01*
X133732Y1477350D01*
X134149Y1477267D01*
X134441Y1477058D01*
X134524Y1476808D01*
X134482Y1476558D01*
X134316Y1476350D01*
X133482Y1475933D01*
X133107Y1475642D01*
X132857Y1475225D01*
X132774Y1474850D01*
X134524D01*
G01X113549Y1478050D02*
Y1474050D01*
X120949D01*
G01X107955Y1497071D02*
Y1489071D01*
X119905D01*
Y1497071D01*
X107955D01*
G01X118749Y1515550D02*
X114749D01*
Y1508150D01*
G01X114599Y1515550D02*
X110599D01*
Y1508150D01*
G01X119905Y1490921D02*
X117905Y1492921D01*
X119905Y1494921D01*
G01X114349Y1532716D02*
Y1530216D01*
G01X113391Y1532716D02*
X115307D01*
G01X116616Y1530216D02*
Y1532716D01*
X117616D01*
X117949Y1532591D01*
X118199Y1532299D01*
X118282Y1531966D01*
X118199Y1531633D01*
X117991Y1531383D01*
X117616Y1531258D01*
X116616D01*
G01X119632Y1530716D02*
X119882Y1530424D01*
X120216Y1530258D01*
X120591Y1530216D01*
X120924Y1530258D01*
X121257Y1530466D01*
X121466Y1530716D01*
X121507Y1530966D01*
X121424Y1531258D01*
X121132Y1531466D01*
X120841Y1531549D01*
X120466D01*
G01X120841D02*
X121091Y1531674D01*
X121299Y1531883D01*
X121382Y1532133D01*
X121299Y1532383D01*
X121091Y1532591D01*
X120716Y1532716D01*
X120341Y1532674D01*
X119966Y1532508D01*
G01X123649Y1530216D02*
Y1532716D01*
X123149Y1532216D01*
G01Y1530216D02*
X124149D01*
G01X117700Y1574500D02*
X128900D01*
G01X117700Y1592500D02*
Y1574500D01*
G01X115500Y1604400D02*
Y1565600D01*
G01X128900Y1592500D02*
X117700D01*
G01X122199Y1634713D02*
Y1640213D01*
G01X130199Y1634713D02*
X122199D01*
G01X116208Y1622867D02*
X116083Y1622617D01*
X116000Y1622325D01*
Y1621992D01*
X116125Y1621617D01*
X116333Y1621325D01*
X116583Y1621117D01*
X117000Y1620950D01*
X117375Y1620908D01*
X117750Y1620992D01*
X118000Y1621117D01*
X118250Y1621367D01*
X118417Y1621658D01*
X118500Y1621950D01*
Y1622242D01*
X118417Y1622533D01*
X118292Y1622783D01*
X118125Y1622992D01*
G01X116417Y1624258D02*
X116167Y1624508D01*
X116042Y1624800D01*
X116000Y1625133D01*
X116083Y1625550D01*
X116292Y1625842D01*
X116542Y1625925D01*
X116792Y1625883D01*
X117000Y1625717D01*
X117417Y1624883D01*
X117708Y1624508D01*
X118125Y1624258D01*
X118500Y1624175D01*
Y1625925D01*
G01Y1628067D02*
X117958Y1628150D01*
X117500Y1628275D01*
X117083Y1628442D01*
X116625Y1628650D01*
X116000Y1628983D01*
Y1627317D01*
G01X118500Y1631750D02*
X116000D01*
X117792Y1630208D01*
Y1632292D01*
G01X113500Y1634700D02*
Y1640200D01*
G01X121500Y1634700D02*
X113500D01*
G01X121500Y1640200D02*
Y1634700D01*
G01X107507Y1622880D02*
X107382Y1622630D01*
X107299Y1622338D01*
Y1622005D01*
X107424Y1621630D01*
X107632Y1621338D01*
X107882Y1621130D01*
X108299Y1620963D01*
X108674Y1620921D01*
X109049Y1621005D01*
X109299Y1621130D01*
X109549Y1621380D01*
X109716Y1621671D01*
X109799Y1621963D01*
Y1622255D01*
X109716Y1622546D01*
X109591Y1622796D01*
X109424Y1623005D01*
G01X107716Y1624271D02*
X107466Y1624521D01*
X107341Y1624813D01*
X107299Y1625146D01*
X107382Y1625563D01*
X107591Y1625855D01*
X107841Y1625938D01*
X108091Y1625896D01*
X108299Y1625730D01*
X108716Y1624896D01*
X109007Y1624521D01*
X109424Y1624271D01*
X109799Y1624188D01*
Y1625938D01*
G01Y1628080D02*
X109257Y1628163D01*
X108799Y1628288D01*
X108382Y1628455D01*
X107924Y1628663D01*
X107299Y1628996D01*
Y1627330D01*
G01X109424Y1630346D02*
X109632Y1630596D01*
X109757Y1630888D01*
X109799Y1631263D01*
X109716Y1631638D01*
X109549Y1631930D01*
X109257Y1632138D01*
X108924Y1632180D01*
X108591Y1632096D01*
X108382Y1631888D01*
X108216Y1631596D01*
X108174Y1631305D01*
X108216Y1631013D01*
X108382Y1630638D01*
X107299Y1630763D01*
Y1631888D01*
G01X104799Y1634713D02*
Y1640213D01*
G01X112799Y1634713D02*
X104799D01*
G01X112799Y1640213D02*
Y1634713D01*
G01X122199Y1652313D02*
X130199D01*
G01X122199Y1646813D02*
Y1652313D01*
G01X121500Y1652300D02*
Y1646800D01*
G01X113500Y1652300D02*
X121500D01*
G01X113500Y1646800D02*
Y1652300D01*
G01X112799Y1652313D02*
Y1646813D01*
G01X104799Y1652313D02*
X112799D01*
G01X104799Y1646813D02*
Y1652313D01*
G01X116499Y1685913D02*
Y1680413D01*
G01X108499D02*
Y1685913D01*
G01Y1668313D02*
Y1673813D01*
G01X116499Y1668313D02*
X108499D01*
G01X116499Y1673813D02*
Y1668313D01*
G01X118149Y1684863D02*
Y1675363D01*
X135849D01*
Y1684863D01*
X118149D01*
G01X119449Y1700613D02*
Y1704613D01*
X112049D01*
G01X108499Y1685913D02*
X116499D01*
G01X103799Y1718613D02*
Y1714613D01*
X111199D01*
G01X103799Y1722613D02*
Y1718613D01*
X111199D01*
G01X127199Y1712550D02*
X113799D01*
G01Y1722550D02*
X127199D01*
G01X113799Y1712550D02*
Y1722550D01*
G01X115483Y1728000D02*
Y1726208D01*
X115650Y1725833D01*
X115983Y1725583D01*
X116400Y1725500D01*
X116817Y1725583D01*
X117150Y1725833D01*
X117317Y1726208D01*
Y1728000D01*
G01X118583Y1726000D02*
X118833Y1725708D01*
X119167Y1725542D01*
X119542Y1725500D01*
X119875Y1725542D01*
X120208Y1725750D01*
X120417Y1726000D01*
X120458Y1726250D01*
X120375Y1726542D01*
X120083Y1726750D01*
X119792Y1726833D01*
X119417D01*
G01X119792D02*
X120042Y1726958D01*
X120250Y1727167D01*
X120333Y1727417D01*
X120250Y1727667D01*
X120042Y1727875D01*
X119667Y1728000D01*
X119292Y1727958D01*
X118917Y1727792D01*
G01X122600Y1725500D02*
Y1728000D01*
X122100Y1727500D01*
G01Y1725500D02*
X123100D01*
G01X116999Y1841150D02*
X126999D01*
G01Y1834150D02*
X116999D01*
G01X121999D02*
Y1841150D01*
G01X116999Y1830717D02*
X126999D01*
Y1827383D01*
X126499Y1826050D01*
X125832Y1825050D01*
X124832Y1824217D01*
X123665Y1823550D01*
X121999Y1823383D01*
X120332Y1823550D01*
X119166Y1824217D01*
X118165Y1825050D01*
X117499Y1826050D01*
X116999Y1827383D01*
Y1830717D01*
G01Y1820117D02*
X126999D01*
Y1816783D01*
X126499Y1815450D01*
X125832Y1814450D01*
X124832Y1813617D01*
X123665Y1812950D01*
X121999Y1812783D01*
X120332Y1812950D01*
X119166Y1813617D01*
X118165Y1814450D01*
X117499Y1815450D01*
X116999Y1816783D01*
Y1820117D01*
G01Y1805850D02*
X126999D01*
X124999Y1807850D01*
G01X116999D02*
Y1803850D01*
G01X126999Y1795250D02*
X126666Y1796584D01*
X125832Y1797583D01*
X124832Y1798250D01*
X123499Y1798750D01*
X121999Y1798917D01*
X120499Y1798750D01*
X119166Y1798250D01*
X118165Y1797583D01*
X117332Y1796584D01*
X116999Y1795250D01*
X117332Y1793917D01*
X118165Y1792917D01*
X119166Y1792250D01*
X120499Y1791750D01*
X121999Y1791583D01*
X123499Y1791750D01*
X124832Y1792250D01*
X125832Y1792917D01*
X126666Y1793917D01*
X126999Y1795250D01*
G01X113666Y1789650D02*
Y1779650D01*
G01X126999Y1777383D02*
X116999D01*
Y1770717D01*
G01Y1760117D02*
Y1766783D01*
X126999D01*
Y1760117D01*
G01X122166Y1762783D02*
Y1766783D01*
G01X116999Y1756517D02*
X126999D01*
Y1753183D01*
X126499Y1751850D01*
X125832Y1750850D01*
X124832Y1750017D01*
X123665Y1749350D01*
X121999Y1749183D01*
X120332Y1749350D01*
X119166Y1750017D01*
X118165Y1750850D01*
X117499Y1751850D01*
X116999Y1753183D01*
Y1756517D01*
G01X115859Y1847546D02*
X115609Y1847671D01*
X115317Y1847754D01*
X114984D01*
X114609Y1847629D01*
X114317Y1847421D01*
X114109Y1847171D01*
X113942Y1846754D01*
X113900Y1846379D01*
X113984Y1846004D01*
X114109Y1845754D01*
X114359Y1845504D01*
X114650Y1845337D01*
X114942Y1845254D01*
X115234D01*
X115525Y1845337D01*
X115775Y1845462D01*
X115984Y1845629D01*
G01X118042Y1845254D02*
Y1847754D01*
X117542Y1847254D01*
G01Y1845254D02*
X118542D01*
G01X121142D02*
X121434Y1845296D01*
X121767Y1845421D01*
X121975Y1845629D01*
X122059Y1845921D01*
X121975Y1846212D01*
X121725Y1846462D01*
X121350Y1846587D01*
X120934D01*
X120684Y1846671D01*
X120475Y1846879D01*
X120392Y1847171D01*
X120517Y1847462D01*
X120809Y1847671D01*
X121142Y1847754D01*
X121475Y1847671D01*
X121767Y1847462D01*
X121892Y1847171D01*
X121809Y1846879D01*
X121600Y1846671D01*
X121350Y1846587D01*
X120934D01*
X120559Y1846462D01*
X120309Y1846212D01*
X120225Y1845921D01*
X120309Y1845629D01*
X120517Y1845421D01*
X120850Y1845296D01*
X121142Y1845254D01*
G01X123450Y1847337D02*
X123700Y1847587D01*
X123992Y1847712D01*
X124325Y1847754D01*
X124742Y1847671D01*
X125034Y1847462D01*
X125117Y1847212D01*
X125075Y1846962D01*
X124909Y1846754D01*
X124075Y1846337D01*
X123700Y1846046D01*
X123450Y1845629D01*
X123367Y1845254D01*
X125117D01*
G01X115859Y1851046D02*
X115609Y1851171D01*
X115317Y1851254D01*
X114984D01*
X114609Y1851129D01*
X114317Y1850921D01*
X114109Y1850671D01*
X113942Y1850254D01*
X113900Y1849879D01*
X113984Y1849504D01*
X114109Y1849254D01*
X114359Y1849004D01*
X114650Y1848837D01*
X114942Y1848754D01*
X115234D01*
X115525Y1848837D01*
X115775Y1848962D01*
X115984Y1849129D01*
G01X118042Y1848754D02*
Y1851254D01*
X117542Y1850754D01*
G01Y1848754D02*
X118542D01*
G01X121142D02*
X121434Y1848796D01*
X121767Y1848921D01*
X121975Y1849129D01*
X122059Y1849421D01*
X121975Y1849712D01*
X121725Y1849962D01*
X121350Y1850087D01*
X120934D01*
X120684Y1850171D01*
X120475Y1850379D01*
X120392Y1850671D01*
X120517Y1850962D01*
X120809Y1851171D01*
X121142Y1851254D01*
X121475Y1851171D01*
X121767Y1850962D01*
X121892Y1850671D01*
X121809Y1850379D01*
X121600Y1850171D01*
X121350Y1850087D01*
X120934D01*
X120559Y1849962D01*
X120309Y1849712D01*
X120225Y1849421D01*
X120309Y1849129D01*
X120517Y1848921D01*
X120850Y1848796D01*
X121142Y1848754D01*
G01X123325Y1849254D02*
X123575Y1848962D01*
X123909Y1848796D01*
X124284Y1848754D01*
X124617Y1848796D01*
X124950Y1849004D01*
X125159Y1849254D01*
X125200Y1849504D01*
X125117Y1849796D01*
X124825Y1850004D01*
X124534Y1850087D01*
X124159D01*
G01X124534D02*
X124784Y1850212D01*
X124992Y1850421D01*
X125075Y1850671D01*
X124992Y1850921D01*
X124784Y1851129D01*
X124409Y1851254D01*
X124034Y1851212D01*
X123659Y1851046D01*
G01X122699Y1861050D02*
X111499D01*
G01X122699Y1879050D02*
Y1861050D01*
G01X111499Y1879050D02*
X122699D01*
G01Y1881550D02*
X111499D01*
G01X122699Y1899550D02*
Y1881550D01*
G01X111499Y1899550D02*
X122699D01*
G01X121529Y1928775D02*
Y1931275D01*
X122529D01*
X122862Y1931150D01*
X123112Y1930858D01*
X123195Y1930525D01*
X123112Y1930192D01*
X122904Y1929942D01*
X122529Y1929817D01*
X121529D01*
G01X124629Y1931275D02*
Y1928775D01*
X126295D01*
G01X127770Y1929817D02*
X128062Y1930108D01*
X128312Y1930275D01*
X128645Y1930358D01*
X128937Y1930275D01*
X129145Y1930108D01*
X129312Y1929858D01*
X129354Y1929567D01*
X129312Y1929317D01*
X129145Y1929067D01*
X128895Y1928858D01*
X128604Y1928775D01*
X128270Y1928858D01*
X127979Y1929108D01*
X127812Y1929483D01*
X127770Y1929900D01*
X127854Y1930442D01*
X127979Y1930733D01*
X128187Y1931025D01*
X128479Y1931233D01*
X128770Y1931275D01*
X129062Y1931192D01*
X129270Y1930983D01*
G01X110566Y1972050D02*
Y1974550D01*
X111566D01*
X111899Y1974425D01*
X112149Y1974133D01*
X112232Y1973800D01*
X112149Y1973467D01*
X111941Y1973217D01*
X111566Y1973092D01*
X110566D01*
G01X113666Y1974550D02*
Y1972050D01*
X115332D01*
G01X116682Y1972425D02*
X116932Y1972217D01*
X117224Y1972092D01*
X117599Y1972050D01*
X117974Y1972133D01*
X118266Y1972300D01*
X118474Y1972592D01*
X118516Y1972925D01*
X118432Y1973258D01*
X118224Y1973467D01*
X117932Y1973633D01*
X117641Y1973675D01*
X117349Y1973633D01*
X116974Y1973467D01*
X117099Y1974550D01*
X118224D01*
G01X127038Y37041D02*
Y39541D01*
G01X128788D02*
Y37041D01*
G01Y38291D02*
X127038D01*
G01X130096Y37416D02*
X130346Y37208D01*
X130638Y37083D01*
X131013Y37041D01*
X131388Y37124D01*
X131680Y37291D01*
X131888Y37583D01*
X131930Y37916D01*
X131846Y38249D01*
X131638Y38458D01*
X131346Y38624D01*
X131055Y38666D01*
X130763Y38624D01*
X130388Y38458D01*
X130513Y39541D01*
X131638D01*
G01X145521Y100877D02*
X163521D01*
G01X145521Y112077D02*
Y100877D01*
G01X142521D02*
Y112077D01*
G01X145521Y128077D02*
Y139277D01*
G01X142521D02*
Y128077D01*
G01X145521Y139277D02*
X163521D01*
G01X135500Y142017D02*
X133000D01*
Y143017D01*
X133125Y143350D01*
X133417Y143600D01*
X133750Y143683D01*
X134083Y143600D01*
X134333Y143392D01*
X134458Y143017D01*
Y142017D01*
G01X133000Y145950D02*
X135500D01*
G01X133000Y144992D02*
Y146908D01*
G01X133208Y149967D02*
X133083Y149717D01*
X133000Y149425D01*
Y149092D01*
X133125Y148717D01*
X133333Y148425D01*
X133583Y148217D01*
X134000Y148050D01*
X134375Y148008D01*
X134750Y148092D01*
X135000Y148217D01*
X135250Y148467D01*
X135417Y148758D01*
X135500Y149050D01*
Y149342D01*
X135417Y149633D01*
X135292Y149883D01*
X135125Y150092D01*
G01X135500Y152650D02*
X133000D01*
X134792Y151108D01*
Y153192D01*
G01X144016Y177550D02*
Y180050D01*
X145057D01*
X145391Y179925D01*
X145599Y179758D01*
X145682Y179425D01*
X145599Y179092D01*
X145349Y178883D01*
X145057Y178758D01*
X144016D01*
G01X145057D02*
X145682Y177550D01*
G01X147157Y179633D02*
X147407Y179883D01*
X147699Y180008D01*
X148032Y180050D01*
X148449Y179967D01*
X148741Y179758D01*
X148824Y179508D01*
X148782Y179258D01*
X148616Y179050D01*
X147782Y178633D01*
X147407Y178342D01*
X147157Y177925D01*
X147074Y177550D01*
X148824D01*
G01X150257Y179633D02*
X150507Y179883D01*
X150799Y180008D01*
X151132Y180050D01*
X151549Y179967D01*
X151841Y179758D01*
X151924Y179508D01*
X151882Y179258D01*
X151716Y179050D01*
X150882Y178633D01*
X150507Y178342D01*
X150257Y177925D01*
X150174Y177550D01*
X151924D01*
G01X154066D02*
X154149Y178092D01*
X154274Y178550D01*
X154441Y178967D01*
X154649Y179425D01*
X154982Y180050D01*
X153316D01*
G01X144016Y173550D02*
Y176050D01*
X145057D01*
X145391Y175925D01*
X145599Y175758D01*
X145682Y175425D01*
X145599Y175092D01*
X145349Y174883D01*
X145057Y174758D01*
X144016D01*
G01X145057D02*
X145682Y173550D01*
G01X147157Y175633D02*
X147407Y175883D01*
X147699Y176008D01*
X148032Y176050D01*
X148449Y175967D01*
X148741Y175758D01*
X148824Y175508D01*
X148782Y175258D01*
X148616Y175050D01*
X147782Y174633D01*
X147407Y174342D01*
X147157Y173925D01*
X147074Y173550D01*
X148824D01*
G01X150257Y175633D02*
X150507Y175883D01*
X150799Y176008D01*
X151132Y176050D01*
X151549Y175967D01*
X151841Y175758D01*
X151924Y175508D01*
X151882Y175258D01*
X151716Y175050D01*
X150882Y174633D01*
X150507Y174342D01*
X150257Y173925D01*
X150174Y173550D01*
X151924D01*
G01X153441Y173842D02*
X153732Y173633D01*
X154066Y173550D01*
X154399Y173633D01*
X154691Y173883D01*
X154899Y174258D01*
X154982Y174633D01*
Y175092D01*
X154899Y175467D01*
X154691Y175800D01*
X154441Y175967D01*
X154149Y176050D01*
X153816Y175967D01*
X153566Y175800D01*
X153399Y175550D01*
X153316Y175217D01*
X153399Y174925D01*
X153607Y174633D01*
X153857Y174467D01*
X154149Y174425D01*
X154482Y174508D01*
X154732Y174717D01*
X154982Y175092D01*
G01X144623Y185817D02*
Y347017D01*
X158223D01*
Y359967D01*
X176423D01*
Y347017D01*
X205323D01*
Y336667D01*
X198623D01*
Y196167D01*
X205323D01*
Y185817D01*
X176423D01*
Y172867D01*
X158223D01*
Y185817D01*
X144623D01*
G01X137667Y271988D02*
X137875Y272321D01*
X138000Y272696D01*
Y273030D01*
X137875Y273363D01*
X137667Y273613D01*
X137375Y273738D01*
X137083Y273655D01*
X136833Y273446D01*
X136667Y273071D01*
X136583Y272571D01*
X136417Y272280D01*
X136125Y272155D01*
X135833Y272238D01*
X135625Y272446D01*
X135500Y272738D01*
Y273030D01*
X135583Y273321D01*
X135792Y273571D01*
G01X138000Y275046D02*
X135500D01*
G01Y276630D02*
X137042Y275046D01*
G01X138000Y276880D02*
X136333Y275755D01*
G01X135500Y279063D02*
X138000D01*
G01X135500Y278105D02*
Y280021D01*
G01X138000Y282163D02*
X135500D01*
X136000Y281663D01*
G01X138000D02*
Y282663D01*
G01X135500Y285263D02*
X135583Y284930D01*
X135792Y284680D01*
X136042Y284513D01*
X136375Y284388D01*
X136750Y284346D01*
X137125Y284388D01*
X137458Y284513D01*
X137708Y284680D01*
X137917Y284930D01*
X138000Y285263D01*
X137917Y285596D01*
X137708Y285846D01*
X137458Y286013D01*
X137125Y286138D01*
X136750Y286180D01*
X136375Y286138D01*
X136042Y286013D01*
X135792Y285846D01*
X135583Y285596D01*
X135500Y285263D01*
G01X144128Y406167D02*
X141628D01*
Y407208D01*
X141753Y407542D01*
X141920Y407750D01*
X142253Y407833D01*
X142586Y407750D01*
X142795Y407500D01*
X142920Y407208D01*
Y406167D01*
G01Y407208D02*
X144128Y407833D01*
G01X142045Y409308D02*
X141795Y409558D01*
X141670Y409850D01*
X141628Y410183D01*
X141711Y410600D01*
X141920Y410892D01*
X142170Y410975D01*
X142420Y410933D01*
X142628Y410767D01*
X143045Y409933D01*
X143336Y409558D01*
X143753Y409308D01*
X144128Y409225D01*
Y410975D01*
G01Y413200D02*
X144086Y413492D01*
X143961Y413825D01*
X143753Y414033D01*
X143461Y414117D01*
X143170Y414033D01*
X142920Y413783D01*
X142795Y413408D01*
Y412992D01*
X142711Y412742D01*
X142503Y412533D01*
X142211Y412450D01*
X141920Y412575D01*
X141711Y412867D01*
X141628Y413200D01*
X141711Y413533D01*
X141920Y413825D01*
X142211Y413950D01*
X142503Y413867D01*
X142711Y413658D01*
X142795Y413408D01*
Y412992D01*
X142920Y412617D01*
X143170Y412367D01*
X143461Y412283D01*
X143753Y412367D01*
X143961Y412575D01*
X144086Y412908D01*
X144128Y413200D01*
G01Y416217D02*
X143586Y416300D01*
X143128Y416425D01*
X142711Y416592D01*
X142253Y416800D01*
X141628Y417133D01*
Y415467D01*
G01X144111Y404587D02*
Y402795D01*
X144278Y402420D01*
X144611Y402170D01*
X145028Y402087D01*
X145445Y402170D01*
X145778Y402420D01*
X145945Y402795D01*
Y404587D01*
G01X148628Y402087D02*
Y404587D01*
X147086Y402795D01*
X149170D01*
G01X150436Y404170D02*
X150686Y404420D01*
X150978Y404545D01*
X151311Y404587D01*
X151728Y404504D01*
X152020Y404295D01*
X152103Y404045D01*
X152061Y403795D01*
X151895Y403587D01*
X151061Y403170D01*
X150686Y402879D01*
X150436Y402462D01*
X150353Y402087D01*
X152103D01*
G01X132299Y425113D02*
Y421113D01*
X139699D01*
G01X132299Y429113D02*
Y425113D01*
X139699D01*
G01X142999Y423413D02*
Y436813D01*
G01X152999Y423413D02*
X142999D01*
G01X139499Y438413D02*
X143499D01*
Y445813D01*
G01X144499Y438413D02*
X148499D01*
Y445813D01*
G01X142999Y436813D02*
X152999D01*
G01X136999Y449813D02*
Y455313D01*
G01X144999Y449813D02*
X136999D01*
G01X144999Y455313D02*
Y449813D01*
G01X128708Y453767D02*
X128583Y453517D01*
X128500Y453225D01*
Y452892D01*
X128625Y452517D01*
X128833Y452225D01*
X129083Y452017D01*
X129500Y451850D01*
X129875Y451808D01*
X130250Y451892D01*
X130500Y452017D01*
X130750Y452267D01*
X130917Y452558D01*
X131000Y452850D01*
Y453142D01*
X130917Y453433D01*
X130792Y453683D01*
X130625Y453892D01*
G01X130500Y455033D02*
X130792Y455283D01*
X130958Y455617D01*
X131000Y455992D01*
X130958Y456325D01*
X130750Y456658D01*
X130500Y456867D01*
X130250Y456908D01*
X129958Y456825D01*
X129750Y456533D01*
X129667Y456242D01*
Y455867D01*
G01Y456242D02*
X129542Y456492D01*
X129333Y456700D01*
X129083Y456783D01*
X128833Y456700D01*
X128625Y456492D01*
X128500Y456117D01*
X128542Y455742D01*
X128708Y455367D01*
G01X128917Y458258D02*
X128667Y458508D01*
X128542Y458800D01*
X128500Y459133D01*
X128583Y459550D01*
X128792Y459842D01*
X129042Y459925D01*
X129292Y459883D01*
X129500Y459717D01*
X129917Y458883D01*
X130208Y458508D01*
X130625Y458258D01*
X131000Y458175D01*
Y459925D01*
G01Y462150D02*
X128500D01*
X129000Y461650D01*
G01X131000D02*
Y462650D01*
G01X136999Y468050D02*
X162999D01*
G01X136999Y481050D02*
Y468050D01*
G01X144999Y467413D02*
Y461913D01*
G01X136999Y467413D02*
X144999D01*
G01X136999Y461913D02*
Y467413D01*
G01X129207Y488817D02*
X129082Y488567D01*
X128999Y488275D01*
Y487942D01*
X129124Y487567D01*
X129332Y487275D01*
X129582Y487067D01*
X129999Y486900D01*
X130374Y486858D01*
X130749Y486942D01*
X130999Y487067D01*
X131249Y487317D01*
X131416Y487608D01*
X131499Y487900D01*
Y488192D01*
X131416Y488483D01*
X131291Y488733D01*
X131124Y488942D01*
G01X130999Y490083D02*
X131291Y490333D01*
X131457Y490667D01*
X131499Y491042D01*
X131457Y491375D01*
X131249Y491708D01*
X130999Y491917D01*
X130749Y491958D01*
X130457Y491875D01*
X130249Y491583D01*
X130166Y491292D01*
Y490917D01*
G01Y491292D02*
X130041Y491542D01*
X129832Y491750D01*
X129582Y491833D01*
X129332Y491750D01*
X129124Y491542D01*
X128999Y491167D01*
X129041Y490792D01*
X129207Y490417D01*
G01X131499Y494100D02*
X128999D01*
X129499Y493600D01*
G01X131499D02*
Y494600D01*
G01X130457Y496408D02*
X130166Y496700D01*
X129999Y496950D01*
X129916Y497283D01*
X129999Y497575D01*
X130166Y497783D01*
X130416Y497950D01*
X130707Y497992D01*
X130957Y497950D01*
X131207Y497783D01*
X131416Y497533D01*
X131499Y497242D01*
X131416Y496908D01*
X131166Y496617D01*
X130791Y496450D01*
X130374Y496408D01*
X129832Y496492D01*
X129541Y496617D01*
X129249Y496825D01*
X129041Y497117D01*
X128999Y497408D01*
X129082Y497700D01*
X129291Y497908D01*
G01X162999Y481050D02*
X136999D01*
G01X133208Y488267D02*
X133083Y488017D01*
X133000Y487725D01*
Y487392D01*
X133125Y487017D01*
X133333Y486725D01*
X133583Y486517D01*
X134000Y486350D01*
X134375Y486308D01*
X134750Y486392D01*
X135000Y486517D01*
X135250Y486767D01*
X135417Y487058D01*
X135500Y487350D01*
Y487642D01*
X135417Y487933D01*
X135292Y488183D01*
X135125Y488392D01*
G01X135000Y489533D02*
X135292Y489783D01*
X135458Y490117D01*
X135500Y490492D01*
X135458Y490825D01*
X135250Y491158D01*
X135000Y491367D01*
X134750Y491408D01*
X134458Y491325D01*
X134250Y491033D01*
X134167Y490742D01*
Y490367D01*
G01Y490742D02*
X134042Y490992D01*
X133833Y491200D01*
X133583Y491283D01*
X133333Y491200D01*
X133125Y490992D01*
X133000Y490617D01*
X133042Y490242D01*
X133208Y489867D01*
G01X135500Y493550D02*
X133000D01*
X133500Y493050D01*
G01X135500D02*
Y494050D01*
G01Y496567D02*
X134958Y496650D01*
X134500Y496775D01*
X134083Y496942D01*
X133625Y497150D01*
X133000Y497483D01*
Y495817D01*
G01X142499Y495413D02*
Y500913D01*
G01Y483313D02*
Y488813D01*
G01X150499Y483313D02*
X142499D01*
G01X137249Y501613D02*
X163249D01*
G01X137249Y514613D02*
Y501613D01*
G01X163249Y514613D02*
X137249D01*
G01X142499Y500913D02*
X150499D01*
G01X128000Y527517D02*
X125500D01*
Y528558D01*
X125625Y528892D01*
X125792Y529100D01*
X126125Y529183D01*
X126458Y529100D01*
X126667Y528850D01*
X126792Y528558D01*
Y527517D01*
G01Y528558D02*
X128000Y529183D01*
G01Y531950D02*
X125500D01*
X127292Y530408D01*
Y532492D01*
G01X125500Y534550D02*
X125583Y534217D01*
X125792Y533967D01*
X126042Y533800D01*
X126375Y533675D01*
X126750Y533633D01*
X127125Y533675D01*
X127458Y533800D01*
X127708Y533967D01*
X127917Y534217D01*
X128000Y534550D01*
X127917Y534883D01*
X127708Y535133D01*
X127458Y535300D01*
X127125Y535425D01*
X126750Y535467D01*
X126375Y535425D01*
X126042Y535300D01*
X125792Y535133D01*
X125583Y534883D01*
X125500Y534550D01*
G01X125917Y536858D02*
X125667Y537108D01*
X125542Y537400D01*
X125500Y537733D01*
X125583Y538150D01*
X125792Y538442D01*
X126042Y538525D01*
X126292Y538483D01*
X126500Y538317D01*
X126917Y537483D01*
X127208Y537108D01*
X127625Y536858D01*
X128000Y536775D01*
Y538525D01*
G01X134000Y526800D02*
X138000D01*
Y534200D01*
G01X132500Y529900D02*
X132458Y529567D01*
X132292Y529275D01*
X132042Y529025D01*
X131750Y528858D01*
X131417Y528775D01*
X131083D01*
X130750Y528858D01*
X130458Y529025D01*
X130208Y529275D01*
X130042Y529567D01*
X130000Y529900D01*
X130042Y530233D01*
X130208Y530525D01*
X130458Y530775D01*
X130750Y530942D01*
X131083Y531025D01*
X131417D01*
X131750Y530942D01*
X132042Y530775D01*
X132292Y530525D01*
X132458Y530233D01*
X132500Y529900D01*
G01X131833Y530233D02*
X132500Y530733D01*
G01Y532917D02*
X131958Y533000D01*
X131500Y533125D01*
X131083Y533292D01*
X130625Y533500D01*
X130000Y533833D01*
Y532167D01*
G01X132000Y535183D02*
X132292Y535433D01*
X132458Y535767D01*
X132500Y536142D01*
X132458Y536475D01*
X132250Y536808D01*
X132000Y537017D01*
X131750Y537058D01*
X131458Y536975D01*
X131250Y536683D01*
X131167Y536392D01*
Y536017D01*
G01Y536392D02*
X131042Y536642D01*
X130833Y536850D01*
X130583Y536933D01*
X130333Y536850D01*
X130125Y536642D01*
X130000Y536267D01*
X130042Y535892D01*
X130208Y535517D01*
G01X138500Y542300D02*
Y528300D01*
G01D02*
X151500D01*
G01X128400Y557000D02*
X128067Y557042D01*
X127775Y557208D01*
X127525Y557458D01*
X127358Y557750D01*
X127275Y558083D01*
Y558417D01*
X127358Y558750D01*
X127525Y559042D01*
X127775Y559292D01*
X128067Y559458D01*
X128400Y559500D01*
X128733Y559458D01*
X129025Y559292D01*
X129275Y559042D01*
X129442Y558750D01*
X129525Y558417D01*
Y558083D01*
X129442Y557750D01*
X129275Y557458D01*
X129025Y557208D01*
X128733Y557042D01*
X128400Y557000D01*
G01X128733Y557667D02*
X129233Y557000D01*
G01X131417D02*
X131500Y557542D01*
X131625Y558000D01*
X131792Y558417D01*
X132000Y558875D01*
X132333Y559500D01*
X130667D01*
G01X133808Y559083D02*
X134058Y559333D01*
X134350Y559458D01*
X134683Y559500D01*
X135100Y559417D01*
X135392Y559208D01*
X135475Y558958D01*
X135433Y558708D01*
X135267Y558500D01*
X134433Y558083D01*
X134058Y557792D01*
X133808Y557375D01*
X133725Y557000D01*
X135475D01*
G01X137800Y547300D02*
X149200D01*
G01X137800Y560700D02*
Y547300D01*
G01X149200Y543000D02*
Y547000D01*
X141800D01*
G01X151500Y542300D02*
X138500D01*
G01X143617Y577763D02*
Y575263D01*
X145283D01*
G01X148383D02*
X146717D01*
Y577763D01*
X148383D01*
G01X147717Y576555D02*
X146717D01*
G01X149733Y575263D02*
Y577763D01*
X150567D01*
X150900Y577638D01*
X151150Y577471D01*
X151358Y577221D01*
X151525Y576930D01*
X151567Y576513D01*
X151525Y576096D01*
X151358Y575805D01*
X151150Y575555D01*
X150900Y575388D01*
X150567Y575263D01*
X149733D01*
G01X153042Y575555D02*
X153333Y575346D01*
X153667Y575263D01*
X154000Y575346D01*
X154292Y575596D01*
X154500Y575971D01*
X154583Y576346D01*
Y576805D01*
X154500Y577180D01*
X154292Y577513D01*
X154042Y577680D01*
X153750Y577763D01*
X153417Y577680D01*
X153167Y577513D01*
X153000Y577263D01*
X152917Y576930D01*
X153000Y576638D01*
X153208Y576346D01*
X153458Y576180D01*
X153750Y576138D01*
X154083Y576221D01*
X154333Y576430D01*
X154583Y576805D01*
G01X149200Y560700D02*
X137800D01*
G01X139516Y568550D02*
Y571050D01*
X140557D01*
X140891Y570925D01*
X141099Y570758D01*
X141182Y570425D01*
X141099Y570092D01*
X140849Y569883D01*
X140557Y569758D01*
X139516D01*
G01X140557D02*
X141182Y568550D01*
G01X142657Y570633D02*
X142907Y570883D01*
X143199Y571008D01*
X143532Y571050D01*
X143949Y570967D01*
X144241Y570758D01*
X144324Y570508D01*
X144282Y570258D01*
X144116Y570050D01*
X143282Y569633D01*
X142907Y569342D01*
X142657Y568925D01*
X142574Y568550D01*
X144324D01*
G01X146549D02*
Y571050D01*
X146049Y570550D01*
G01Y568550D02*
X147049D01*
G01X148732Y569050D02*
X148982Y568758D01*
X149316Y568592D01*
X149691Y568550D01*
X150024Y568592D01*
X150357Y568800D01*
X150566Y569050D01*
X150607Y569300D01*
X150524Y569592D01*
X150232Y569800D01*
X149941Y569883D01*
X149566D01*
G01X149941D02*
X150191Y570008D01*
X150399Y570217D01*
X150482Y570467D01*
X150399Y570717D01*
X150191Y570925D01*
X149816Y571050D01*
X149441Y571008D01*
X149066Y570842D01*
G01X139516Y564550D02*
Y567050D01*
X140557D01*
X140891Y566925D01*
X141099Y566758D01*
X141182Y566425D01*
X141099Y566092D01*
X140849Y565883D01*
X140557Y565758D01*
X139516D01*
G01X140557D02*
X141182Y564550D01*
G01X142657Y566633D02*
X142907Y566883D01*
X143199Y567008D01*
X143532Y567050D01*
X143949Y566967D01*
X144241Y566758D01*
X144324Y566508D01*
X144282Y566258D01*
X144116Y566050D01*
X143282Y565633D01*
X142907Y565342D01*
X142657Y564925D01*
X142574Y564550D01*
X144324D01*
G01X146549D02*
Y567050D01*
X146049Y566550D01*
G01Y564550D02*
X147049D01*
G01X148732Y564925D02*
X148982Y564717D01*
X149274Y564592D01*
X149649Y564550D01*
X150024Y564633D01*
X150316Y564800D01*
X150524Y565092D01*
X150566Y565425D01*
X150482Y565758D01*
X150274Y565967D01*
X149982Y566133D01*
X149691Y566175D01*
X149399Y566133D01*
X149024Y565967D01*
X149149Y567050D01*
X150274D01*
G01X144623Y591329D02*
Y752529D01*
X158223D01*
Y765479D01*
X176423D01*
Y752529D01*
X205323D01*
Y742179D01*
X198623D01*
Y601679D01*
X205323D01*
Y591329D01*
X176423D01*
Y578379D01*
X158223D01*
Y591329D01*
X144623D01*
G01X141167Y675038D02*
X141375Y675371D01*
X141500Y675746D01*
Y676080D01*
X141375Y676413D01*
X141167Y676663D01*
X140875Y676788D01*
X140583Y676705D01*
X140333Y676496D01*
X140167Y676121D01*
X140083Y675621D01*
X139917Y675330D01*
X139625Y675205D01*
X139333Y675288D01*
X139125Y675496D01*
X139000Y675788D01*
Y676080D01*
X139083Y676371D01*
X139292Y676621D01*
G01X141500Y678096D02*
X139000D01*
G01Y679680D02*
X140542Y678096D01*
G01X141500Y679930D02*
X139833Y678805D01*
G01X139000Y682113D02*
X141500D01*
G01X139000Y681155D02*
Y683071D01*
G01X141208Y684505D02*
X141417Y684796D01*
X141500Y685130D01*
X141417Y685463D01*
X141167Y685755D01*
X140792Y685963D01*
X140417Y686046D01*
X139958D01*
X139583Y685963D01*
X139250Y685755D01*
X139083Y685505D01*
X139000Y685213D01*
X139083Y684880D01*
X139250Y684630D01*
X139500Y684463D01*
X139833Y684380D01*
X140125Y684463D01*
X140417Y684671D01*
X140583Y684921D01*
X140625Y685213D01*
X140542Y685546D01*
X140333Y685796D01*
X139958Y686046D01*
G01X143708Y852767D02*
X143583Y852517D01*
X143500Y852225D01*
Y851892D01*
X143625Y851517D01*
X143833Y851225D01*
X144083Y851017D01*
X144500Y850850D01*
X144875Y850808D01*
X145250Y850892D01*
X145500Y851017D01*
X145750Y851267D01*
X145917Y851558D01*
X146000Y851850D01*
Y852142D01*
X145917Y852433D01*
X145792Y852683D01*
X145625Y852892D01*
G01X145500Y854033D02*
X145792Y854283D01*
X145958Y854617D01*
X146000Y854992D01*
X145958Y855325D01*
X145750Y855658D01*
X145500Y855867D01*
X145250Y855908D01*
X144958Y855825D01*
X144750Y855533D01*
X144667Y855242D01*
Y854867D01*
G01Y855242D02*
X144542Y855492D01*
X144333Y855700D01*
X144083Y855783D01*
X143833Y855700D01*
X143625Y855492D01*
X143500Y855117D01*
X143542Y854742D01*
X143708Y854367D01*
G01X143500Y858050D02*
X143583Y857717D01*
X143792Y857467D01*
X144042Y857300D01*
X144375Y857175D01*
X144750Y857133D01*
X145125Y857175D01*
X145458Y857300D01*
X145708Y857467D01*
X145917Y857717D01*
X146000Y858050D01*
X145917Y858383D01*
X145708Y858633D01*
X145458Y858800D01*
X145125Y858925D01*
X144750Y858967D01*
X144375Y858925D01*
X144042Y858800D01*
X143792Y858633D01*
X143583Y858383D01*
X143500Y858050D01*
G01X146000Y861067D02*
X145458Y861150D01*
X145000Y861275D01*
X144583Y861442D01*
X144125Y861650D01*
X143500Y861983D01*
Y860317D01*
G01X138516Y975050D02*
Y977550D01*
X139557D01*
X139891Y977425D01*
X140099Y977258D01*
X140182Y976925D01*
X140099Y976592D01*
X139849Y976383D01*
X139557Y976258D01*
X138516D01*
G01X139557D02*
X140182Y975050D01*
G01X142449D02*
Y977550D01*
X141949Y977050D01*
G01Y975050D02*
X142949D01*
G01X144841Y975342D02*
X145132Y975133D01*
X145466Y975050D01*
X145799Y975133D01*
X146091Y975383D01*
X146299Y975758D01*
X146382Y976133D01*
Y976592D01*
X146299Y976967D01*
X146091Y977300D01*
X145841Y977467D01*
X145549Y977550D01*
X145216Y977467D01*
X144966Y977300D01*
X144799Y977050D01*
X144716Y976717D01*
X144799Y976425D01*
X145007Y976133D01*
X145257Y975967D01*
X145549Y975925D01*
X145882Y976008D01*
X146132Y976217D01*
X146382Y976592D01*
G01X147941Y975342D02*
X148232Y975133D01*
X148566Y975050D01*
X148899Y975133D01*
X149191Y975383D01*
X149399Y975758D01*
X149482Y976133D01*
Y976592D01*
X149399Y976967D01*
X149191Y977300D01*
X148941Y977467D01*
X148649Y977550D01*
X148316Y977467D01*
X148066Y977300D01*
X147899Y977050D01*
X147816Y976717D01*
X147899Y976425D01*
X148107Y976133D01*
X148357Y975967D01*
X148649Y975925D01*
X148982Y976008D01*
X149232Y976217D01*
X149482Y976592D01*
G01X138516Y971050D02*
Y973550D01*
X139557D01*
X139891Y973425D01*
X140099Y973258D01*
X140182Y972925D01*
X140099Y972592D01*
X139849Y972383D01*
X139557Y972258D01*
X138516D01*
G01X139557D02*
X140182Y971050D01*
G01X141657Y973133D02*
X141907Y973383D01*
X142199Y973508D01*
X142532Y973550D01*
X142949Y973467D01*
X143241Y973258D01*
X143324Y973008D01*
X143282Y972758D01*
X143116Y972550D01*
X142282Y972133D01*
X141907Y971842D01*
X141657Y971425D01*
X141574Y971050D01*
X143324D01*
G01X145549Y973550D02*
X145216Y973467D01*
X144966Y973258D01*
X144799Y973008D01*
X144674Y972675D01*
X144632Y972300D01*
X144674Y971925D01*
X144799Y971592D01*
X144966Y971342D01*
X145216Y971133D01*
X145549Y971050D01*
X145882Y971133D01*
X146132Y971342D01*
X146299Y971592D01*
X146424Y971925D01*
X146466Y972300D01*
X146424Y972675D01*
X146299Y973008D01*
X146132Y973258D01*
X145882Y973467D01*
X145549Y973550D01*
G01X148649Y971050D02*
Y973550D01*
X148149Y973050D01*
G01Y971050D02*
X149149D01*
G01X144623Y996841D02*
Y1158041D01*
X158223D01*
Y1170991D01*
X176423D01*
Y1158041D01*
X205323D01*
Y1147691D01*
X198623D01*
Y1007191D01*
X205323D01*
Y996841D01*
X176423D01*
Y983891D01*
X158223D01*
Y996841D01*
X144623D01*
G01X128266Y1053342D02*
X128016Y1053467D01*
X127724Y1053550D01*
X127391D01*
X127016Y1053425D01*
X126724Y1053217D01*
X126516Y1052967D01*
X126349Y1052550D01*
X126307Y1052175D01*
X126391Y1051800D01*
X126516Y1051550D01*
X126766Y1051300D01*
X127057Y1051133D01*
X127349Y1051050D01*
X127641D01*
X127932Y1051133D01*
X128182Y1051258D01*
X128391Y1051425D01*
G01X129657Y1053133D02*
X129907Y1053383D01*
X130199Y1053508D01*
X130532Y1053550D01*
X130949Y1053467D01*
X131241Y1053258D01*
X131324Y1053008D01*
X131282Y1052758D01*
X131116Y1052550D01*
X130282Y1052133D01*
X129907Y1051842D01*
X129657Y1051425D01*
X129574Y1051050D01*
X131324D01*
G01X133549D02*
Y1053550D01*
X133049Y1053050D01*
G01Y1051050D02*
X134049D01*
G01X135857Y1052092D02*
X136149Y1052383D01*
X136399Y1052550D01*
X136732Y1052633D01*
X137024Y1052550D01*
X137232Y1052383D01*
X137399Y1052133D01*
X137441Y1051842D01*
X137399Y1051592D01*
X137232Y1051342D01*
X136982Y1051133D01*
X136691Y1051050D01*
X136357Y1051133D01*
X136066Y1051383D01*
X135899Y1051758D01*
X135857Y1052175D01*
X135941Y1052717D01*
X136066Y1053008D01*
X136274Y1053300D01*
X136566Y1053508D01*
X136857Y1053550D01*
X137149Y1053467D01*
X137357Y1053258D01*
G01X128266Y1056842D02*
X128016Y1056967D01*
X127724Y1057050D01*
X127391D01*
X127016Y1056925D01*
X126724Y1056717D01*
X126516Y1056467D01*
X126349Y1056050D01*
X126307Y1055675D01*
X126391Y1055300D01*
X126516Y1055050D01*
X126766Y1054800D01*
X127057Y1054633D01*
X127349Y1054550D01*
X127641D01*
X127932Y1054633D01*
X128182Y1054758D01*
X128391Y1054925D01*
G01X129657Y1056633D02*
X129907Y1056883D01*
X130199Y1057008D01*
X130532Y1057050D01*
X130949Y1056967D01*
X131241Y1056758D01*
X131324Y1056508D01*
X131282Y1056258D01*
X131116Y1056050D01*
X130282Y1055633D01*
X129907Y1055342D01*
X129657Y1054925D01*
X129574Y1054550D01*
X131324D01*
G01X133549D02*
Y1057050D01*
X133049Y1056550D01*
G01Y1054550D02*
X134049D01*
G01X136566D02*
X136649Y1055092D01*
X136774Y1055550D01*
X136941Y1055967D01*
X137149Y1056425D01*
X137482Y1057050D01*
X135816D01*
G01X141167Y1071038D02*
X141375Y1071371D01*
X141500Y1071746D01*
Y1072080D01*
X141375Y1072413D01*
X141167Y1072663D01*
X140875Y1072788D01*
X140583Y1072705D01*
X140333Y1072496D01*
X140167Y1072121D01*
X140083Y1071621D01*
X139917Y1071330D01*
X139625Y1071205D01*
X139333Y1071288D01*
X139125Y1071496D01*
X139000Y1071788D01*
Y1072080D01*
X139083Y1072371D01*
X139292Y1072621D01*
G01X141500Y1074096D02*
X139000D01*
G01Y1075680D02*
X140542Y1074096D01*
G01X141500Y1075930D02*
X139833Y1074805D01*
G01X139000Y1078113D02*
X141500D01*
G01X139000Y1077155D02*
Y1079071D01*
G01X141500Y1081213D02*
X141458Y1081505D01*
X141333Y1081838D01*
X141125Y1082046D01*
X140833Y1082130D01*
X140542Y1082046D01*
X140292Y1081796D01*
X140167Y1081421D01*
Y1081005D01*
X140083Y1080755D01*
X139875Y1080546D01*
X139583Y1080463D01*
X139292Y1080588D01*
X139083Y1080880D01*
X139000Y1081213D01*
X139083Y1081546D01*
X139292Y1081838D01*
X139583Y1081963D01*
X139875Y1081880D01*
X140083Y1081671D01*
X140167Y1081421D01*
Y1081005D01*
X140292Y1080630D01*
X140542Y1080380D01*
X140833Y1080296D01*
X141125Y1080380D01*
X141333Y1080588D01*
X141458Y1080921D01*
X141500Y1081213D01*
G01X131497Y1097482D02*
Y1099982D01*
X132538D01*
X132872Y1099857D01*
X133080Y1099690D01*
X133163Y1099357D01*
X133080Y1099024D01*
X132830Y1098815D01*
X132538Y1098690D01*
X131497D01*
G01X132538D02*
X133163Y1097482D01*
G01X135930D02*
Y1099982D01*
X134388Y1098190D01*
X136472D01*
G01X137613Y1097857D02*
X137863Y1097649D01*
X138155Y1097524D01*
X138530Y1097482D01*
X138905Y1097565D01*
X139197Y1097732D01*
X139405Y1098024D01*
X139447Y1098357D01*
X139363Y1098690D01*
X139155Y1098899D01*
X138863Y1099065D01*
X138572Y1099107D01*
X138280Y1099065D01*
X137905Y1098899D01*
X138030Y1099982D01*
X139155D01*
G01X141630D02*
X141297Y1099899D01*
X141047Y1099690D01*
X140880Y1099440D01*
X140755Y1099107D01*
X140713Y1098732D01*
X140755Y1098357D01*
X140880Y1098024D01*
X141047Y1097774D01*
X141297Y1097565D01*
X141630Y1097482D01*
X141963Y1097565D01*
X142213Y1097774D01*
X142380Y1098024D01*
X142505Y1098357D01*
X142547Y1098732D01*
X142505Y1099107D01*
X142380Y1099440D01*
X142213Y1099690D01*
X141963Y1099899D01*
X141630Y1099982D01*
G01X131497Y1093482D02*
Y1095982D01*
X132538D01*
X132872Y1095857D01*
X133080Y1095690D01*
X133163Y1095357D01*
X133080Y1095024D01*
X132830Y1094815D01*
X132538Y1094690D01*
X131497D01*
G01X132538D02*
X133163Y1093482D01*
G01X135930D02*
Y1095982D01*
X134388Y1094190D01*
X136472D01*
G01X137613Y1093857D02*
X137863Y1093649D01*
X138155Y1093524D01*
X138530Y1093482D01*
X138905Y1093565D01*
X139197Y1093732D01*
X139405Y1094024D01*
X139447Y1094357D01*
X139363Y1094690D01*
X139155Y1094899D01*
X138863Y1095065D01*
X138572Y1095107D01*
X138280Y1095065D01*
X137905Y1094899D01*
X138030Y1095982D01*
X139155D01*
G01X141630Y1093482D02*
Y1095982D01*
X141130Y1095482D01*
G01Y1093482D02*
X142130D01*
G01X131999Y1115400D02*
X134499D01*
G01X131999Y1114442D02*
Y1116358D01*
G01X134499Y1117667D02*
X131999D01*
Y1118667D01*
X132124Y1119000D01*
X132416Y1119250D01*
X132749Y1119333D01*
X133082Y1119250D01*
X133332Y1119042D01*
X133457Y1118667D01*
Y1117667D01*
G01X133999Y1120683D02*
X134291Y1120933D01*
X134457Y1121267D01*
X134499Y1121642D01*
X134457Y1121975D01*
X134249Y1122308D01*
X133999Y1122517D01*
X133749Y1122558D01*
X133457Y1122475D01*
X133249Y1122183D01*
X133166Y1121892D01*
Y1121517D01*
G01Y1121892D02*
X133041Y1122142D01*
X132832Y1122350D01*
X132582Y1122433D01*
X132332Y1122350D01*
X132124Y1122142D01*
X131999Y1121767D01*
X132041Y1121392D01*
X132207Y1121017D01*
G01X132416Y1123908D02*
X132166Y1124158D01*
X132041Y1124450D01*
X131999Y1124783D01*
X132082Y1125200D01*
X132291Y1125492D01*
X132541Y1125575D01*
X132791Y1125533D01*
X132999Y1125367D01*
X133416Y1124533D01*
X133707Y1124158D01*
X134124Y1123908D01*
X134499Y1123825D01*
Y1125575D01*
G01X133499Y1150067D02*
X130999D01*
Y1151108D01*
X131124Y1151442D01*
X131291Y1151650D01*
X131624Y1151733D01*
X131957Y1151650D01*
X132166Y1151400D01*
X132291Y1151108D01*
Y1150067D01*
G01Y1151108D02*
X133499Y1151733D01*
G01X131416Y1153208D02*
X131166Y1153458D01*
X131041Y1153750D01*
X130999Y1154083D01*
X131082Y1154500D01*
X131291Y1154792D01*
X131541Y1154875D01*
X131791Y1154833D01*
X131999Y1154667D01*
X132416Y1153833D01*
X132707Y1153458D01*
X133124Y1153208D01*
X133499Y1153125D01*
Y1154875D01*
G01X130999Y1157100D02*
X131082Y1156767D01*
X131291Y1156517D01*
X131541Y1156350D01*
X131874Y1156225D01*
X132249Y1156183D01*
X132624Y1156225D01*
X132957Y1156350D01*
X133207Y1156517D01*
X133416Y1156767D01*
X133499Y1157100D01*
X133416Y1157433D01*
X133207Y1157683D01*
X132957Y1157850D01*
X132624Y1157975D01*
X132249Y1158017D01*
X131874Y1157975D01*
X131541Y1157850D01*
X131291Y1157683D01*
X131082Y1157433D01*
X130999Y1157100D01*
G01X133207Y1159492D02*
X133416Y1159783D01*
X133499Y1160117D01*
X133416Y1160450D01*
X133166Y1160742D01*
X132791Y1160950D01*
X132416Y1161033D01*
X131957D01*
X131582Y1160950D01*
X131249Y1160742D01*
X131082Y1160492D01*
X130999Y1160200D01*
X131082Y1159867D01*
X131249Y1159617D01*
X131499Y1159450D01*
X131832Y1159367D01*
X132124Y1159450D01*
X132416Y1159658D01*
X132582Y1159908D01*
X132624Y1160200D01*
X132541Y1160533D01*
X132332Y1160783D01*
X131957Y1161033D01*
G01X125900Y1168200D02*
Y1173700D01*
G01X133900Y1168200D02*
X125900D01*
G01X133900Y1173700D02*
Y1168200D01*
G01X124999Y1173750D02*
Y1168250D01*
G01X133900Y1185800D02*
Y1180300D01*
G01X125900Y1185800D02*
X133900D01*
G01X125900Y1180300D02*
Y1185800D01*
G01X140208Y1176267D02*
X140083Y1176017D01*
X140000Y1175725D01*
Y1175392D01*
X140125Y1175017D01*
X140333Y1174725D01*
X140583Y1174517D01*
X141000Y1174350D01*
X141375Y1174308D01*
X141750Y1174392D01*
X142000Y1174517D01*
X142250Y1174767D01*
X142417Y1175058D01*
X142500Y1175350D01*
Y1175642D01*
X142417Y1175933D01*
X142292Y1176183D01*
X142125Y1176392D01*
G01X140417Y1177658D02*
X140167Y1177908D01*
X140042Y1178200D01*
X140000Y1178533D01*
X140083Y1178950D01*
X140292Y1179242D01*
X140542Y1179325D01*
X140792Y1179283D01*
X141000Y1179117D01*
X141417Y1178283D01*
X141708Y1177908D01*
X142125Y1177658D01*
X142500Y1177575D01*
Y1179325D01*
G01X140417Y1180758D02*
X140167Y1181008D01*
X140042Y1181300D01*
X140000Y1181633D01*
X140083Y1182050D01*
X140292Y1182342D01*
X140542Y1182425D01*
X140792Y1182383D01*
X141000Y1182217D01*
X141417Y1181383D01*
X141708Y1181008D01*
X142125Y1180758D01*
X142500Y1180675D01*
Y1182425D01*
G01Y1185150D02*
X140000D01*
X141792Y1183608D01*
Y1185692D01*
G01X144208Y1176267D02*
X144083Y1176017D01*
X144000Y1175725D01*
Y1175392D01*
X144125Y1175017D01*
X144333Y1174725D01*
X144583Y1174517D01*
X145000Y1174350D01*
X145375Y1174308D01*
X145750Y1174392D01*
X146000Y1174517D01*
X146250Y1174767D01*
X146417Y1175058D01*
X146500Y1175350D01*
Y1175642D01*
X146417Y1175933D01*
X146292Y1176183D01*
X146125Y1176392D01*
G01X144417Y1177658D02*
X144167Y1177908D01*
X144042Y1178200D01*
X144000Y1178533D01*
X144083Y1178950D01*
X144292Y1179242D01*
X144542Y1179325D01*
X144792Y1179283D01*
X145000Y1179117D01*
X145417Y1178283D01*
X145708Y1177908D01*
X146125Y1177658D01*
X146500Y1177575D01*
Y1179325D01*
G01X144417Y1180758D02*
X144167Y1181008D01*
X144042Y1181300D01*
X144000Y1181633D01*
X144083Y1182050D01*
X144292Y1182342D01*
X144542Y1182425D01*
X144792Y1182383D01*
X145000Y1182217D01*
X145417Y1181383D01*
X145708Y1181008D01*
X146125Y1180758D01*
X146500Y1180675D01*
Y1182425D01*
G01X146125Y1183733D02*
X146333Y1183983D01*
X146458Y1184275D01*
X146500Y1184650D01*
X146417Y1185025D01*
X146250Y1185317D01*
X145958Y1185525D01*
X145625Y1185567D01*
X145292Y1185483D01*
X145083Y1185275D01*
X144917Y1184983D01*
X144875Y1184692D01*
X144917Y1184400D01*
X145083Y1184025D01*
X144000Y1184150D01*
Y1185275D01*
G01X124999Y1185850D02*
Y1180350D01*
G01X126900Y1200500D02*
X126567Y1200542D01*
X126275Y1200708D01*
X126025Y1200958D01*
X125858Y1201250D01*
X125775Y1201583D01*
Y1201917D01*
X125858Y1202250D01*
X126025Y1202542D01*
X126275Y1202792D01*
X126567Y1202958D01*
X126900Y1203000D01*
X127233Y1202958D01*
X127525Y1202792D01*
X127775Y1202542D01*
X127942Y1202250D01*
X128025Y1201917D01*
Y1201583D01*
X127942Y1201250D01*
X127775Y1200958D01*
X127525Y1200708D01*
X127233Y1200542D01*
X126900Y1200500D01*
G01X127233Y1201167D02*
X127733Y1200500D01*
G01X129208Y1202583D02*
X129458Y1202833D01*
X129750Y1202958D01*
X130083Y1203000D01*
X130500Y1202917D01*
X130792Y1202708D01*
X130875Y1202458D01*
X130833Y1202208D01*
X130667Y1202000D01*
X129833Y1201583D01*
X129458Y1201292D01*
X129208Y1200875D01*
X129125Y1200500D01*
X130875D01*
G01X133600D02*
Y1203000D01*
X132058Y1201208D01*
X134142D01*
G01X133699Y1210413D02*
Y1221813D01*
G01X144017Y1208000D02*
Y1210500D01*
X145058D01*
X145392Y1210375D01*
X145600Y1210208D01*
X145683Y1209875D01*
X145600Y1209542D01*
X145350Y1209333D01*
X145058Y1209208D01*
X144017D01*
G01X145058D02*
X145683Y1208000D01*
G01X148450D02*
Y1210500D01*
X146908Y1208708D01*
X148992D01*
G01X151050Y1208000D02*
Y1210500D01*
X150550Y1210000D01*
G01Y1208000D02*
X151550D01*
G01X153442Y1208292D02*
X153733Y1208083D01*
X154067Y1208000D01*
X154400Y1208083D01*
X154692Y1208333D01*
X154900Y1208708D01*
X154983Y1209083D01*
Y1209542D01*
X154900Y1209917D01*
X154692Y1210250D01*
X154442Y1210417D01*
X154150Y1210500D01*
X153817Y1210417D01*
X153567Y1210250D01*
X153400Y1210000D01*
X153317Y1209667D01*
X153400Y1209375D01*
X153608Y1209083D01*
X153858Y1208917D01*
X154150Y1208875D01*
X154483Y1208958D01*
X154733Y1209167D01*
X154983Y1209542D01*
G01X134200Y1212400D02*
Y1208400D01*
X141600D01*
G01X142899Y1234413D02*
Y1215213D01*
X154099D01*
Y1234413D01*
X142899D01*
G01X133999Y1229813D02*
X129999D01*
Y1222413D01*
G01X129499Y1229813D02*
X125499D01*
Y1222413D01*
G01X138099Y1235613D02*
Y1258613D01*
G01X176899Y1235613D02*
X138099D01*
G01X125499Y1230313D02*
Y1235813D01*
G01X133499Y1230313D02*
X125499D01*
G01X133499Y1235813D02*
Y1230313D01*
G01X127999Y1248613D02*
Y1261613D01*
G01X128700Y1251100D02*
Y1256600D01*
G01X136700Y1251100D02*
X128700D01*
G01X136700Y1256600D02*
Y1251100D01*
G01X133499Y1247913D02*
Y1242413D01*
G01X125499Y1247913D02*
X133499D01*
G01X125499Y1242413D02*
Y1247913D01*
G01X138850Y1275000D02*
Y1272500D01*
G01X137892Y1275000D02*
X139808D01*
G01X141117Y1272500D02*
Y1275000D01*
X142117D01*
X142450Y1274875D01*
X142700Y1274583D01*
X142783Y1274250D01*
X142700Y1273917D01*
X142492Y1273667D01*
X142117Y1273542D01*
X141117D01*
G01X144133Y1273000D02*
X144383Y1272708D01*
X144717Y1272542D01*
X145092Y1272500D01*
X145425Y1272542D01*
X145758Y1272750D01*
X145967Y1273000D01*
X146008Y1273250D01*
X145925Y1273542D01*
X145633Y1273750D01*
X145342Y1273833D01*
X144967D01*
G01X145342D02*
X145592Y1273958D01*
X145800Y1274167D01*
X145883Y1274417D01*
X145800Y1274667D01*
X145592Y1274875D01*
X145217Y1275000D01*
X144842Y1274958D01*
X144467Y1274792D01*
G01X147358Y1273542D02*
X147650Y1273833D01*
X147900Y1274000D01*
X148233Y1274083D01*
X148525Y1274000D01*
X148733Y1273833D01*
X148900Y1273583D01*
X148942Y1273292D01*
X148900Y1273042D01*
X148733Y1272792D01*
X148483Y1272583D01*
X148192Y1272500D01*
X147858Y1272583D01*
X147567Y1272833D01*
X147400Y1273208D01*
X147358Y1273625D01*
X147442Y1274167D01*
X147567Y1274458D01*
X147775Y1274750D01*
X148067Y1274958D01*
X148358Y1275000D01*
X148650Y1274917D01*
X148858Y1274708D01*
G01X138099Y1258613D02*
X176899D01*
G01X136700Y1268700D02*
Y1263200D01*
G01X128700Y1268700D02*
X136700D01*
G01X128700Y1263200D02*
Y1268700D01*
G01X143100Y1278100D02*
X136100D01*
Y1291500D01*
X143100D01*
Y1278100D01*
G01X127999Y1282113D02*
Y1295113D01*
G01X125983Y1303500D02*
Y1301708D01*
X126150Y1301333D01*
X126483Y1301083D01*
X126900Y1301000D01*
X127317Y1301083D01*
X127650Y1301333D01*
X127817Y1301708D01*
Y1303500D01*
G01X129083Y1301500D02*
X129333Y1301208D01*
X129667Y1301042D01*
X130042Y1301000D01*
X130375Y1301042D01*
X130708Y1301250D01*
X130917Y1301500D01*
X130958Y1301750D01*
X130875Y1302042D01*
X130583Y1302250D01*
X130292Y1302333D01*
X129917D01*
G01X130292D02*
X130542Y1302458D01*
X130750Y1302667D01*
X130833Y1302917D01*
X130750Y1303167D01*
X130542Y1303375D01*
X130167Y1303500D01*
X129792Y1303458D01*
X129417Y1303292D01*
G01X133600Y1301000D02*
Y1303500D01*
X132058Y1301708D01*
X134142D01*
G01X133000Y1282608D02*
X130500D01*
Y1284192D01*
G01X131708Y1283608D02*
Y1282608D01*
G01X130917Y1285708D02*
X130667Y1285958D01*
X130542Y1286250D01*
X130500Y1286583D01*
X130583Y1287000D01*
X130792Y1287292D01*
X131042Y1287375D01*
X131292Y1287333D01*
X131500Y1287167D01*
X131917Y1286333D01*
X132208Y1285958D01*
X132625Y1285708D01*
X133000Y1285625D01*
Y1287375D01*
G01X132500Y1288683D02*
X132792Y1288933D01*
X132958Y1289267D01*
X133000Y1289642D01*
X132958Y1289975D01*
X132750Y1290308D01*
X132500Y1290517D01*
X132250Y1290558D01*
X131958Y1290475D01*
X131750Y1290183D01*
X131667Y1289892D01*
Y1289517D01*
G01Y1289892D02*
X131542Y1290142D01*
X131333Y1290350D01*
X131083Y1290433D01*
X130833Y1290350D01*
X130625Y1290142D01*
X130500Y1289767D01*
X130542Y1289392D01*
X130708Y1289017D01*
G01X137000Y1321400D02*
X150400D01*
G01X137000Y1332800D02*
Y1321400D01*
G01X133517Y1316000D02*
Y1318500D01*
X134558D01*
X134892Y1318375D01*
X135100Y1318208D01*
X135183Y1317875D01*
X135100Y1317542D01*
X134850Y1317333D01*
X134558Y1317208D01*
X133517D01*
G01X134558D02*
X135183Y1316000D01*
G01X136533Y1316500D02*
X136783Y1316208D01*
X137117Y1316042D01*
X137492Y1316000D01*
X137825Y1316042D01*
X138158Y1316250D01*
X138367Y1316500D01*
X138408Y1316750D01*
X138325Y1317042D01*
X138033Y1317250D01*
X137742Y1317333D01*
X137367D01*
G01X137742D02*
X137992Y1317458D01*
X138200Y1317667D01*
X138283Y1317917D01*
X138200Y1318167D01*
X137992Y1318375D01*
X137617Y1318500D01*
X137242Y1318458D01*
X136867Y1318292D01*
G01X139842Y1316292D02*
X140133Y1316083D01*
X140467Y1316000D01*
X140800Y1316083D01*
X141092Y1316333D01*
X141300Y1316708D01*
X141383Y1317083D01*
Y1317542D01*
X141300Y1317917D01*
X141092Y1318250D01*
X140842Y1318417D01*
X140550Y1318500D01*
X140217Y1318417D01*
X139967Y1318250D01*
X139800Y1318000D01*
X139717Y1317667D01*
X139800Y1317375D01*
X140008Y1317083D01*
X140258Y1316917D01*
X140550Y1316875D01*
X140883Y1316958D01*
X141133Y1317167D01*
X141383Y1317542D01*
G01X143650Y1316000D02*
X143942Y1316042D01*
X144275Y1316167D01*
X144483Y1316375D01*
X144567Y1316667D01*
X144483Y1316958D01*
X144233Y1317208D01*
X143858Y1317333D01*
X143442D01*
X143192Y1317417D01*
X142983Y1317625D01*
X142900Y1317917D01*
X143025Y1318208D01*
X143317Y1318417D01*
X143650Y1318500D01*
X143983Y1318417D01*
X144275Y1318208D01*
X144400Y1317917D01*
X144317Y1317625D01*
X144108Y1317417D01*
X143858Y1317333D01*
X143442D01*
X143067Y1317208D01*
X142817Y1316958D01*
X142733Y1316667D01*
X142817Y1316375D01*
X143025Y1316167D01*
X143358Y1316042D01*
X143650Y1316000D01*
G01X150400Y1332800D02*
X137000D01*
G01X145517Y1335500D02*
Y1338000D01*
X146558D01*
X146892Y1337875D01*
X147100Y1337708D01*
X147183Y1337375D01*
X147100Y1337042D01*
X146850Y1336833D01*
X146558Y1336708D01*
X145517D01*
G01X146558D02*
X147183Y1335500D01*
G01X148533Y1336000D02*
X148783Y1335708D01*
X149117Y1335542D01*
X149492Y1335500D01*
X149825Y1335542D01*
X150158Y1335750D01*
X150367Y1336000D01*
X150408Y1336250D01*
X150325Y1336542D01*
X150033Y1336750D01*
X149742Y1336833D01*
X149367D01*
G01X149742D02*
X149992Y1336958D01*
X150200Y1337167D01*
X150283Y1337417D01*
X150200Y1337667D01*
X149992Y1337875D01*
X149617Y1338000D01*
X149242Y1337958D01*
X148867Y1337792D01*
G01X151842Y1335792D02*
X152133Y1335583D01*
X152467Y1335500D01*
X152800Y1335583D01*
X153092Y1335833D01*
X153300Y1336208D01*
X153383Y1336583D01*
Y1337042D01*
X153300Y1337417D01*
X153092Y1337750D01*
X152842Y1337917D01*
X152550Y1338000D01*
X152217Y1337917D01*
X151967Y1337750D01*
X151800Y1337500D01*
X151717Y1337167D01*
X151800Y1336875D01*
X152008Y1336583D01*
X152258Y1336417D01*
X152550Y1336375D01*
X152883Y1336458D01*
X153133Y1336667D01*
X153383Y1337042D01*
G01X154942Y1335792D02*
X155233Y1335583D01*
X155567Y1335500D01*
X155900Y1335583D01*
X156192Y1335833D01*
X156400Y1336208D01*
X156483Y1336583D01*
Y1337042D01*
X156400Y1337417D01*
X156192Y1337750D01*
X155942Y1337917D01*
X155650Y1338000D01*
X155317Y1337917D01*
X155067Y1337750D01*
X154900Y1337500D01*
X154817Y1337167D01*
X154900Y1336875D01*
X155108Y1336583D01*
X155358Y1336417D01*
X155650Y1336375D01*
X155983Y1336458D01*
X156233Y1336667D01*
X156483Y1337042D01*
G01X144100Y1333800D02*
Y1337800D01*
X136700D01*
G01X140517Y1340000D02*
Y1342500D01*
X141558D01*
X141892Y1342375D01*
X142100Y1342208D01*
X142183Y1341875D01*
X142100Y1341542D01*
X141850Y1341333D01*
X141558Y1341208D01*
X140517D01*
G01X141558D02*
X142183Y1340000D01*
G01X143533Y1340375D02*
X143783Y1340167D01*
X144075Y1340042D01*
X144450Y1340000D01*
X144825Y1340083D01*
X145117Y1340250D01*
X145325Y1340542D01*
X145367Y1340875D01*
X145283Y1341208D01*
X145075Y1341417D01*
X144783Y1341583D01*
X144492Y1341625D01*
X144200Y1341583D01*
X143825Y1341417D01*
X143950Y1342500D01*
X145075D01*
G01X147550D02*
X147217Y1342417D01*
X146967Y1342208D01*
X146800Y1341958D01*
X146675Y1341625D01*
X146633Y1341250D01*
X146675Y1340875D01*
X146800Y1340542D01*
X146967Y1340292D01*
X147217Y1340083D01*
X147550Y1340000D01*
X147883Y1340083D01*
X148133Y1340292D01*
X148300Y1340542D01*
X148425Y1340875D01*
X148467Y1341250D01*
X148425Y1341625D01*
X148300Y1341958D01*
X148133Y1342208D01*
X147883Y1342417D01*
X147550Y1342500D01*
G01X150650Y1340000D02*
Y1342500D01*
X150150Y1342000D01*
G01Y1340000D02*
X151150D01*
G01X133199Y1340050D02*
Y1344050D01*
X125799D01*
G01X136100Y1323500D02*
Y1337500D01*
G01X143826Y1354181D02*
Y1356681D01*
X144867D01*
X145201Y1356556D01*
X145409Y1356389D01*
X145492Y1356056D01*
X145409Y1355723D01*
X145159Y1355514D01*
X144867Y1355389D01*
X143826D01*
G01X144867D02*
X145492Y1354181D01*
G01X146967Y1356264D02*
X147217Y1356514D01*
X147509Y1356639D01*
X147842Y1356681D01*
X148259Y1356598D01*
X148551Y1356389D01*
X148634Y1356139D01*
X148592Y1355889D01*
X148426Y1355681D01*
X147592Y1355264D01*
X147217Y1354973D01*
X146967Y1354556D01*
X146884Y1354181D01*
X148634D01*
G01X149942Y1354556D02*
X150192Y1354348D01*
X150484Y1354223D01*
X150859Y1354181D01*
X151234Y1354264D01*
X151526Y1354431D01*
X151734Y1354723D01*
X151776Y1355056D01*
X151692Y1355389D01*
X151484Y1355598D01*
X151192Y1355764D01*
X150901Y1355806D01*
X150609Y1355764D01*
X150234Y1355598D01*
X150359Y1356681D01*
X151484D01*
G01X154459Y1354181D02*
Y1356681D01*
X152917Y1354889D01*
X155001D01*
G01X138017Y1360000D02*
Y1362500D01*
X139058D01*
X139392Y1362375D01*
X139600Y1362208D01*
X139683Y1361875D01*
X139600Y1361542D01*
X139350Y1361333D01*
X139058Y1361208D01*
X138017D01*
G01X139058D02*
X139683Y1360000D01*
G01X141158Y1362083D02*
X141408Y1362333D01*
X141700Y1362458D01*
X142033Y1362500D01*
X142450Y1362417D01*
X142742Y1362208D01*
X142825Y1361958D01*
X142783Y1361708D01*
X142617Y1361500D01*
X141783Y1361083D01*
X141408Y1360792D01*
X141158Y1360375D01*
X141075Y1360000D01*
X142825D01*
G01X144133Y1360375D02*
X144383Y1360167D01*
X144675Y1360042D01*
X145050Y1360000D01*
X145425Y1360083D01*
X145717Y1360250D01*
X145925Y1360542D01*
X145967Y1360875D01*
X145883Y1361208D01*
X145675Y1361417D01*
X145383Y1361583D01*
X145092Y1361625D01*
X144800Y1361583D01*
X144425Y1361417D01*
X144550Y1362500D01*
X145675D01*
G01X147233Y1360375D02*
X147483Y1360167D01*
X147775Y1360042D01*
X148150Y1360000D01*
X148525Y1360083D01*
X148817Y1360250D01*
X149025Y1360542D01*
X149067Y1360875D01*
X148983Y1361208D01*
X148775Y1361417D01*
X148483Y1361583D01*
X148192Y1361625D01*
X147900Y1361583D01*
X147525Y1361417D01*
X147650Y1362500D01*
X148775D01*
G01X133700Y1359000D02*
Y1363000D01*
X126300D01*
G01X143826Y1350181D02*
Y1352681D01*
X144867D01*
X145201Y1352556D01*
X145409Y1352389D01*
X145492Y1352056D01*
X145409Y1351723D01*
X145159Y1351514D01*
X144867Y1351389D01*
X143826D01*
G01X144867D02*
X145492Y1350181D01*
G01X146967Y1352264D02*
X147217Y1352514D01*
X147509Y1352639D01*
X147842Y1352681D01*
X148259Y1352598D01*
X148551Y1352389D01*
X148634Y1352139D01*
X148592Y1351889D01*
X148426Y1351681D01*
X147592Y1351264D01*
X147217Y1350973D01*
X146967Y1350556D01*
X146884Y1350181D01*
X148634D01*
G01X149942Y1350556D02*
X150192Y1350348D01*
X150484Y1350223D01*
X150859Y1350181D01*
X151234Y1350264D01*
X151526Y1350431D01*
X151734Y1350723D01*
X151776Y1351056D01*
X151692Y1351389D01*
X151484Y1351598D01*
X151192Y1351764D01*
X150901Y1351806D01*
X150609Y1351764D01*
X150234Y1351598D01*
X150359Y1352681D01*
X151484D01*
G01X153167Y1351223D02*
X153459Y1351514D01*
X153709Y1351681D01*
X154042Y1351764D01*
X154334Y1351681D01*
X154542Y1351514D01*
X154709Y1351264D01*
X154751Y1350973D01*
X154709Y1350723D01*
X154542Y1350473D01*
X154292Y1350264D01*
X154001Y1350181D01*
X153667Y1350264D01*
X153376Y1350514D01*
X153209Y1350889D01*
X153167Y1351306D01*
X153251Y1351848D01*
X153376Y1352139D01*
X153584Y1352431D01*
X153876Y1352639D01*
X154167Y1352681D01*
X154459Y1352598D01*
X154667Y1352389D01*
G01X138017Y1364500D02*
Y1367000D01*
X139058D01*
X139392Y1366875D01*
X139600Y1366708D01*
X139683Y1366375D01*
X139600Y1366042D01*
X139350Y1365833D01*
X139058Y1365708D01*
X138017D01*
G01X139058D02*
X139683Y1364500D01*
G01X141158Y1366583D02*
X141408Y1366833D01*
X141700Y1366958D01*
X142033Y1367000D01*
X142450Y1366917D01*
X142742Y1366708D01*
X142825Y1366458D01*
X142783Y1366208D01*
X142617Y1366000D01*
X141783Y1365583D01*
X141408Y1365292D01*
X141158Y1364875D01*
X141075Y1364500D01*
X142825D01*
G01X144133Y1364875D02*
X144383Y1364667D01*
X144675Y1364542D01*
X145050Y1364500D01*
X145425Y1364583D01*
X145717Y1364750D01*
X145925Y1365042D01*
X145967Y1365375D01*
X145883Y1365708D01*
X145675Y1365917D01*
X145383Y1366083D01*
X145092Y1366125D01*
X144800Y1366083D01*
X144425Y1365917D01*
X144550Y1367000D01*
X145675D01*
G01X148067Y1364500D02*
X148150Y1365042D01*
X148275Y1365500D01*
X148442Y1365917D01*
X148650Y1366375D01*
X148983Y1367000D01*
X147317D01*
G01X126300D02*
Y1363000D01*
X133700D01*
G01X126499Y1345050D02*
X140499D01*
G01X126499Y1358050D02*
Y1345050D01*
G01X140499Y1358050D02*
X126499D01*
G01X140499Y1345050D02*
Y1358050D01*
G01X144623Y1402353D02*
Y1563553D01*
X158223D01*
Y1576503D01*
X176423D01*
Y1563553D01*
X205323D01*
Y1553203D01*
X198623D01*
Y1412703D01*
X205323D01*
Y1402353D01*
X176423D01*
Y1389403D01*
X158223D01*
Y1402353D01*
X144623D01*
G01X127657Y1457333D02*
X127407Y1457458D01*
X127115Y1457541D01*
X126782D01*
X126407Y1457416D01*
X126115Y1457208D01*
X125907Y1456958D01*
X125740Y1456541D01*
X125698Y1456166D01*
X125782Y1455791D01*
X125907Y1455541D01*
X126157Y1455291D01*
X126448Y1455124D01*
X126740Y1455041D01*
X127032D01*
X127323Y1455124D01*
X127573Y1455249D01*
X127782Y1455416D01*
G01X129048Y1457124D02*
X129298Y1457374D01*
X129590Y1457499D01*
X129923Y1457541D01*
X130340Y1457458D01*
X130632Y1457249D01*
X130715Y1456999D01*
X130673Y1456749D01*
X130507Y1456541D01*
X129673Y1456124D01*
X129298Y1455833D01*
X129048Y1455416D01*
X128965Y1455041D01*
X130715D01*
G01X132940Y1457541D02*
X132607Y1457458D01*
X132357Y1457249D01*
X132190Y1456999D01*
X132065Y1456666D01*
X132023Y1456291D01*
X132065Y1455916D01*
X132190Y1455583D01*
X132357Y1455333D01*
X132607Y1455124D01*
X132940Y1455041D01*
X133273Y1455124D01*
X133523Y1455333D01*
X133690Y1455583D01*
X133815Y1455916D01*
X133857Y1456291D01*
X133815Y1456666D01*
X133690Y1456999D01*
X133523Y1457249D01*
X133273Y1457458D01*
X132940Y1457541D01*
G01X136040D02*
X135707Y1457458D01*
X135457Y1457249D01*
X135290Y1456999D01*
X135165Y1456666D01*
X135123Y1456291D01*
X135165Y1455916D01*
X135290Y1455583D01*
X135457Y1455333D01*
X135707Y1455124D01*
X136040Y1455041D01*
X136373Y1455124D01*
X136623Y1455333D01*
X136790Y1455583D01*
X136915Y1455916D01*
X136957Y1456291D01*
X136915Y1456666D01*
X136790Y1456999D01*
X136623Y1457249D01*
X136373Y1457458D01*
X136040Y1457541D01*
G01X127766Y1461142D02*
X127516Y1461267D01*
X127224Y1461350D01*
X126891D01*
X126516Y1461225D01*
X126224Y1461017D01*
X126016Y1460767D01*
X125849Y1460350D01*
X125807Y1459975D01*
X125891Y1459600D01*
X126016Y1459350D01*
X126266Y1459100D01*
X126557Y1458933D01*
X126849Y1458850D01*
X127141D01*
X127432Y1458933D01*
X127682Y1459058D01*
X127891Y1459225D01*
G01X129157Y1460933D02*
X129407Y1461183D01*
X129699Y1461308D01*
X130032Y1461350D01*
X130449Y1461267D01*
X130741Y1461058D01*
X130824Y1460808D01*
X130782Y1460558D01*
X130616Y1460350D01*
X129782Y1459933D01*
X129407Y1459642D01*
X129157Y1459225D01*
X129074Y1458850D01*
X130824D01*
G01X133049Y1461350D02*
X132716Y1461267D01*
X132466Y1461058D01*
X132299Y1460808D01*
X132174Y1460475D01*
X132132Y1460100D01*
X132174Y1459725D01*
X132299Y1459392D01*
X132466Y1459142D01*
X132716Y1458933D01*
X133049Y1458850D01*
X133382Y1458933D01*
X133632Y1459142D01*
X133799Y1459392D01*
X133924Y1459725D01*
X133966Y1460100D01*
X133924Y1460475D01*
X133799Y1460808D01*
X133632Y1461058D01*
X133382Y1461267D01*
X133049Y1461350D01*
G01X136149Y1458850D02*
Y1461350D01*
X135649Y1460850D01*
G01Y1458850D02*
X136649D01*
G01X126207Y1485217D02*
X126082Y1484967D01*
X125999Y1484675D01*
Y1484342D01*
X126124Y1483967D01*
X126332Y1483675D01*
X126582Y1483467D01*
X126999Y1483300D01*
X127374Y1483258D01*
X127749Y1483342D01*
X127999Y1483467D01*
X128249Y1483717D01*
X128416Y1484008D01*
X128499Y1484300D01*
Y1484592D01*
X128416Y1484883D01*
X128291Y1485133D01*
X128124Y1485342D01*
G01X127999Y1486483D02*
X128291Y1486733D01*
X128457Y1487067D01*
X128499Y1487442D01*
X128457Y1487775D01*
X128249Y1488108D01*
X127999Y1488317D01*
X127749Y1488358D01*
X127457Y1488275D01*
X127249Y1487983D01*
X127166Y1487692D01*
Y1487317D01*
G01Y1487692D02*
X127041Y1487942D01*
X126832Y1488150D01*
X126582Y1488233D01*
X126332Y1488150D01*
X126124Y1487942D01*
X125999Y1487567D01*
X126041Y1487192D01*
X126207Y1486817D01*
G01X128499Y1491000D02*
X125999D01*
X127791Y1489458D01*
Y1491542D01*
G01X125999Y1493600D02*
X126082Y1493267D01*
X126291Y1493017D01*
X126541Y1492850D01*
X126874Y1492725D01*
X127249Y1492683D01*
X127624Y1492725D01*
X127957Y1492850D01*
X128207Y1493017D01*
X128416Y1493267D01*
X128499Y1493600D01*
X128416Y1493933D01*
X128207Y1494183D01*
X127957Y1494350D01*
X127624Y1494475D01*
X127249Y1494517D01*
X126874Y1494475D01*
X126541Y1494350D01*
X126291Y1494183D01*
X126082Y1493933D01*
X125999Y1493600D01*
G01X131449Y1508367D02*
X128949D01*
Y1509408D01*
X129074Y1509742D01*
X129241Y1509950D01*
X129574Y1510033D01*
X129907Y1509950D01*
X130116Y1509700D01*
X130241Y1509408D01*
Y1508367D01*
G01Y1509408D02*
X131449Y1510033D01*
G01X130949Y1511383D02*
X131241Y1511633D01*
X131407Y1511967D01*
X131449Y1512342D01*
X131407Y1512675D01*
X131199Y1513008D01*
X130949Y1513217D01*
X130699Y1513258D01*
X130407Y1513175D01*
X130199Y1512883D01*
X130116Y1512592D01*
Y1512217D01*
G01Y1512592D02*
X129991Y1512842D01*
X129782Y1513050D01*
X129532Y1513133D01*
X129282Y1513050D01*
X129074Y1512842D01*
X128949Y1512467D01*
X128991Y1512092D01*
X129157Y1511717D01*
G01X131449Y1515400D02*
X128949D01*
X129449Y1514900D01*
G01X131449D02*
Y1515900D01*
G01X128949Y1518500D02*
X129032Y1518167D01*
X129241Y1517917D01*
X129491Y1517750D01*
X129824Y1517625D01*
X130199Y1517583D01*
X130574Y1517625D01*
X130907Y1517750D01*
X131157Y1517917D01*
X131366Y1518167D01*
X131449Y1518500D01*
X131366Y1518833D01*
X131157Y1519083D01*
X130907Y1519250D01*
X130574Y1519375D01*
X130199Y1519417D01*
X129824Y1519375D01*
X129491Y1519250D01*
X129241Y1519083D01*
X129032Y1518833D01*
X128949Y1518500D01*
G01X127299Y1508367D02*
X124799D01*
Y1509408D01*
X124924Y1509742D01*
X125091Y1509950D01*
X125424Y1510033D01*
X125757Y1509950D01*
X125966Y1509700D01*
X126091Y1509408D01*
Y1508367D01*
G01Y1509408D02*
X127299Y1510033D01*
G01X126799Y1511383D02*
X127091Y1511633D01*
X127257Y1511967D01*
X127299Y1512342D01*
X127257Y1512675D01*
X127049Y1513008D01*
X126799Y1513217D01*
X126549Y1513258D01*
X126257Y1513175D01*
X126049Y1512883D01*
X125966Y1512592D01*
Y1512217D01*
G01Y1512592D02*
X125841Y1512842D01*
X125632Y1513050D01*
X125382Y1513133D01*
X125132Y1513050D01*
X124924Y1512842D01*
X124799Y1512467D01*
X124841Y1512092D01*
X125007Y1511717D01*
G01X127299Y1515400D02*
X124799D01*
X125299Y1514900D01*
G01X127299D02*
Y1515900D01*
G01Y1518500D02*
X127257Y1518792D01*
X127132Y1519125D01*
X126924Y1519333D01*
X126632Y1519417D01*
X126341Y1519333D01*
X126091Y1519083D01*
X125966Y1518708D01*
Y1518292D01*
X125882Y1518042D01*
X125674Y1517833D01*
X125382Y1517750D01*
X125091Y1517875D01*
X124882Y1518167D01*
X124799Y1518500D01*
X124882Y1518833D01*
X125091Y1519125D01*
X125382Y1519250D01*
X125674Y1519167D01*
X125882Y1518958D01*
X125966Y1518708D01*
Y1518292D01*
X126091Y1517917D01*
X126341Y1517667D01*
X126632Y1517583D01*
X126924Y1517667D01*
X127132Y1517875D01*
X127257Y1518208D01*
X127299Y1518500D01*
G01X138367Y1493938D02*
X138575Y1494271D01*
X138700Y1494646D01*
Y1494980D01*
X138575Y1495313D01*
X138367Y1495563D01*
X138075Y1495688D01*
X137783Y1495605D01*
X137533Y1495396D01*
X137367Y1495021D01*
X137283Y1494521D01*
X137117Y1494230D01*
X136825Y1494105D01*
X136533Y1494188D01*
X136325Y1494396D01*
X136200Y1494688D01*
Y1494980D01*
X136283Y1495271D01*
X136492Y1495521D01*
G01X138700Y1496996D02*
X136200D01*
G01Y1498580D02*
X137742Y1496996D01*
G01X138700Y1498830D02*
X137033Y1497705D01*
G01X136200Y1501013D02*
X138700D01*
G01X136200Y1500055D02*
Y1501971D01*
G01X138700Y1504030D02*
X138158Y1504113D01*
X137700Y1504238D01*
X137283Y1504405D01*
X136825Y1504613D01*
X136200Y1504946D01*
Y1503280D01*
G01X133800Y1565000D02*
Y1562500D01*
G01X132842Y1565000D02*
X134758D01*
G01X137817Y1564792D02*
X137567Y1564917D01*
X137275Y1565000D01*
X136942D01*
X136567Y1564875D01*
X136275Y1564667D01*
X136067Y1564417D01*
X135900Y1564000D01*
X135858Y1563625D01*
X135942Y1563250D01*
X136067Y1563000D01*
X136317Y1562750D01*
X136608Y1562583D01*
X136900Y1562500D01*
X137192D01*
X137483Y1562583D01*
X137733Y1562708D01*
X137942Y1562875D01*
G01X140000Y1562500D02*
Y1565000D01*
X139500Y1564500D01*
G01Y1562500D02*
X140500D01*
G01X156100Y1574500D02*
X144900D01*
G01Y1592500D02*
X156100D01*
G01X128666Y1606942D02*
X128416Y1607067D01*
X128124Y1607150D01*
X127791D01*
X127416Y1607025D01*
X127124Y1606817D01*
X126916Y1606567D01*
X126749Y1606150D01*
X126707Y1605775D01*
X126791Y1605400D01*
X126916Y1605150D01*
X127166Y1604900D01*
X127457Y1604733D01*
X127749Y1604650D01*
X128041D01*
X128332Y1604733D01*
X128582Y1604858D01*
X128791Y1605025D01*
G01X129932Y1605150D02*
X130182Y1604858D01*
X130516Y1604692D01*
X130891Y1604650D01*
X131224Y1604692D01*
X131557Y1604900D01*
X131766Y1605150D01*
X131807Y1605400D01*
X131724Y1605692D01*
X131432Y1605900D01*
X131141Y1605983D01*
X130766D01*
G01X131141D02*
X131391Y1606108D01*
X131599Y1606317D01*
X131682Y1606567D01*
X131599Y1606817D01*
X131391Y1607025D01*
X131016Y1607150D01*
X130641Y1607108D01*
X130266Y1606942D01*
G01X133032Y1605025D02*
X133282Y1604817D01*
X133574Y1604692D01*
X133949Y1604650D01*
X134324Y1604733D01*
X134616Y1604900D01*
X134824Y1605192D01*
X134866Y1605525D01*
X134782Y1605858D01*
X134574Y1606067D01*
X134282Y1606233D01*
X133991Y1606275D01*
X133699Y1606233D01*
X133324Y1606067D01*
X133449Y1607150D01*
X134574D01*
G01X137049D02*
X136716Y1607067D01*
X136466Y1606858D01*
X136299Y1606608D01*
X136174Y1606275D01*
X136132Y1605900D01*
X136174Y1605525D01*
X136299Y1605192D01*
X136466Y1604942D01*
X136716Y1604733D01*
X137049Y1604650D01*
X137382Y1604733D01*
X137632Y1604942D01*
X137799Y1605192D01*
X137924Y1605525D01*
X137966Y1605900D01*
X137924Y1606275D01*
X137799Y1606608D01*
X137632Y1606858D01*
X137382Y1607067D01*
X137049Y1607150D01*
G01X162999Y1628087D02*
X139999D01*
G01D02*
Y1666887D01*
G01X124907Y1622880D02*
X124782Y1622630D01*
X124699Y1622338D01*
Y1622005D01*
X124824Y1621630D01*
X125032Y1621338D01*
X125282Y1621130D01*
X125699Y1620963D01*
X126074Y1620921D01*
X126449Y1621005D01*
X126699Y1621130D01*
X126949Y1621380D01*
X127116Y1621671D01*
X127199Y1621963D01*
Y1622255D01*
X127116Y1622546D01*
X126991Y1622796D01*
X126824Y1623005D01*
G01X125116Y1624271D02*
X124866Y1624521D01*
X124741Y1624813D01*
X124699Y1625146D01*
X124782Y1625563D01*
X124991Y1625855D01*
X125241Y1625938D01*
X125491Y1625896D01*
X125699Y1625730D01*
X126116Y1624896D01*
X126407Y1624521D01*
X126824Y1624271D01*
X127199Y1624188D01*
Y1625938D01*
G01Y1628080D02*
X126657Y1628163D01*
X126199Y1628288D01*
X125782Y1628455D01*
X125324Y1628663D01*
X124699Y1628996D01*
Y1627330D01*
G01X126699Y1630346D02*
X126991Y1630596D01*
X127157Y1630930D01*
X127199Y1631305D01*
X127157Y1631638D01*
X126949Y1631971D01*
X126699Y1632180D01*
X126449Y1632221D01*
X126157Y1632138D01*
X125949Y1631846D01*
X125866Y1631555D01*
Y1631180D01*
G01Y1631555D02*
X125741Y1631805D01*
X125532Y1632013D01*
X125282Y1632096D01*
X125032Y1632013D01*
X124824Y1631805D01*
X124699Y1631430D01*
X124741Y1631055D01*
X124907Y1630680D01*
G01X130199Y1640213D02*
Y1634713D01*
G01X132000Y1620517D02*
X129500D01*
Y1621558D01*
X129625Y1621892D01*
X129792Y1622100D01*
X130125Y1622183D01*
X130458Y1622100D01*
X130667Y1621850D01*
X130792Y1621558D01*
Y1620517D01*
G01Y1621558D02*
X132000Y1622183D01*
G01X131625Y1623533D02*
X131833Y1623783D01*
X131958Y1624075D01*
X132000Y1624450D01*
X131917Y1624825D01*
X131750Y1625117D01*
X131458Y1625325D01*
X131125Y1625367D01*
X130792Y1625283D01*
X130583Y1625075D01*
X130417Y1624783D01*
X130375Y1624492D01*
X130417Y1624200D01*
X130583Y1623825D01*
X129500Y1623950D01*
Y1625075D01*
G01X131500Y1626633D02*
X131792Y1626883D01*
X131958Y1627217D01*
X132000Y1627592D01*
X131958Y1627925D01*
X131750Y1628258D01*
X131500Y1628467D01*
X131250Y1628508D01*
X130958Y1628425D01*
X130750Y1628133D01*
X130667Y1627842D01*
Y1627467D01*
G01Y1627842D02*
X130542Y1628092D01*
X130333Y1628300D01*
X130083Y1628383D01*
X129833Y1628300D01*
X129625Y1628092D01*
X129500Y1627717D01*
X129542Y1627342D01*
X129708Y1626967D01*
G01X131500Y1629733D02*
X131792Y1629983D01*
X131958Y1630317D01*
X132000Y1630692D01*
X131958Y1631025D01*
X131750Y1631358D01*
X131500Y1631567D01*
X131250Y1631608D01*
X130958Y1631525D01*
X130750Y1631233D01*
X130667Y1630942D01*
Y1630567D01*
G01Y1630942D02*
X130542Y1631192D01*
X130333Y1631400D01*
X130083Y1631483D01*
X129833Y1631400D01*
X129625Y1631192D01*
X129500Y1630817D01*
X129542Y1630442D01*
X129708Y1630067D01*
G01X130900Y1652300D02*
Y1634700D01*
G01X138900D02*
Y1652300D01*
G01X130900Y1634700D02*
X138900D01*
G01X128999Y1653113D02*
Y1666113D01*
G01X129999Y1656313D02*
Y1661813D01*
G01X137999Y1656313D02*
X129999D01*
G01X137999Y1661813D02*
Y1656313D01*
G01X130199Y1652313D02*
Y1646813D01*
G01X138900Y1652300D02*
X130900D01*
G01X139999Y1666887D02*
X162999D01*
G01X140208Y1671267D02*
X140083Y1671017D01*
X140000Y1670725D01*
Y1670392D01*
X140125Y1670017D01*
X140333Y1669725D01*
X140583Y1669517D01*
X141000Y1669350D01*
X141375Y1669308D01*
X141750Y1669392D01*
X142000Y1669517D01*
X142250Y1669767D01*
X142417Y1670058D01*
X142500Y1670350D01*
Y1670642D01*
X142417Y1670933D01*
X142292Y1671183D01*
X142125Y1671392D01*
G01X140417Y1672658D02*
X140167Y1672908D01*
X140042Y1673200D01*
X140000Y1673533D01*
X140083Y1673950D01*
X140292Y1674242D01*
X140542Y1674325D01*
X140792Y1674283D01*
X141000Y1674117D01*
X141417Y1673283D01*
X141708Y1672908D01*
X142125Y1672658D01*
X142500Y1672575D01*
Y1674325D01*
G01Y1676467D02*
X141958Y1676550D01*
X141500Y1676675D01*
X141083Y1676842D01*
X140625Y1677050D01*
X140000Y1677383D01*
Y1675717D01*
G01X142500Y1679650D02*
X140000D01*
X140500Y1679150D01*
G01X142500D02*
Y1680150D01*
G01X137999Y1673913D02*
Y1668413D01*
G01X129999Y1673913D02*
X137999D01*
G01X129999Y1668413D02*
Y1673913D01*
G01X129499Y1686613D02*
Y1699613D01*
G01X133999Y1701350D02*
X137999D01*
Y1708750D01*
G01X129999Y1701350D02*
X133999D01*
Y1708750D01*
G01X138107Y1683550D02*
Y1686050D01*
X139691D01*
G01X139107Y1684842D02*
X138107D01*
G01X141207Y1685633D02*
X141457Y1685883D01*
X141749Y1686008D01*
X142082Y1686050D01*
X142499Y1685967D01*
X142791Y1685758D01*
X142874Y1685508D01*
X142832Y1685258D01*
X142666Y1685050D01*
X141832Y1684633D01*
X141457Y1684342D01*
X141207Y1683925D01*
X141124Y1683550D01*
X142874D01*
G01X145099D02*
Y1686050D01*
X144599Y1685550D01*
G01Y1683550D02*
X145599D01*
G01X148000Y1689017D02*
X145500D01*
Y1690058D01*
X145625Y1690392D01*
X145792Y1690600D01*
X146125Y1690683D01*
X146458Y1690600D01*
X146667Y1690350D01*
X146792Y1690058D01*
Y1689017D01*
G01Y1690058D02*
X148000Y1690683D01*
G01X147625Y1692033D02*
X147833Y1692283D01*
X147958Y1692575D01*
X148000Y1692950D01*
X147917Y1693325D01*
X147750Y1693617D01*
X147458Y1693825D01*
X147125Y1693867D01*
X146792Y1693783D01*
X146583Y1693575D01*
X146417Y1693283D01*
X146375Y1692992D01*
X146417Y1692700D01*
X146583Y1692325D01*
X145500Y1692450D01*
Y1693575D01*
G01X147500Y1695133D02*
X147792Y1695383D01*
X147958Y1695717D01*
X148000Y1696092D01*
X147958Y1696425D01*
X147750Y1696758D01*
X147500Y1696967D01*
X147250Y1697008D01*
X146958Y1696925D01*
X146750Y1696633D01*
X146667Y1696342D01*
Y1695967D01*
G01Y1696342D02*
X146542Y1696592D01*
X146333Y1696800D01*
X146083Y1696883D01*
X145833Y1696800D01*
X145625Y1696592D01*
X145500Y1696217D01*
X145542Y1695842D01*
X145708Y1695467D01*
G01X145917Y1698358D02*
X145667Y1698608D01*
X145542Y1698900D01*
X145500Y1699233D01*
X145583Y1699650D01*
X145792Y1699942D01*
X146042Y1700025D01*
X146292Y1699983D01*
X146500Y1699817D01*
X146917Y1698983D01*
X147208Y1698608D01*
X147625Y1698358D01*
X148000Y1698275D01*
Y1700025D01*
G01X143600Y1698100D02*
Y1691100D01*
X130200D01*
Y1698100D01*
X143600D01*
G01X142299Y1724550D02*
Y1720550D01*
X149699D01*
G01X142299D02*
Y1716550D01*
X149699D01*
G01X127199Y1722550D02*
Y1712550D01*
G01X140499Y1724750D02*
Y1711350D01*
G01X130499D02*
Y1724750D01*
G01X140499Y1711350D02*
X130499D01*
G01X129208Y1735767D02*
X129083Y1735517D01*
X129000Y1735225D01*
Y1734892D01*
X129125Y1734517D01*
X129333Y1734225D01*
X129583Y1734017D01*
X130000Y1733850D01*
X130375Y1733808D01*
X130750Y1733892D01*
X131000Y1734017D01*
X131250Y1734267D01*
X131417Y1734558D01*
X131500Y1734850D01*
Y1735142D01*
X131417Y1735433D01*
X131292Y1735683D01*
X131125Y1735892D01*
G01X129417Y1737158D02*
X129167Y1737408D01*
X129042Y1737700D01*
X129000Y1738033D01*
X129083Y1738450D01*
X129292Y1738742D01*
X129542Y1738825D01*
X129792Y1738783D01*
X130000Y1738617D01*
X130417Y1737783D01*
X130708Y1737408D01*
X131125Y1737158D01*
X131500Y1737075D01*
Y1738825D01*
G01X130458Y1740258D02*
X130167Y1740550D01*
X130000Y1740800D01*
X129917Y1741133D01*
X130000Y1741425D01*
X130167Y1741633D01*
X130417Y1741800D01*
X130708Y1741842D01*
X130958Y1741800D01*
X131208Y1741633D01*
X131417Y1741383D01*
X131500Y1741092D01*
X131417Y1740758D01*
X131167Y1740467D01*
X130792Y1740300D01*
X130375Y1740258D01*
X129833Y1740342D01*
X129542Y1740467D01*
X129250Y1740675D01*
X129042Y1740967D01*
X129000Y1741258D01*
X129083Y1741550D01*
X129292Y1741758D01*
G01X131500Y1744150D02*
X129000D01*
X129500Y1743650D01*
G01X131500D02*
Y1744650D01*
G01X127517Y1730000D02*
Y1732500D01*
X128558D01*
X128892Y1732375D01*
X129100Y1732208D01*
X129183Y1731875D01*
X129100Y1731542D01*
X128850Y1731333D01*
X128558Y1731208D01*
X127517D01*
G01X128558D02*
X129183Y1730000D01*
G01X131950D02*
Y1732500D01*
X130408Y1730708D01*
X132492D01*
G01X133758Y1731042D02*
X134050Y1731333D01*
X134300Y1731500D01*
X134633Y1731583D01*
X134925Y1731500D01*
X135133Y1731333D01*
X135300Y1731083D01*
X135342Y1730792D01*
X135300Y1730542D01*
X135133Y1730292D01*
X134883Y1730083D01*
X134592Y1730000D01*
X134258Y1730083D01*
X133967Y1730333D01*
X133800Y1730708D01*
X133758Y1731125D01*
X133842Y1731667D01*
X133967Y1731958D01*
X134175Y1732250D01*
X134467Y1732458D01*
X134758Y1732500D01*
X135050Y1732417D01*
X135258Y1732208D01*
G01X136858Y1732083D02*
X137108Y1732333D01*
X137400Y1732458D01*
X137733Y1732500D01*
X138150Y1732417D01*
X138442Y1732208D01*
X138525Y1731958D01*
X138483Y1731708D01*
X138317Y1731500D01*
X137483Y1731083D01*
X137108Y1730792D01*
X136858Y1730375D01*
X136775Y1730000D01*
X138525D01*
G01X127517Y1726500D02*
Y1729000D01*
X128558D01*
X128892Y1728875D01*
X129100Y1728708D01*
X129183Y1728375D01*
X129100Y1728042D01*
X128850Y1727833D01*
X128558Y1727708D01*
X127517D01*
G01X128558D02*
X129183Y1726500D01*
G01X131950D02*
Y1729000D01*
X130408Y1727208D01*
X132492D01*
G01X133758Y1727542D02*
X134050Y1727833D01*
X134300Y1728000D01*
X134633Y1728083D01*
X134925Y1728000D01*
X135133Y1727833D01*
X135300Y1727583D01*
X135342Y1727292D01*
X135300Y1727042D01*
X135133Y1726792D01*
X134883Y1726583D01*
X134592Y1726500D01*
X134258Y1726583D01*
X133967Y1726833D01*
X133800Y1727208D01*
X133758Y1727625D01*
X133842Y1728167D01*
X133967Y1728458D01*
X134175Y1728750D01*
X134467Y1728958D01*
X134758Y1729000D01*
X135050Y1728917D01*
X135258Y1728708D01*
G01X136733Y1727000D02*
X136983Y1726708D01*
X137317Y1726542D01*
X137692Y1726500D01*
X138025Y1726542D01*
X138358Y1726750D01*
X138567Y1727000D01*
X138608Y1727250D01*
X138525Y1727542D01*
X138233Y1727750D01*
X137942Y1727833D01*
X137567D01*
G01X137942D02*
X138192Y1727958D01*
X138400Y1728167D01*
X138483Y1728417D01*
X138400Y1728667D01*
X138192Y1728875D01*
X137817Y1729000D01*
X137442Y1728958D01*
X137067Y1728792D01*
G01X140983Y1729500D02*
Y1727708D01*
X141150Y1727333D01*
X141483Y1727083D01*
X141900Y1727000D01*
X142317Y1727083D01*
X142650Y1727333D01*
X142817Y1727708D01*
Y1729500D01*
G01X144083Y1727500D02*
X144333Y1727208D01*
X144667Y1727042D01*
X145042Y1727000D01*
X145375Y1727042D01*
X145708Y1727250D01*
X145917Y1727500D01*
X145958Y1727750D01*
X145875Y1728042D01*
X145583Y1728250D01*
X145292Y1728333D01*
X144917D01*
G01X145292D02*
X145542Y1728458D01*
X145750Y1728667D01*
X145833Y1728917D01*
X145750Y1729167D01*
X145542Y1729375D01*
X145167Y1729500D01*
X144792Y1729458D01*
X144417Y1729292D01*
G01X147183Y1727500D02*
X147433Y1727208D01*
X147767Y1727042D01*
X148142Y1727000D01*
X148475Y1727042D01*
X148808Y1727250D01*
X149017Y1727500D01*
X149058Y1727750D01*
X148975Y1728042D01*
X148683Y1728250D01*
X148392Y1728333D01*
X148017D01*
G01X148392D02*
X148642Y1728458D01*
X148850Y1728667D01*
X148933Y1728917D01*
X148850Y1729167D01*
X148642Y1729375D01*
X148267Y1729500D01*
X147892Y1729458D01*
X147517Y1729292D01*
G01X130499Y1724750D02*
X140499D01*
G01X137708Y1747267D02*
X137583Y1747017D01*
X137500Y1746725D01*
Y1746392D01*
X137625Y1746017D01*
X137833Y1745725D01*
X138083Y1745517D01*
X138500Y1745350D01*
X138875Y1745308D01*
X139250Y1745392D01*
X139500Y1745517D01*
X139750Y1745767D01*
X139917Y1746058D01*
X140000Y1746350D01*
Y1746642D01*
X139917Y1746933D01*
X139792Y1747183D01*
X139625Y1747392D01*
G01X137917Y1748658D02*
X137667Y1748908D01*
X137542Y1749200D01*
X137500Y1749533D01*
X137583Y1749950D01*
X137792Y1750242D01*
X138042Y1750325D01*
X138292Y1750283D01*
X138500Y1750117D01*
X138917Y1749283D01*
X139208Y1748908D01*
X139625Y1748658D01*
X140000Y1748575D01*
Y1750325D01*
G01X138958Y1751758D02*
X138667Y1752050D01*
X138500Y1752300D01*
X138417Y1752633D01*
X138500Y1752925D01*
X138667Y1753133D01*
X138917Y1753300D01*
X139208Y1753342D01*
X139458Y1753300D01*
X139708Y1753133D01*
X139917Y1752883D01*
X140000Y1752592D01*
X139917Y1752258D01*
X139667Y1751967D01*
X139292Y1751800D01*
X138875Y1751758D01*
X138333Y1751842D01*
X138042Y1751967D01*
X137750Y1752175D01*
X137542Y1752467D01*
X137500Y1752758D01*
X137583Y1753050D01*
X137792Y1753258D01*
G01X139708Y1754942D02*
X139917Y1755233D01*
X140000Y1755567D01*
X139917Y1755900D01*
X139667Y1756192D01*
X139292Y1756400D01*
X138917Y1756483D01*
X138458D01*
X138083Y1756400D01*
X137750Y1756192D01*
X137583Y1755942D01*
X137500Y1755650D01*
X137583Y1755317D01*
X137750Y1755067D01*
X138000Y1754900D01*
X138333Y1754817D01*
X138625Y1754900D01*
X138917Y1755108D01*
X139083Y1755358D01*
X139125Y1755650D01*
X139042Y1755983D01*
X138833Y1756233D01*
X138458Y1756483D01*
G01X140488Y1785409D02*
Y1787909D01*
X141529D01*
X141863Y1787784D01*
X142071Y1787617D01*
X142154Y1787284D01*
X142071Y1786951D01*
X141821Y1786742D01*
X141529Y1786617D01*
X140488D01*
G01X141529D02*
X142154Y1785409D01*
G01X144421D02*
Y1787909D01*
X143921Y1787409D01*
G01Y1785409D02*
X144921D01*
G01X147438D02*
X147521Y1785951D01*
X147646Y1786409D01*
X147813Y1786826D01*
X148021Y1787284D01*
X148354Y1787909D01*
X146688D01*
G01X150621Y1785409D02*
Y1787909D01*
X150121Y1787409D01*
G01Y1785409D02*
X151121D01*
G01X140488Y1781409D02*
Y1783909D01*
X141529D01*
X141863Y1783784D01*
X142071Y1783617D01*
X142154Y1783284D01*
X142071Y1782951D01*
X141821Y1782742D01*
X141529Y1782617D01*
X140488D01*
G01X141529D02*
X142154Y1781409D01*
G01X144421D02*
Y1783909D01*
X143921Y1783409D01*
G01Y1781409D02*
X144921D01*
G01X147438D02*
X147521Y1781951D01*
X147646Y1782409D01*
X147813Y1782826D01*
X148021Y1783284D01*
X148354Y1783909D01*
X146688D01*
G01X149704Y1781909D02*
X149954Y1781617D01*
X150288Y1781451D01*
X150663Y1781409D01*
X150996Y1781451D01*
X151329Y1781659D01*
X151538Y1781909D01*
X151579Y1782159D01*
X151496Y1782451D01*
X151204Y1782659D01*
X150913Y1782742D01*
X150538D01*
G01X150913D02*
X151163Y1782867D01*
X151371Y1783076D01*
X151454Y1783326D01*
X151371Y1783576D01*
X151163Y1783784D01*
X150788Y1783909D01*
X150413Y1783867D01*
X150038Y1783701D01*
G01X144623Y1807865D02*
Y1969065D01*
X158223D01*
Y1982015D01*
X176423D01*
Y1969065D01*
X205323D01*
Y1958715D01*
X198623D01*
Y1818215D01*
X205323D01*
Y1807865D01*
X176423D01*
Y1794915D01*
X158223D01*
Y1807865D01*
X144623D01*
G01X127359Y1864046D02*
X127109Y1864171D01*
X126817Y1864254D01*
X126484D01*
X126109Y1864129D01*
X125817Y1863921D01*
X125609Y1863671D01*
X125442Y1863254D01*
X125400Y1862879D01*
X125484Y1862504D01*
X125609Y1862254D01*
X125859Y1862004D01*
X126150Y1861837D01*
X126442Y1861754D01*
X126734D01*
X127025Y1861837D01*
X127275Y1861962D01*
X127484Y1862129D01*
G01X129542Y1861754D02*
Y1864254D01*
X129042Y1863754D01*
G01Y1861754D02*
X130042D01*
G01X132642D02*
X132934Y1861796D01*
X133267Y1861921D01*
X133475Y1862129D01*
X133559Y1862421D01*
X133475Y1862712D01*
X133225Y1862962D01*
X132850Y1863087D01*
X132434D01*
X132184Y1863171D01*
X131975Y1863379D01*
X131892Y1863671D01*
X132017Y1863962D01*
X132309Y1864171D01*
X132642Y1864254D01*
X132975Y1864171D01*
X133267Y1863962D01*
X133392Y1863671D01*
X133309Y1863379D01*
X133100Y1863171D01*
X132850Y1863087D01*
X132434D01*
X132059Y1862962D01*
X131809Y1862712D01*
X131725Y1862421D01*
X131809Y1862129D01*
X132017Y1861921D01*
X132350Y1861796D01*
X132642Y1861754D01*
G01X136242D02*
Y1864254D01*
X134700Y1862462D01*
X136784D01*
G01X127359Y1867546D02*
X127109Y1867671D01*
X126817Y1867754D01*
X126484D01*
X126109Y1867629D01*
X125817Y1867421D01*
X125609Y1867171D01*
X125442Y1866754D01*
X125400Y1866379D01*
X125484Y1866004D01*
X125609Y1865754D01*
X125859Y1865504D01*
X126150Y1865337D01*
X126442Y1865254D01*
X126734D01*
X127025Y1865337D01*
X127275Y1865462D01*
X127484Y1865629D01*
G01X129542Y1865254D02*
Y1867754D01*
X129042Y1867254D01*
G01Y1865254D02*
X130042D01*
G01X132642D02*
X132934Y1865296D01*
X133267Y1865421D01*
X133475Y1865629D01*
X133559Y1865921D01*
X133475Y1866212D01*
X133225Y1866462D01*
X132850Y1866587D01*
X132434D01*
X132184Y1866671D01*
X131975Y1866879D01*
X131892Y1867171D01*
X132017Y1867462D01*
X132309Y1867671D01*
X132642Y1867754D01*
X132975Y1867671D01*
X133267Y1867462D01*
X133392Y1867171D01*
X133309Y1866879D01*
X133100Y1866671D01*
X132850Y1866587D01*
X132434D01*
X132059Y1866462D01*
X131809Y1866212D01*
X131725Y1865921D01*
X131809Y1865629D01*
X132017Y1865421D01*
X132350Y1865296D01*
X132642Y1865254D01*
G01X134825Y1865629D02*
X135075Y1865421D01*
X135367Y1865296D01*
X135742Y1865254D01*
X136117Y1865337D01*
X136409Y1865504D01*
X136617Y1865796D01*
X136659Y1866129D01*
X136575Y1866462D01*
X136367Y1866671D01*
X136075Y1866837D01*
X135784Y1866879D01*
X135492Y1866837D01*
X135117Y1866671D01*
X135242Y1867754D01*
X136367D01*
G01X126017Y1881000D02*
Y1883500D01*
X127017D01*
X127350Y1883375D01*
X127600Y1883083D01*
X127683Y1882750D01*
X127600Y1882417D01*
X127392Y1882167D01*
X127017Y1882042D01*
X126017D01*
G01X129950Y1883500D02*
Y1881000D01*
G01X128992Y1883500D02*
X130908D01*
G01X133967Y1883292D02*
X133717Y1883417D01*
X133425Y1883500D01*
X133092D01*
X132717Y1883375D01*
X132425Y1883167D01*
X132217Y1882917D01*
X132050Y1882500D01*
X132008Y1882125D01*
X132092Y1881750D01*
X132217Y1881500D01*
X132467Y1881250D01*
X132758Y1881083D01*
X133050Y1881000D01*
X133342D01*
X133633Y1881083D01*
X133883Y1881208D01*
X134092Y1881375D01*
G01X135233D02*
X135483Y1881167D01*
X135775Y1881042D01*
X136150Y1881000D01*
X136525Y1881083D01*
X136817Y1881250D01*
X137025Y1881542D01*
X137067Y1881875D01*
X136983Y1882208D01*
X136775Y1882417D01*
X136483Y1882583D01*
X136192Y1882625D01*
X135900Y1882583D01*
X135525Y1882417D01*
X135650Y1883500D01*
X136775D01*
G01X126017Y1885000D02*
Y1887500D01*
X127017D01*
X127350Y1887375D01*
X127600Y1887083D01*
X127683Y1886750D01*
X127600Y1886417D01*
X127392Y1886167D01*
X127017Y1886042D01*
X126017D01*
G01X129950Y1887500D02*
Y1885000D01*
G01X128992Y1887500D02*
X130908D01*
G01X133967Y1887292D02*
X133717Y1887417D01*
X133425Y1887500D01*
X133092D01*
X132717Y1887375D01*
X132425Y1887167D01*
X132217Y1886917D01*
X132050Y1886500D01*
X132008Y1886125D01*
X132092Y1885750D01*
X132217Y1885500D01*
X132467Y1885250D01*
X132758Y1885083D01*
X133050Y1885000D01*
X133342D01*
X133633Y1885083D01*
X133883Y1885208D01*
X134092Y1885375D01*
G01X135358Y1886042D02*
X135650Y1886333D01*
X135900Y1886500D01*
X136233Y1886583D01*
X136525Y1886500D01*
X136733Y1886333D01*
X136900Y1886083D01*
X136942Y1885792D01*
X136900Y1885542D01*
X136733Y1885292D01*
X136483Y1885083D01*
X136192Y1885000D01*
X135858Y1885083D01*
X135567Y1885333D01*
X135400Y1885708D01*
X135358Y1886125D01*
X135442Y1886667D01*
X135567Y1886958D01*
X135775Y1887250D01*
X136067Y1887458D01*
X136358Y1887500D01*
X136650Y1887417D01*
X136858Y1887208D01*
G01X141667Y1901538D02*
X141875Y1901871D01*
X142000Y1902246D01*
Y1902580D01*
X141875Y1902913D01*
X141667Y1903163D01*
X141375Y1903288D01*
X141083Y1903205D01*
X140833Y1902996D01*
X140667Y1902621D01*
X140583Y1902121D01*
X140417Y1901830D01*
X140125Y1901705D01*
X139833Y1901788D01*
X139625Y1901996D01*
X139500Y1902288D01*
Y1902580D01*
X139583Y1902871D01*
X139792Y1903121D01*
G01X142000Y1904596D02*
X139500D01*
G01Y1906180D02*
X141042Y1904596D01*
G01X142000Y1906430D02*
X140333Y1905305D01*
G01X139500Y1908613D02*
X142000D01*
G01X139500Y1907655D02*
Y1909571D01*
G01X140958Y1910921D02*
X140667Y1911213D01*
X140500Y1911463D01*
X140417Y1911796D01*
X140500Y1912088D01*
X140667Y1912296D01*
X140917Y1912463D01*
X141208Y1912505D01*
X141458Y1912463D01*
X141708Y1912296D01*
X141917Y1912046D01*
X142000Y1911755D01*
X141917Y1911421D01*
X141667Y1911130D01*
X141292Y1910963D01*
X140875Y1910921D01*
X140333Y1911005D01*
X140042Y1911130D01*
X139750Y1911338D01*
X139542Y1911630D01*
X139500Y1911921D01*
X139583Y1912213D01*
X139792Y1912421D01*
G01X124799Y1958950D02*
Y1969150D01*
G01Y1958950D02*
Y1969150D01*
G01X165999Y109250D02*
Y114750D01*
G01X173999Y109250D02*
X165999D01*
G01X163521Y100877D02*
Y112077D01*
G01X165999Y126850D02*
X173999D01*
G01X165999Y121350D02*
Y126850D01*
G01X163521Y139277D02*
Y128077D01*
G01X155500Y142017D02*
X153000D01*
Y143017D01*
X153125Y143350D01*
X153417Y143600D01*
X153750Y143683D01*
X154083Y143600D01*
X154333Y143392D01*
X154458Y143017D01*
Y142017D01*
G01X153000Y145950D02*
X155500D01*
G01X153000Y144992D02*
Y146908D01*
G01X153208Y149967D02*
X153083Y149717D01*
X153000Y149425D01*
Y149092D01*
X153125Y148717D01*
X153333Y148425D01*
X153583Y148217D01*
X154000Y148050D01*
X154375Y148008D01*
X154750Y148092D01*
X155000Y148217D01*
X155250Y148467D01*
X155417Y148758D01*
X155500Y149050D01*
Y149342D01*
X155417Y149633D01*
X155292Y149883D01*
X155125Y150092D01*
G01X155000Y151233D02*
X155292Y151483D01*
X155458Y151817D01*
X155500Y152192D01*
X155458Y152525D01*
X155250Y152858D01*
X155000Y153067D01*
X154750Y153108D01*
X154458Y153025D01*
X154250Y152733D01*
X154167Y152442D01*
Y152067D01*
G01Y152442D02*
X154042Y152692D01*
X153833Y152900D01*
X153583Y152983D01*
X153333Y152900D01*
X153125Y152692D01*
X153000Y152317D01*
X153042Y151942D01*
X153208Y151567D01*
G01X159967Y170563D02*
Y168063D01*
X161633D01*
G01X164733D02*
X163067D01*
Y170563D01*
X164733D01*
G01X164067Y169355D02*
X163067D01*
G01X166083Y168063D02*
Y170563D01*
X166917D01*
X167250Y170438D01*
X167500Y170271D01*
X167708Y170021D01*
X167875Y169730D01*
X167917Y169313D01*
X167875Y168896D01*
X167708Y168605D01*
X167500Y168355D01*
X167250Y168188D01*
X166917Y168063D01*
X166083D01*
G01X170100D02*
Y170563D01*
X169600Y170063D01*
G01Y168063D02*
X170600D01*
G01X173200Y170563D02*
X172867Y170480D01*
X172617Y170271D01*
X172450Y170021D01*
X172325Y169688D01*
X172283Y169313D01*
X172325Y168938D01*
X172450Y168605D01*
X172617Y168355D01*
X172867Y168146D01*
X173200Y168063D01*
X173533Y168146D01*
X173783Y168355D01*
X173950Y168605D01*
X174075Y168938D01*
X174117Y169313D01*
X174075Y169688D01*
X173950Y170021D01*
X173783Y170271D01*
X173533Y170480D01*
X173200Y170563D01*
G01X173023Y165847D02*
Y158247D01*
X161623D01*
Y165847D01*
X173023D01*
G01X152799Y167050D02*
Y163050D01*
X160199D01*
G01X152799D02*
Y159050D01*
X160199D01*
G01X158418Y405972D02*
X158085Y406014D01*
X157793Y406180D01*
X157543Y406430D01*
X157376Y406722D01*
X157293Y407055D01*
Y407389D01*
X157376Y407722D01*
X157543Y408014D01*
X157793Y408264D01*
X158085Y408430D01*
X158418Y408472D01*
X158751Y408430D01*
X159043Y408264D01*
X159293Y408014D01*
X159460Y407722D01*
X159543Y407389D01*
Y407055D01*
X159460Y406722D01*
X159293Y406430D01*
X159043Y406180D01*
X158751Y406014D01*
X158418Y405972D01*
G01X158751Y406639D02*
X159251Y405972D01*
G01X160726Y408055D02*
X160976Y408305D01*
X161268Y408430D01*
X161601Y408472D01*
X162018Y408389D01*
X162310Y408180D01*
X162393Y407930D01*
X162351Y407680D01*
X162185Y407472D01*
X161351Y407055D01*
X160976Y406764D01*
X160726Y406347D01*
X160643Y405972D01*
X162393D01*
G01X164618D02*
X164910Y406014D01*
X165243Y406139D01*
X165451Y406347D01*
X165535Y406639D01*
X165451Y406930D01*
X165201Y407180D01*
X164826Y407305D01*
X164410D01*
X164160Y407389D01*
X163951Y407597D01*
X163868Y407889D01*
X163993Y408180D01*
X164285Y408389D01*
X164618Y408472D01*
X164951Y408389D01*
X165243Y408180D01*
X165368Y407889D01*
X165285Y407597D01*
X165076Y407389D01*
X164826Y407305D01*
X164410D01*
X164035Y407180D01*
X163785Y406930D01*
X163701Y406639D01*
X163785Y406347D01*
X163993Y406139D01*
X164326Y406014D01*
X164618Y405972D01*
G01X161018Y410052D02*
X158518D01*
Y411093D01*
X158643Y411427D01*
X158810Y411635D01*
X159143Y411718D01*
X159476Y411635D01*
X159685Y411385D01*
X159810Y411093D01*
Y410052D01*
G01Y411093D02*
X161018Y411718D01*
G01X158935Y413193D02*
X158685Y413443D01*
X158560Y413735D01*
X158518Y414068D01*
X158601Y414485D01*
X158810Y414777D01*
X159060Y414860D01*
X159310Y414818D01*
X159518Y414652D01*
X159935Y413818D01*
X160226Y413443D01*
X160643Y413193D01*
X161018Y413110D01*
Y414860D01*
G01Y417085D02*
X160976Y417377D01*
X160851Y417710D01*
X160643Y417918D01*
X160351Y418002D01*
X160060Y417918D01*
X159810Y417668D01*
X159685Y417293D01*
Y416877D01*
X159601Y416627D01*
X159393Y416418D01*
X159101Y416335D01*
X158810Y416460D01*
X158601Y416752D01*
X158518Y417085D01*
X158601Y417418D01*
X158810Y417710D01*
X159101Y417835D01*
X159393Y417752D01*
X159601Y417543D01*
X159685Y417293D01*
Y416877D01*
X159810Y416502D01*
X160060Y416252D01*
X160351Y416168D01*
X160643Y416252D01*
X160851Y416460D01*
X160976Y416793D01*
X161018Y417085D01*
G01Y420185D02*
X160976Y420477D01*
X160851Y420810D01*
X160643Y421018D01*
X160351Y421102D01*
X160060Y421018D01*
X159810Y420768D01*
X159685Y420393D01*
Y419977D01*
X159601Y419727D01*
X159393Y419518D01*
X159101Y419435D01*
X158810Y419560D01*
X158601Y419852D01*
X158518Y420185D01*
X158601Y420518D01*
X158810Y420810D01*
X159101Y420935D01*
X159393Y420852D01*
X159601Y420643D01*
X159685Y420393D01*
Y419977D01*
X159810Y419602D01*
X160060Y419352D01*
X160351Y419268D01*
X160643Y419352D01*
X160851Y419560D01*
X160976Y419893D01*
X161018Y420185D01*
G01X165018Y410052D02*
X162518D01*
Y411093D01*
X162643Y411427D01*
X162810Y411635D01*
X163143Y411718D01*
X163476Y411635D01*
X163685Y411385D01*
X163810Y411093D01*
Y410052D01*
G01Y411093D02*
X165018Y411718D01*
G01X162935Y413193D02*
X162685Y413443D01*
X162560Y413735D01*
X162518Y414068D01*
X162601Y414485D01*
X162810Y414777D01*
X163060Y414860D01*
X163310Y414818D01*
X163518Y414652D01*
X163935Y413818D01*
X164226Y413443D01*
X164643Y413193D01*
X165018Y413110D01*
Y414860D01*
G01X164726Y416377D02*
X164935Y416668D01*
X165018Y417002D01*
X164935Y417335D01*
X164685Y417627D01*
X164310Y417835D01*
X163935Y417918D01*
X163476D01*
X163101Y417835D01*
X162768Y417627D01*
X162601Y417377D01*
X162518Y417085D01*
X162601Y416752D01*
X162768Y416502D01*
X163018Y416335D01*
X163351Y416252D01*
X163643Y416335D01*
X163935Y416543D01*
X164101Y416793D01*
X164143Y417085D01*
X164060Y417418D01*
X163851Y417668D01*
X163476Y417918D01*
G01X162518Y420185D02*
X162601Y419852D01*
X162810Y419602D01*
X163060Y419435D01*
X163393Y419310D01*
X163768Y419268D01*
X164143Y419310D01*
X164476Y419435D01*
X164726Y419602D01*
X164935Y419852D01*
X165018Y420185D01*
X164935Y420518D01*
X164726Y420768D01*
X164476Y420935D01*
X164143Y421060D01*
X163768Y421102D01*
X163393Y421060D01*
X163060Y420935D01*
X162810Y420768D01*
X162601Y420518D01*
X162518Y420185D01*
G01X153628Y406167D02*
X151128D01*
Y407208D01*
X151253Y407542D01*
X151420Y407750D01*
X151753Y407833D01*
X152086Y407750D01*
X152295Y407500D01*
X152420Y407208D01*
Y406167D01*
G01Y407208D02*
X153628Y407833D01*
G01X151545Y409308D02*
X151295Y409558D01*
X151170Y409850D01*
X151128Y410183D01*
X151211Y410600D01*
X151420Y410892D01*
X151670Y410975D01*
X151920Y410933D01*
X152128Y410767D01*
X152545Y409933D01*
X152836Y409558D01*
X153253Y409308D01*
X153628Y409225D01*
Y410975D01*
G01X153336Y412492D02*
X153545Y412783D01*
X153628Y413117D01*
X153545Y413450D01*
X153295Y413742D01*
X152920Y413950D01*
X152545Y414033D01*
X152086D01*
X151711Y413950D01*
X151378Y413742D01*
X151211Y413492D01*
X151128Y413200D01*
X151211Y412867D01*
X151378Y412617D01*
X151628Y412450D01*
X151961Y412367D01*
X152253Y412450D01*
X152545Y412658D01*
X152711Y412908D01*
X152753Y413200D01*
X152670Y413533D01*
X152461Y413783D01*
X152086Y414033D01*
G01X153628Y416800D02*
X151128D01*
X152920Y415258D01*
Y417342D01*
G01X149128Y406167D02*
X146628D01*
Y407208D01*
X146753Y407542D01*
X146920Y407750D01*
X147253Y407833D01*
X147586Y407750D01*
X147795Y407500D01*
X147920Y407208D01*
Y406167D01*
G01Y407208D02*
X149128Y407833D01*
G01X147045Y409308D02*
X146795Y409558D01*
X146670Y409850D01*
X146628Y410183D01*
X146711Y410600D01*
X146920Y410892D01*
X147170Y410975D01*
X147420Y410933D01*
X147628Y410767D01*
X148045Y409933D01*
X148336Y409558D01*
X148753Y409308D01*
X149128Y409225D01*
Y410975D01*
G01X148836Y412492D02*
X149045Y412783D01*
X149128Y413117D01*
X149045Y413450D01*
X148795Y413742D01*
X148420Y413950D01*
X148045Y414033D01*
X147586D01*
X147211Y413950D01*
X146878Y413742D01*
X146711Y413492D01*
X146628Y413200D01*
X146711Y412867D01*
X146878Y412617D01*
X147128Y412450D01*
X147461Y412367D01*
X147753Y412450D01*
X148045Y412658D01*
X148211Y412908D01*
X148253Y413200D01*
X148170Y413533D01*
X147961Y413783D01*
X147586Y414033D01*
G01X148753Y415383D02*
X148961Y415633D01*
X149086Y415925D01*
X149128Y416300D01*
X149045Y416675D01*
X148878Y416967D01*
X148586Y417175D01*
X148253Y417217D01*
X147920Y417133D01*
X147711Y416925D01*
X147545Y416633D01*
X147503Y416342D01*
X147545Y416050D01*
X147711Y415675D01*
X146628Y415800D01*
Y416925D01*
G01X155299Y441313D02*
Y429913D01*
G01D02*
X168699D01*
G01X152999Y436813D02*
Y423413D01*
G01X168699Y441313D02*
X155299D01*
G01X164999Y449313D02*
X160999D01*
Y441913D01*
G01X168999Y449313D02*
X164999D01*
Y441913D01*
G01X152999Y445813D02*
X148999D01*
Y438413D01*
G01X154999Y449813D02*
Y455313D01*
G01X162999Y449813D02*
X154999D01*
G01X162999Y455313D02*
Y449813D01*
G01X145999D02*
Y455313D01*
G01X153999Y449813D02*
X145999D01*
G01X153999Y455313D02*
Y449813D01*
G01X163900Y449800D02*
Y455300D01*
G01X171900Y449800D02*
X163900D01*
G01X162999Y468050D02*
Y481050D01*
G01Y467413D02*
Y461913D01*
G01X154999Y467413D02*
X162999D01*
G01X154999Y461913D02*
Y467413D01*
G01X153999D02*
Y461913D01*
G01X145999Y467413D02*
X153999D01*
G01X145999Y461913D02*
Y467413D01*
G01X163900Y467400D02*
X171900D01*
G01X163900Y461900D02*
Y467400D01*
G01X150499Y500913D02*
Y495413D01*
G01Y488813D02*
Y483313D01*
G01X151889Y499863D02*
Y490363D01*
X169589D01*
Y499863D01*
X151889D01*
G01X165017Y478000D02*
Y480500D01*
X166058D01*
X166392Y480375D01*
X166600Y480208D01*
X166683Y479875D01*
X166600Y479542D01*
X166350Y479333D01*
X166058Y479208D01*
X165017D01*
G01X166058D02*
X166683Y478000D01*
G01X168033Y478375D02*
X168283Y478167D01*
X168575Y478042D01*
X168950Y478000D01*
X169325Y478083D01*
X169617Y478250D01*
X169825Y478542D01*
X169867Y478875D01*
X169783Y479208D01*
X169575Y479417D01*
X169283Y479583D01*
X168992Y479625D01*
X168700Y479583D01*
X168325Y479417D01*
X168450Y480500D01*
X169575D01*
G01X171133Y478500D02*
X171383Y478208D01*
X171717Y478042D01*
X172092Y478000D01*
X172425Y478042D01*
X172758Y478250D01*
X172967Y478500D01*
X173008Y478750D01*
X172925Y479042D01*
X172633Y479250D01*
X172342Y479333D01*
X171967D01*
G01X172342D02*
X172592Y479458D01*
X172800Y479667D01*
X172883Y479917D01*
X172800Y480167D01*
X172592Y480375D01*
X172217Y480500D01*
X171842Y480458D01*
X171467Y480292D01*
G01X175150Y478000D02*
X175442Y478042D01*
X175775Y478167D01*
X175983Y478375D01*
X176067Y478667D01*
X175983Y478958D01*
X175733Y479208D01*
X175358Y479333D01*
X174942D01*
X174692Y479417D01*
X174483Y479625D01*
X174400Y479917D01*
X174525Y480208D01*
X174817Y480417D01*
X175150Y480500D01*
X175483Y480417D01*
X175775Y480208D01*
X175900Y479917D01*
X175817Y479625D01*
X175608Y479417D01*
X175358Y479333D01*
X174942D01*
X174567Y479208D01*
X174317Y478958D01*
X174233Y478667D01*
X174317Y478375D01*
X174525Y478167D01*
X174858Y478042D01*
X175150Y478000D01*
G01X170000Y489000D02*
Y482000D01*
X156600D01*
Y489000D01*
X170000D01*
G01X163249Y501613D02*
Y514613D01*
G01X153699Y515613D02*
Y519613D01*
X146299D01*
G01X157199Y515150D02*
X161199D01*
Y522550D01*
G01X165199Y515150D02*
X169199D01*
Y522550D01*
G01X152099Y542050D02*
Y538050D01*
X159499D01*
G01X161399Y522850D02*
Y526850D01*
X153999D01*
G01X168899Y522850D02*
Y526850D01*
X161499D01*
G01X163467Y545378D02*
Y537378D01*
X175417D01*
Y545378D01*
X163467D01*
G01X151500Y528300D02*
Y542300D01*
G01X149200Y547300D02*
Y560700D01*
G01X152099Y546250D02*
Y542250D01*
X159499D01*
G01X151400Y558000D02*
Y555500D01*
G01X150442Y558000D02*
X152358D01*
G01X153667Y555500D02*
Y558000D01*
X154667D01*
X155000Y557875D01*
X155250Y557583D01*
X155333Y557250D01*
X155250Y556917D01*
X155042Y556667D01*
X154667Y556542D01*
X153667D01*
G01X156808Y557583D02*
X157058Y557833D01*
X157350Y557958D01*
X157683Y558000D01*
X158100Y557917D01*
X158392Y557708D01*
X158475Y557458D01*
X158433Y557208D01*
X158267Y557000D01*
X157433Y556583D01*
X157058Y556292D01*
X156808Y555875D01*
X156725Y555500D01*
X158475D01*
G01X173023Y571359D02*
Y563759D01*
X161623D01*
Y571359D01*
X173023D01*
G01X152299Y572050D02*
Y568050D01*
X159699D01*
G01X152299D02*
Y564050D01*
X159699D01*
G01X167499Y794630D02*
X164999D01*
Y795671D01*
X165124Y796005D01*
X165291Y796213D01*
X165624Y796296D01*
X165957Y796213D01*
X166166Y795963D01*
X166291Y795671D01*
Y794630D01*
G01Y795671D02*
X167499Y796296D01*
G01Y799063D02*
X164999D01*
X166791Y797521D01*
Y799605D01*
G01X167499Y801580D02*
X166957Y801663D01*
X166499Y801788D01*
X166082Y801955D01*
X165624Y802163D01*
X164999Y802496D01*
Y800830D01*
G01X167499Y804763D02*
X164999D01*
X165499Y804263D01*
G01X167499D02*
Y805263D01*
G01X164499Y806913D02*
X168499D01*
Y814313D01*
G01X154208Y816267D02*
X154083Y816017D01*
X154000Y815725D01*
Y815392D01*
X154125Y815017D01*
X154333Y814725D01*
X154583Y814517D01*
X155000Y814350D01*
X155375Y814308D01*
X155750Y814392D01*
X156000Y814517D01*
X156250Y814767D01*
X156417Y815058D01*
X156500Y815350D01*
Y815642D01*
X156417Y815933D01*
X156292Y816183D01*
X156125Y816392D01*
G01X156000Y817533D02*
X156292Y817783D01*
X156458Y818117D01*
X156500Y818492D01*
X156458Y818825D01*
X156250Y819158D01*
X156000Y819367D01*
X155750Y819408D01*
X155458Y819325D01*
X155250Y819033D01*
X155167Y818742D01*
Y818367D01*
G01Y818742D02*
X155042Y818992D01*
X154833Y819200D01*
X154583Y819283D01*
X154333Y819200D01*
X154125Y818992D01*
X154000Y818617D01*
X154042Y818242D01*
X154208Y817867D01*
G01X154000Y821550D02*
X154083Y821217D01*
X154292Y820967D01*
X154542Y820800D01*
X154875Y820675D01*
X155250Y820633D01*
X155625Y820675D01*
X155958Y820800D01*
X156208Y820967D01*
X156417Y821217D01*
X156500Y821550D01*
X156417Y821883D01*
X156208Y822133D01*
X155958Y822300D01*
X155625Y822425D01*
X155250Y822467D01*
X154875Y822425D01*
X154542Y822300D01*
X154292Y822133D01*
X154083Y821883D01*
X154000Y821550D01*
G01X156500Y824650D02*
X154000D01*
X154500Y824150D01*
G01X156500D02*
Y825150D01*
G01X154999Y832630D02*
X152499D01*
Y833671D01*
X152624Y834005D01*
X152791Y834213D01*
X153124Y834296D01*
X153457Y834213D01*
X153666Y833963D01*
X153791Y833671D01*
Y832630D01*
G01Y833671D02*
X154999Y834296D01*
G01X152916Y835771D02*
X152666Y836021D01*
X152541Y836313D01*
X152499Y836646D01*
X152582Y837063D01*
X152791Y837355D01*
X153041Y837438D01*
X153291Y837396D01*
X153499Y837230D01*
X153916Y836396D01*
X154207Y836021D01*
X154624Y835771D01*
X154999Y835688D01*
Y837438D01*
G01Y839580D02*
X154457Y839663D01*
X153999Y839788D01*
X153582Y839955D01*
X153124Y840163D01*
X152499Y840496D01*
Y838830D01*
G01X154999Y842680D02*
X154457Y842763D01*
X153999Y842888D01*
X153582Y843055D01*
X153124Y843263D01*
X152499Y843596D01*
Y841930D01*
G01X165499Y831413D02*
X169499D01*
Y838813D01*
G01X162999Y832567D02*
X160499D01*
Y833608D01*
X160624Y833942D01*
X160791Y834150D01*
X161124Y834233D01*
X161457Y834150D01*
X161666Y833900D01*
X161791Y833608D01*
Y832567D01*
G01Y833608D02*
X162999Y834233D01*
G01X160916Y835708D02*
X160666Y835958D01*
X160541Y836250D01*
X160499Y836583D01*
X160582Y837000D01*
X160791Y837292D01*
X161041Y837375D01*
X161291Y837333D01*
X161499Y837167D01*
X161916Y836333D01*
X162207Y835958D01*
X162624Y835708D01*
X162999Y835625D01*
Y837375D01*
G01Y839600D02*
X162957Y839892D01*
X162832Y840225D01*
X162624Y840433D01*
X162332Y840517D01*
X162041Y840433D01*
X161791Y840183D01*
X161666Y839808D01*
Y839392D01*
X161582Y839142D01*
X161374Y838933D01*
X161082Y838850D01*
X160791Y838975D01*
X160582Y839267D01*
X160499Y839600D01*
X160582Y839933D01*
X160791Y840225D01*
X161082Y840350D01*
X161374Y840267D01*
X161582Y840058D01*
X161666Y839808D01*
Y839392D01*
X161791Y839017D01*
X162041Y838767D01*
X162332Y838683D01*
X162624Y838767D01*
X162832Y838975D01*
X162957Y839308D01*
X162999Y839600D01*
G01X160499Y842700D02*
X160582Y842367D01*
X160791Y842117D01*
X161041Y841950D01*
X161374Y841825D01*
X161749Y841783D01*
X162124Y841825D01*
X162457Y841950D01*
X162707Y842117D01*
X162916Y842367D01*
X162999Y842700D01*
X162916Y843033D01*
X162707Y843283D01*
X162457Y843450D01*
X162124Y843575D01*
X161749Y843617D01*
X161374Y843575D01*
X161041Y843450D01*
X160791Y843283D01*
X160582Y843033D01*
X160499Y842700D01*
G01X158999Y832567D02*
X156499D01*
Y833608D01*
X156624Y833942D01*
X156791Y834150D01*
X157124Y834233D01*
X157457Y834150D01*
X157666Y833900D01*
X157791Y833608D01*
Y832567D01*
G01Y833608D02*
X158999Y834233D01*
G01X156916Y835708D02*
X156666Y835958D01*
X156541Y836250D01*
X156499Y836583D01*
X156582Y837000D01*
X156791Y837292D01*
X157041Y837375D01*
X157291Y837333D01*
X157499Y837167D01*
X157916Y836333D01*
X158207Y835958D01*
X158624Y835708D01*
X158999Y835625D01*
Y837375D01*
G01Y839600D02*
X158957Y839892D01*
X158832Y840225D01*
X158624Y840433D01*
X158332Y840517D01*
X158041Y840433D01*
X157791Y840183D01*
X157666Y839808D01*
Y839392D01*
X157582Y839142D01*
X157374Y838933D01*
X157082Y838850D01*
X156791Y838975D01*
X156582Y839267D01*
X156499Y839600D01*
X156582Y839933D01*
X156791Y840225D01*
X157082Y840350D01*
X157374Y840267D01*
X157582Y840058D01*
X157666Y839808D01*
Y839392D01*
X157791Y839017D01*
X158041Y838767D01*
X158332Y838683D01*
X158624Y838767D01*
X158832Y838975D01*
X158957Y839308D01*
X158999Y839600D01*
G01Y842700D02*
X156499D01*
X156999Y842200D01*
G01X158999D02*
Y843200D01*
G01X164999Y830313D02*
X174999D01*
G01X164999Y816913D02*
Y830313D01*
G01X174999Y816913D02*
X164999D01*
G01X157208Y852767D02*
X157083Y852517D01*
X157000Y852225D01*
Y851892D01*
X157125Y851517D01*
X157333Y851225D01*
X157583Y851017D01*
X158000Y850850D01*
X158375Y850808D01*
X158750Y850892D01*
X159000Y851017D01*
X159250Y851267D01*
X159417Y851558D01*
X159500Y851850D01*
Y852142D01*
X159417Y852433D01*
X159292Y852683D01*
X159125Y852892D01*
G01X159000Y854033D02*
X159292Y854283D01*
X159458Y854617D01*
X159500Y854992D01*
X159458Y855325D01*
X159250Y855658D01*
X159000Y855867D01*
X158750Y855908D01*
X158458Y855825D01*
X158250Y855533D01*
X158167Y855242D01*
Y854867D01*
G01Y855242D02*
X158042Y855492D01*
X157833Y855700D01*
X157583Y855783D01*
X157333Y855700D01*
X157125Y855492D01*
X157000Y855117D01*
X157042Y854742D01*
X157208Y854367D01*
G01X157000Y858050D02*
X157083Y857717D01*
X157292Y857467D01*
X157542Y857300D01*
X157875Y857175D01*
X158250Y857133D01*
X158625Y857175D01*
X158958Y857300D01*
X159208Y857467D01*
X159417Y857717D01*
X159500Y858050D01*
X159417Y858383D01*
X159208Y858633D01*
X158958Y858800D01*
X158625Y858925D01*
X158250Y858967D01*
X157875Y858925D01*
X157542Y858800D01*
X157292Y858633D01*
X157083Y858383D01*
X157000Y858050D01*
G01X159500Y861650D02*
X157000D01*
X158792Y860108D01*
Y862192D01*
G01X152708Y852767D02*
X152583Y852517D01*
X152500Y852225D01*
Y851892D01*
X152625Y851517D01*
X152833Y851225D01*
X153083Y851017D01*
X153500Y850850D01*
X153875Y850808D01*
X154250Y850892D01*
X154500Y851017D01*
X154750Y851267D01*
X154917Y851558D01*
X155000Y851850D01*
Y852142D01*
X154917Y852433D01*
X154792Y852683D01*
X154625Y852892D01*
G01X154500Y854033D02*
X154792Y854283D01*
X154958Y854617D01*
X155000Y854992D01*
X154958Y855325D01*
X154750Y855658D01*
X154500Y855867D01*
X154250Y855908D01*
X153958Y855825D01*
X153750Y855533D01*
X153667Y855242D01*
Y854867D01*
G01Y855242D02*
X153542Y855492D01*
X153333Y855700D01*
X153083Y855783D01*
X152833Y855700D01*
X152625Y855492D01*
X152500Y855117D01*
X152542Y854742D01*
X152708Y854367D01*
G01X152500Y858050D02*
X152583Y857717D01*
X152792Y857467D01*
X153042Y857300D01*
X153375Y857175D01*
X153750Y857133D01*
X154125Y857175D01*
X154458Y857300D01*
X154708Y857467D01*
X154917Y857717D01*
X155000Y858050D01*
X154917Y858383D01*
X154708Y858633D01*
X154458Y858800D01*
X154125Y858925D01*
X153750Y858967D01*
X153375Y858925D01*
X153042Y858800D01*
X152792Y858633D01*
X152583Y858383D01*
X152500Y858050D01*
G01X154625Y860233D02*
X154833Y860483D01*
X154958Y860775D01*
X155000Y861150D01*
X154917Y861525D01*
X154750Y861817D01*
X154458Y862025D01*
X154125Y862067D01*
X153792Y861983D01*
X153583Y861775D01*
X153417Y861483D01*
X153375Y861192D01*
X153417Y860900D01*
X153583Y860525D01*
X152500Y860650D01*
Y861775D01*
G01X148208Y852767D02*
X148083Y852517D01*
X148000Y852225D01*
Y851892D01*
X148125Y851517D01*
X148333Y851225D01*
X148583Y851017D01*
X149000Y850850D01*
X149375Y850808D01*
X149750Y850892D01*
X150000Y851017D01*
X150250Y851267D01*
X150417Y851558D01*
X150500Y851850D01*
Y852142D01*
X150417Y852433D01*
X150292Y852683D01*
X150125Y852892D01*
G01X150000Y854033D02*
X150292Y854283D01*
X150458Y854617D01*
X150500Y854992D01*
X150458Y855325D01*
X150250Y855658D01*
X150000Y855867D01*
X149750Y855908D01*
X149458Y855825D01*
X149250Y855533D01*
X149167Y855242D01*
Y854867D01*
G01Y855242D02*
X149042Y855492D01*
X148833Y855700D01*
X148583Y855783D01*
X148333Y855700D01*
X148125Y855492D01*
X148000Y855117D01*
X148042Y854742D01*
X148208Y854367D01*
G01X148000Y858050D02*
X148083Y857717D01*
X148292Y857467D01*
X148542Y857300D01*
X148875Y857175D01*
X149250Y857133D01*
X149625Y857175D01*
X149958Y857300D01*
X150208Y857467D01*
X150417Y857717D01*
X150500Y858050D01*
X150417Y858383D01*
X150208Y858633D01*
X149958Y858800D01*
X149625Y858925D01*
X149250Y858967D01*
X148875Y858925D01*
X148542Y858800D01*
X148292Y858633D01*
X148083Y858383D01*
X148000Y858050D01*
G01X149458Y860358D02*
X149167Y860650D01*
X149000Y860900D01*
X148917Y861233D01*
X149000Y861525D01*
X149167Y861733D01*
X149417Y861900D01*
X149708Y861942D01*
X149958Y861900D01*
X150208Y861733D01*
X150417Y861483D01*
X150500Y861192D01*
X150417Y860858D01*
X150167Y860567D01*
X149792Y860400D01*
X149375Y860358D01*
X148833Y860442D01*
X148542Y860567D01*
X148250Y860775D01*
X148042Y861067D01*
X148000Y861358D01*
X148083Y861650D01*
X148292Y861858D01*
G01X165999Y848313D02*
Y853813D01*
G01X173999Y848313D02*
X165999D01*
G01X147516Y872050D02*
Y874550D01*
X148557D01*
X148891Y874425D01*
X149099Y874258D01*
X149182Y873925D01*
X149099Y873592D01*
X148849Y873383D01*
X148557Y873258D01*
X147516D01*
G01X148557D02*
X149182Y872050D01*
G01X150657Y874133D02*
X150907Y874383D01*
X151199Y874508D01*
X151532Y874550D01*
X151949Y874467D01*
X152241Y874258D01*
X152324Y874008D01*
X152282Y873758D01*
X152116Y873550D01*
X151282Y873133D01*
X150907Y872842D01*
X150657Y872425D01*
X150574Y872050D01*
X152324D01*
G01X154466D02*
X154549Y872592D01*
X154674Y873050D01*
X154841Y873467D01*
X155049Y873925D01*
X155382Y874550D01*
X153716D01*
G01X156857Y873092D02*
X157149Y873383D01*
X157399Y873550D01*
X157732Y873633D01*
X158024Y873550D01*
X158232Y873383D01*
X158399Y873133D01*
X158441Y872842D01*
X158399Y872592D01*
X158232Y872342D01*
X157982Y872133D01*
X157691Y872050D01*
X157357Y872133D01*
X157066Y872383D01*
X156899Y872758D01*
X156857Y873175D01*
X156941Y873717D01*
X157066Y874008D01*
X157274Y874300D01*
X157566Y874508D01*
X157857Y874550D01*
X158149Y874467D01*
X158357Y874258D01*
G01X160499Y866613D02*
X186499D01*
G01X160499Y879613D02*
Y866613D01*
G01X165999Y865913D02*
X173999D01*
G01X165999Y860413D02*
Y865913D01*
G01X152207Y886817D02*
X152082Y886567D01*
X151999Y886275D01*
Y885942D01*
X152124Y885567D01*
X152332Y885275D01*
X152582Y885067D01*
X152999Y884900D01*
X153374Y884858D01*
X153749Y884942D01*
X153999Y885067D01*
X154249Y885317D01*
X154416Y885608D01*
X154499Y885900D01*
Y886192D01*
X154416Y886483D01*
X154291Y886733D01*
X154124Y886942D01*
G01X152416Y888208D02*
X152166Y888458D01*
X152041Y888750D01*
X151999Y889083D01*
X152082Y889500D01*
X152291Y889792D01*
X152541Y889875D01*
X152791Y889833D01*
X152999Y889667D01*
X153416Y888833D01*
X153707Y888458D01*
X154124Y888208D01*
X154499Y888125D01*
Y889875D01*
G01X154207Y891392D02*
X154416Y891683D01*
X154499Y892017D01*
X154416Y892350D01*
X154166Y892642D01*
X153791Y892850D01*
X153416Y892933D01*
X152957D01*
X152582Y892850D01*
X152249Y892642D01*
X152082Y892392D01*
X151999Y892100D01*
X152082Y891767D01*
X152249Y891517D01*
X152499Y891350D01*
X152832Y891267D01*
X153124Y891350D01*
X153416Y891558D01*
X153582Y891808D01*
X153624Y892100D01*
X153541Y892433D01*
X153332Y892683D01*
X152957Y892933D01*
G01X154499Y895200D02*
X154457Y895492D01*
X154332Y895825D01*
X154124Y896033D01*
X153832Y896117D01*
X153541Y896033D01*
X153291Y895783D01*
X153166Y895408D01*
Y894992D01*
X153082Y894742D01*
X152874Y894533D01*
X152582Y894450D01*
X152291Y894575D01*
X152082Y894867D01*
X151999Y895200D01*
X152082Y895533D01*
X152291Y895825D01*
X152582Y895950D01*
X152874Y895867D01*
X153082Y895658D01*
X153166Y895408D01*
Y894992D01*
X153291Y894617D01*
X153541Y894367D01*
X153832Y894283D01*
X154124Y894367D01*
X154332Y894575D01*
X154457Y894908D01*
X154499Y895200D01*
G01X186499Y879613D02*
X160499D01*
G01X156208Y886767D02*
X156083Y886517D01*
X156000Y886225D01*
Y885892D01*
X156125Y885517D01*
X156333Y885225D01*
X156583Y885017D01*
X157000Y884850D01*
X157375Y884808D01*
X157750Y884892D01*
X158000Y885017D01*
X158250Y885267D01*
X158417Y885558D01*
X158500Y885850D01*
Y886142D01*
X158417Y886433D01*
X158292Y886683D01*
X158125Y886892D01*
G01X156417Y888158D02*
X156167Y888408D01*
X156042Y888700D01*
X156000Y889033D01*
X156083Y889450D01*
X156292Y889742D01*
X156542Y889825D01*
X156792Y889783D01*
X157000Y889617D01*
X157417Y888783D01*
X157708Y888408D01*
X158125Y888158D01*
X158500Y888075D01*
Y889825D01*
G01X158208Y891342D02*
X158417Y891633D01*
X158500Y891967D01*
X158417Y892300D01*
X158167Y892592D01*
X157792Y892800D01*
X157417Y892883D01*
X156958D01*
X156583Y892800D01*
X156250Y892592D01*
X156083Y892342D01*
X156000Y892050D01*
X156083Y891717D01*
X156250Y891467D01*
X156500Y891300D01*
X156833Y891217D01*
X157125Y891300D01*
X157417Y891508D01*
X157583Y891758D01*
X157625Y892050D01*
X157542Y892383D01*
X157333Y892633D01*
X156958Y892883D01*
G01X158208Y894442D02*
X158417Y894733D01*
X158500Y895067D01*
X158417Y895400D01*
X158167Y895692D01*
X157792Y895900D01*
X157417Y895983D01*
X156958D01*
X156583Y895900D01*
X156250Y895692D01*
X156083Y895442D01*
X156000Y895150D01*
X156083Y894817D01*
X156250Y894567D01*
X156500Y894400D01*
X156833Y894317D01*
X157125Y894400D01*
X157417Y894608D01*
X157583Y894858D01*
X157625Y895150D01*
X157542Y895483D01*
X157333Y895733D01*
X156958Y895983D01*
G01X165499Y893913D02*
Y899413D01*
G01Y881813D02*
Y887313D01*
G01X173499Y881813D02*
X165499D01*
G01X147516Y905550D02*
Y908050D01*
X148557D01*
X148891Y907925D01*
X149099Y907758D01*
X149182Y907425D01*
X149099Y907092D01*
X148849Y906883D01*
X148557Y906758D01*
X147516D01*
G01X148557D02*
X149182Y905550D01*
G01X150657Y907633D02*
X150907Y907883D01*
X151199Y908008D01*
X151532Y908050D01*
X151949Y907967D01*
X152241Y907758D01*
X152324Y907508D01*
X152282Y907258D01*
X152116Y907050D01*
X151282Y906633D01*
X150907Y906342D01*
X150657Y905925D01*
X150574Y905550D01*
X152324D01*
G01X154466D02*
X154549Y906092D01*
X154674Y906550D01*
X154841Y906967D01*
X155049Y907425D01*
X155382Y908050D01*
X153716D01*
G01X156732Y906050D02*
X156982Y905758D01*
X157316Y905592D01*
X157691Y905550D01*
X158024Y905592D01*
X158357Y905800D01*
X158566Y906050D01*
X158607Y906300D01*
X158524Y906592D01*
X158232Y906800D01*
X157941Y906883D01*
X157566D01*
G01X157941D02*
X158191Y907008D01*
X158399Y907217D01*
X158482Y907467D01*
X158399Y907717D01*
X158191Y907925D01*
X157816Y908050D01*
X157441Y908008D01*
X157066Y907842D01*
G01X160499Y900113D02*
X186499D01*
G01X160499Y913113D02*
Y900113D01*
G01X186499Y913113D02*
X160499D01*
G01X165499Y899413D02*
X173499D01*
G01X148208Y925267D02*
X148083Y925017D01*
X148000Y924725D01*
Y924392D01*
X148125Y924017D01*
X148333Y923725D01*
X148583Y923517D01*
X149000Y923350D01*
X149375Y923308D01*
X149750Y923392D01*
X150000Y923517D01*
X150250Y923767D01*
X150417Y924058D01*
X150500Y924350D01*
Y924642D01*
X150417Y924933D01*
X150292Y925183D01*
X150125Y925392D01*
G01X150000Y926533D02*
X150292Y926783D01*
X150458Y927117D01*
X150500Y927492D01*
X150458Y927825D01*
X150250Y928158D01*
X150000Y928367D01*
X149750Y928408D01*
X149458Y928325D01*
X149250Y928033D01*
X149167Y927742D01*
Y927367D01*
G01Y927742D02*
X149042Y927992D01*
X148833Y928200D01*
X148583Y928283D01*
X148333Y928200D01*
X148125Y927992D01*
X148000Y927617D01*
X148042Y927242D01*
X148208Y926867D01*
G01X148000Y930550D02*
X148083Y930217D01*
X148292Y929967D01*
X148542Y929800D01*
X148875Y929675D01*
X149250Y929633D01*
X149625Y929675D01*
X149958Y929800D01*
X150208Y929967D01*
X150417Y930217D01*
X150500Y930550D01*
X150417Y930883D01*
X150208Y931133D01*
X149958Y931300D01*
X149625Y931425D01*
X149250Y931467D01*
X148875Y931425D01*
X148542Y931300D01*
X148292Y931133D01*
X148083Y930883D01*
X148000Y930550D01*
G01X150000Y932733D02*
X150292Y932983D01*
X150458Y933317D01*
X150500Y933692D01*
X150458Y934025D01*
X150250Y934358D01*
X150000Y934567D01*
X149750Y934608D01*
X149458Y934525D01*
X149250Y934233D01*
X149167Y933942D01*
Y933567D01*
G01Y933942D02*
X149042Y934192D01*
X148833Y934400D01*
X148583Y934483D01*
X148333Y934400D01*
X148125Y934192D01*
X148000Y933817D01*
X148042Y933442D01*
X148208Y933067D01*
G01X158500Y923517D02*
X156000D01*
Y924558D01*
X156125Y924892D01*
X156292Y925100D01*
X156625Y925183D01*
X156958Y925100D01*
X157167Y924850D01*
X157292Y924558D01*
Y923517D01*
G01Y924558D02*
X158500Y925183D01*
G01X156417Y926658D02*
X156167Y926908D01*
X156042Y927200D01*
X156000Y927533D01*
X156083Y927950D01*
X156292Y928242D01*
X156542Y928325D01*
X156792Y928283D01*
X157000Y928117D01*
X157417Y927283D01*
X157708Y926908D01*
X158125Y926658D01*
X158500Y926575D01*
Y928325D01*
G01Y930467D02*
X157958Y930550D01*
X157500Y930675D01*
X157083Y930842D01*
X156625Y931050D01*
X156000Y931383D01*
Y929717D01*
G01X158500Y934150D02*
X156000D01*
X157792Y932608D01*
Y934692D01*
G01X162500Y923517D02*
X160000D01*
Y924558D01*
X160125Y924892D01*
X160292Y925100D01*
X160625Y925183D01*
X160958Y925100D01*
X161167Y924850D01*
X161292Y924558D01*
Y923517D01*
G01Y924558D02*
X162500Y925183D01*
G01Y927950D02*
X160000D01*
X161792Y926408D01*
Y928492D01*
G01X160000Y930550D02*
X160083Y930217D01*
X160292Y929967D01*
X160542Y929800D01*
X160875Y929675D01*
X161250Y929633D01*
X161625Y929675D01*
X161958Y929800D01*
X162208Y929967D01*
X162417Y930217D01*
X162500Y930550D01*
X162417Y930883D01*
X162208Y931133D01*
X161958Y931300D01*
X161625Y931425D01*
X161250Y931467D01*
X160875Y931425D01*
X160542Y931300D01*
X160292Y931133D01*
X160083Y930883D01*
X160000Y930550D01*
G01Y933650D02*
X160083Y933317D01*
X160292Y933067D01*
X160542Y932900D01*
X160875Y932775D01*
X161250Y932733D01*
X161625Y932775D01*
X161958Y932900D01*
X162208Y933067D01*
X162417Y933317D01*
X162500Y933650D01*
X162417Y933983D01*
X162208Y934233D01*
X161958Y934400D01*
X161625Y934525D01*
X161250Y934567D01*
X160875Y934525D01*
X160542Y934400D01*
X160292Y934233D01*
X160083Y933983D01*
X160000Y933650D01*
G01X154500Y923517D02*
X152000D01*
Y924558D01*
X152125Y924892D01*
X152292Y925100D01*
X152625Y925183D01*
X152958Y925100D01*
X153167Y924850D01*
X153292Y924558D01*
Y923517D01*
G01Y924558D02*
X154500Y925183D01*
G01X152417Y926658D02*
X152167Y926908D01*
X152042Y927200D01*
X152000Y927533D01*
X152083Y927950D01*
X152292Y928242D01*
X152542Y928325D01*
X152792Y928283D01*
X153000Y928117D01*
X153417Y927283D01*
X153708Y926908D01*
X154125Y926658D01*
X154500Y926575D01*
Y928325D01*
G01Y930467D02*
X153958Y930550D01*
X153500Y930675D01*
X153083Y930842D01*
X152625Y931050D01*
X152000Y931383D01*
Y929717D01*
G01X154208Y932942D02*
X154417Y933233D01*
X154500Y933567D01*
X154417Y933900D01*
X154167Y934192D01*
X153792Y934400D01*
X153417Y934483D01*
X152958D01*
X152583Y934400D01*
X152250Y934192D01*
X152083Y933942D01*
X152000Y933650D01*
X152083Y933317D01*
X152250Y933067D01*
X152500Y932900D01*
X152833Y932817D01*
X153125Y932900D01*
X153417Y933108D01*
X153583Y933358D01*
X153625Y933650D01*
X153542Y933983D01*
X153333Y934233D01*
X152958Y934483D01*
G01X164287Y959310D02*
Y961810D01*
X165328D01*
X165662Y961685D01*
X165870Y961518D01*
X165953Y961185D01*
X165870Y960852D01*
X165620Y960643D01*
X165328Y960518D01*
X164287D01*
G01X165328D02*
X165953Y959310D01*
G01X168220D02*
Y961810D01*
X167720Y961310D01*
G01Y959310D02*
X168720D01*
G01X170612Y959602D02*
X170903Y959393D01*
X171237Y959310D01*
X171570Y959393D01*
X171862Y959643D01*
X172070Y960018D01*
X172153Y960393D01*
Y960852D01*
X172070Y961227D01*
X171862Y961560D01*
X171612Y961727D01*
X171320Y961810D01*
X170987Y961727D01*
X170737Y961560D01*
X170570Y961310D01*
X170487Y960977D01*
X170570Y960685D01*
X170778Y960393D01*
X171028Y960227D01*
X171320Y960185D01*
X171653Y960268D01*
X171903Y960477D01*
X172153Y960852D01*
G01X174420Y959310D02*
X174712Y959352D01*
X175045Y959477D01*
X175253Y959685D01*
X175337Y959977D01*
X175253Y960268D01*
X175003Y960518D01*
X174628Y960643D01*
X174212D01*
X173962Y960727D01*
X173753Y960935D01*
X173670Y961227D01*
X173795Y961518D01*
X174087Y961727D01*
X174420Y961810D01*
X174753Y961727D01*
X175045Y961518D01*
X175170Y961227D01*
X175087Y960935D01*
X174878Y960727D01*
X174628Y960643D01*
X174212D01*
X173837Y960518D01*
X173587Y960268D01*
X173503Y959977D01*
X173587Y959685D01*
X173795Y959477D01*
X174128Y959352D01*
X174420Y959310D01*
G01X164287Y955310D02*
Y957810D01*
X165328D01*
X165662Y957685D01*
X165870Y957518D01*
X165953Y957185D01*
X165870Y956852D01*
X165620Y956643D01*
X165328Y956518D01*
X164287D01*
G01X165328D02*
X165953Y955310D01*
G01X167428Y957393D02*
X167678Y957643D01*
X167970Y957768D01*
X168303Y957810D01*
X168720Y957727D01*
X169012Y957518D01*
X169095Y957268D01*
X169053Y957018D01*
X168887Y956810D01*
X168053Y956393D01*
X167678Y956102D01*
X167428Y955685D01*
X167345Y955310D01*
X169095D01*
G01X171320Y957810D02*
X170987Y957727D01*
X170737Y957518D01*
X170570Y957268D01*
X170445Y956935D01*
X170403Y956560D01*
X170445Y956185D01*
X170570Y955852D01*
X170737Y955602D01*
X170987Y955393D01*
X171320Y955310D01*
X171653Y955393D01*
X171903Y955602D01*
X172070Y955852D01*
X172195Y956185D01*
X172237Y956560D01*
X172195Y956935D01*
X172070Y957268D01*
X171903Y957518D01*
X171653Y957727D01*
X171320Y957810D01*
G01X174420D02*
X174087Y957727D01*
X173837Y957518D01*
X173670Y957268D01*
X173545Y956935D01*
X173503Y956560D01*
X173545Y956185D01*
X173670Y955852D01*
X173837Y955602D01*
X174087Y955393D01*
X174420Y955310D01*
X174753Y955393D01*
X175003Y955602D01*
X175170Y955852D01*
X175295Y956185D01*
X175337Y956560D01*
X175295Y956935D01*
X175170Y957268D01*
X175003Y957518D01*
X174753Y957727D01*
X174420Y957810D01*
G01X164537Y950310D02*
Y952810D01*
X165578D01*
X165912Y952685D01*
X166120Y952518D01*
X166203Y952185D01*
X166120Y951852D01*
X165870Y951643D01*
X165578Y951518D01*
X164537D01*
G01X165578D02*
X166203Y950310D01*
G01X167678Y952393D02*
X167928Y952643D01*
X168220Y952768D01*
X168553Y952810D01*
X168970Y952727D01*
X169262Y952518D01*
X169345Y952268D01*
X169303Y952018D01*
X169137Y951810D01*
X168303Y951393D01*
X167928Y951102D01*
X167678Y950685D01*
X167595Y950310D01*
X169345D01*
G01X171570Y952810D02*
X171237Y952727D01*
X170987Y952518D01*
X170820Y952268D01*
X170695Y951935D01*
X170653Y951560D01*
X170695Y951185D01*
X170820Y950852D01*
X170987Y950602D01*
X171237Y950393D01*
X171570Y950310D01*
X171903Y950393D01*
X172153Y950602D01*
X172320Y950852D01*
X172445Y951185D01*
X172487Y951560D01*
X172445Y951935D01*
X172320Y952268D01*
X172153Y952518D01*
X171903Y952727D01*
X171570Y952810D01*
G01X173878Y952393D02*
X174128Y952643D01*
X174420Y952768D01*
X174753Y952810D01*
X175170Y952727D01*
X175462Y952518D01*
X175545Y952268D01*
X175503Y952018D01*
X175337Y951810D01*
X174503Y951393D01*
X174128Y951102D01*
X173878Y950685D01*
X173795Y950310D01*
X175545D01*
G01X161517Y981563D02*
Y979063D01*
X163183D01*
G01X166283D02*
X164617D01*
Y981563D01*
X166283D01*
G01X165617Y980355D02*
X164617D01*
G01X167633Y979063D02*
Y981563D01*
X168467D01*
X168800Y981438D01*
X169050Y981271D01*
X169258Y981021D01*
X169425Y980730D01*
X169467Y980313D01*
X169425Y979896D01*
X169258Y979605D01*
X169050Y979355D01*
X168800Y979188D01*
X168467Y979063D01*
X167633D01*
G01X171650D02*
X171942Y979105D01*
X172275Y979230D01*
X172483Y979438D01*
X172567Y979730D01*
X172483Y980021D01*
X172233Y980271D01*
X171858Y980396D01*
X171442D01*
X171192Y980480D01*
X170983Y980688D01*
X170900Y980980D01*
X171025Y981271D01*
X171317Y981480D01*
X171650Y981563D01*
X171983Y981480D01*
X172275Y981271D01*
X172400Y980980D01*
X172317Y980688D01*
X172108Y980480D01*
X171858Y980396D01*
X171442D01*
X171067Y980271D01*
X170817Y980021D01*
X170733Y979730D01*
X170817Y979438D01*
X171025Y979230D01*
X171358Y979105D01*
X171650Y979063D01*
G01X173023Y976871D02*
Y969271D01*
X161623D01*
Y976871D01*
X173023D01*
G01X152799Y977550D02*
Y973550D01*
X160199D01*
G01X152799D02*
Y969550D01*
X160199D01*
G01X156708Y1176267D02*
X156583Y1176017D01*
X156500Y1175725D01*
Y1175392D01*
X156625Y1175017D01*
X156833Y1174725D01*
X157083Y1174517D01*
X157500Y1174350D01*
X157875Y1174308D01*
X158250Y1174392D01*
X158500Y1174517D01*
X158750Y1174767D01*
X158917Y1175058D01*
X159000Y1175350D01*
Y1175642D01*
X158917Y1175933D01*
X158792Y1176183D01*
X158625Y1176392D01*
G01X156917Y1177658D02*
X156667Y1177908D01*
X156542Y1178200D01*
X156500Y1178533D01*
X156583Y1178950D01*
X156792Y1179242D01*
X157042Y1179325D01*
X157292Y1179283D01*
X157500Y1179117D01*
X157917Y1178283D01*
X158208Y1177908D01*
X158625Y1177658D01*
X159000Y1177575D01*
Y1179325D01*
G01X156917Y1180758D02*
X156667Y1181008D01*
X156542Y1181300D01*
X156500Y1181633D01*
X156583Y1182050D01*
X156792Y1182342D01*
X157042Y1182425D01*
X157292Y1182383D01*
X157500Y1182217D01*
X157917Y1181383D01*
X158208Y1181008D01*
X158625Y1180758D01*
X159000Y1180675D01*
Y1182425D01*
G01Y1184567D02*
X158458Y1184650D01*
X158000Y1184775D01*
X157583Y1184942D01*
X157125Y1185150D01*
X156500Y1185483D01*
Y1183817D01*
G01X152608Y1176167D02*
X152483Y1175917D01*
X152400Y1175625D01*
Y1175292D01*
X152525Y1174917D01*
X152733Y1174625D01*
X152983Y1174417D01*
X153400Y1174250D01*
X153775Y1174208D01*
X154150Y1174292D01*
X154400Y1174417D01*
X154650Y1174667D01*
X154817Y1174958D01*
X154900Y1175250D01*
Y1175542D01*
X154817Y1175833D01*
X154692Y1176083D01*
X154525Y1176292D01*
G01X152817Y1177558D02*
X152567Y1177808D01*
X152442Y1178100D01*
X152400Y1178433D01*
X152483Y1178850D01*
X152692Y1179142D01*
X152942Y1179225D01*
X153192Y1179183D01*
X153400Y1179017D01*
X153817Y1178183D01*
X154108Y1177808D01*
X154525Y1177558D01*
X154900Y1177475D01*
Y1179225D01*
G01X152817Y1180658D02*
X152567Y1180908D01*
X152442Y1181200D01*
X152400Y1181533D01*
X152483Y1181950D01*
X152692Y1182242D01*
X152942Y1182325D01*
X153192Y1182283D01*
X153400Y1182117D01*
X153817Y1181283D01*
X154108Y1180908D01*
X154525Y1180658D01*
X154900Y1180575D01*
Y1182325D01*
G01X154400Y1183633D02*
X154692Y1183883D01*
X154858Y1184217D01*
X154900Y1184592D01*
X154858Y1184925D01*
X154650Y1185258D01*
X154400Y1185467D01*
X154150Y1185508D01*
X153858Y1185425D01*
X153650Y1185133D01*
X153567Y1184842D01*
Y1184467D01*
G01Y1184842D02*
X153442Y1185092D01*
X153233Y1185300D01*
X152983Y1185383D01*
X152733Y1185300D01*
X152525Y1185092D01*
X152400Y1184717D01*
X152442Y1184342D01*
X152608Y1183967D01*
G01X148208Y1176267D02*
X148083Y1176017D01*
X148000Y1175725D01*
Y1175392D01*
X148125Y1175017D01*
X148333Y1174725D01*
X148583Y1174517D01*
X149000Y1174350D01*
X149375Y1174308D01*
X149750Y1174392D01*
X150000Y1174517D01*
X150250Y1174767D01*
X150417Y1175058D01*
X150500Y1175350D01*
Y1175642D01*
X150417Y1175933D01*
X150292Y1176183D01*
X150125Y1176392D01*
G01X148417Y1177658D02*
X148167Y1177908D01*
X148042Y1178200D01*
X148000Y1178533D01*
X148083Y1178950D01*
X148292Y1179242D01*
X148542Y1179325D01*
X148792Y1179283D01*
X149000Y1179117D01*
X149417Y1178283D01*
X149708Y1177908D01*
X150125Y1177658D01*
X150500Y1177575D01*
Y1179325D01*
G01X148417Y1180758D02*
X148167Y1181008D01*
X148042Y1181300D01*
X148000Y1181633D01*
X148083Y1182050D01*
X148292Y1182342D01*
X148542Y1182425D01*
X148792Y1182383D01*
X149000Y1182217D01*
X149417Y1181383D01*
X149708Y1181008D01*
X150125Y1180758D01*
X150500Y1180675D01*
Y1182425D01*
G01X149458Y1183858D02*
X149167Y1184150D01*
X149000Y1184400D01*
X148917Y1184733D01*
X149000Y1185025D01*
X149167Y1185233D01*
X149417Y1185400D01*
X149708Y1185442D01*
X149958Y1185400D01*
X150208Y1185233D01*
X150417Y1184983D01*
X150500Y1184692D01*
X150417Y1184358D01*
X150167Y1184067D01*
X149792Y1183900D01*
X149375Y1183858D01*
X148833Y1183942D01*
X148542Y1184067D01*
X148250Y1184275D01*
X148042Y1184567D01*
X148000Y1184858D01*
X148083Y1185150D01*
X148292Y1185358D01*
G01X165983Y1228000D02*
Y1226208D01*
X166150Y1225833D01*
X166483Y1225583D01*
X166900Y1225500D01*
X167317Y1225583D01*
X167650Y1225833D01*
X167817Y1226208D01*
Y1228000D01*
G01X169083Y1226000D02*
X169333Y1225708D01*
X169667Y1225542D01*
X170042Y1225500D01*
X170375Y1225542D01*
X170708Y1225750D01*
X170917Y1226000D01*
X170958Y1226250D01*
X170875Y1226542D01*
X170583Y1226750D01*
X170292Y1226833D01*
X169917D01*
G01X170292D02*
X170542Y1226958D01*
X170750Y1227167D01*
X170833Y1227417D01*
X170750Y1227667D01*
X170542Y1227875D01*
X170167Y1228000D01*
X169792Y1227958D01*
X169417Y1227792D01*
G01X172183Y1225875D02*
X172433Y1225667D01*
X172725Y1225542D01*
X173100Y1225500D01*
X173475Y1225583D01*
X173767Y1225750D01*
X173975Y1226042D01*
X174017Y1226375D01*
X173933Y1226708D01*
X173725Y1226917D01*
X173433Y1227083D01*
X173142Y1227125D01*
X172850Y1227083D01*
X172475Y1226917D01*
X172600Y1228000D01*
X173725D01*
G01X150499Y1234413D02*
X148499Y1232413D01*
X146499Y1234413D01*
G01X146800Y1259700D02*
X164400D01*
G01X146800Y1267700D02*
Y1259700D01*
G01X164400Y1267700D02*
X146800D01*
G01X164400Y1259700D02*
Y1267700D01*
G01X153299Y1289113D02*
X155399Y1287313D01*
X153299Y1285113D01*
G01X153199Y1281513D02*
X172399D01*
Y1292713D01*
X153199D01*
Y1281513D01*
X153599D01*
G01X148500Y1284517D02*
X146000D01*
Y1285558D01*
X146125Y1285892D01*
X146292Y1286100D01*
X146625Y1286183D01*
X146958Y1286100D01*
X147167Y1285850D01*
X147292Y1285558D01*
Y1284517D01*
G01Y1285558D02*
X148500Y1286183D01*
G01X148125Y1287533D02*
X148333Y1287783D01*
X148458Y1288075D01*
X148500Y1288450D01*
X148417Y1288825D01*
X148250Y1289117D01*
X147958Y1289325D01*
X147625Y1289367D01*
X147292Y1289283D01*
X147083Y1289075D01*
X146917Y1288783D01*
X146875Y1288492D01*
X146917Y1288200D01*
X147083Y1287825D01*
X146000Y1287950D01*
Y1289075D01*
G01X148000Y1290633D02*
X148292Y1290883D01*
X148458Y1291217D01*
X148500Y1291592D01*
X148458Y1291925D01*
X148250Y1292258D01*
X148000Y1292467D01*
X147750Y1292508D01*
X147458Y1292425D01*
X147250Y1292133D01*
X147167Y1291842D01*
Y1291467D01*
G01Y1291842D02*
X147042Y1292092D01*
X146833Y1292300D01*
X146583Y1292383D01*
X146333Y1292300D01*
X146125Y1292092D01*
X146000Y1291717D01*
X146042Y1291342D01*
X146208Y1290967D01*
G01X148500Y1295150D02*
X146000D01*
X147792Y1293608D01*
Y1295692D01*
G01X161708Y1311317D02*
X161583Y1311067D01*
X161500Y1310775D01*
Y1310442D01*
X161625Y1310067D01*
X161833Y1309775D01*
X162083Y1309567D01*
X162500Y1309400D01*
X162875Y1309358D01*
X163250Y1309442D01*
X163500Y1309567D01*
X163750Y1309817D01*
X163917Y1310108D01*
X164000Y1310400D01*
Y1310692D01*
X163917Y1310983D01*
X163792Y1311233D01*
X163625Y1311442D01*
G01X161917Y1312708D02*
X161667Y1312958D01*
X161542Y1313250D01*
X161500Y1313583D01*
X161583Y1314000D01*
X161792Y1314292D01*
X162042Y1314375D01*
X162292Y1314333D01*
X162500Y1314167D01*
X162917Y1313333D01*
X163208Y1312958D01*
X163625Y1312708D01*
X164000Y1312625D01*
Y1314375D01*
G01Y1316600D02*
X163958Y1316892D01*
X163833Y1317225D01*
X163625Y1317433D01*
X163333Y1317517D01*
X163042Y1317433D01*
X162792Y1317183D01*
X162667Y1316808D01*
Y1316392D01*
X162583Y1316142D01*
X162375Y1315933D01*
X162083Y1315850D01*
X161792Y1315975D01*
X161583Y1316267D01*
X161500Y1316600D01*
X161583Y1316933D01*
X161792Y1317225D01*
X162083Y1317350D01*
X162375Y1317267D01*
X162583Y1317058D01*
X162667Y1316808D01*
Y1316392D01*
X162792Y1316017D01*
X163042Y1315767D01*
X163333Y1315683D01*
X163625Y1315767D01*
X163833Y1315975D01*
X163958Y1316308D01*
X164000Y1316600D01*
G01X163500Y1318783D02*
X163792Y1319033D01*
X163958Y1319367D01*
X164000Y1319742D01*
X163958Y1320075D01*
X163750Y1320408D01*
X163500Y1320617D01*
X163250Y1320658D01*
X162958Y1320575D01*
X162750Y1320283D01*
X162667Y1319992D01*
Y1319617D01*
G01Y1319992D02*
X162542Y1320242D01*
X162333Y1320450D01*
X162083Y1320533D01*
X161833Y1320450D01*
X161625Y1320242D01*
X161500Y1319867D01*
X161542Y1319492D01*
X161708Y1319117D01*
G01X157708Y1311317D02*
X157583Y1311067D01*
X157500Y1310775D01*
Y1310442D01*
X157625Y1310067D01*
X157833Y1309775D01*
X158083Y1309567D01*
X158500Y1309400D01*
X158875Y1309358D01*
X159250Y1309442D01*
X159500Y1309567D01*
X159750Y1309817D01*
X159917Y1310108D01*
X160000Y1310400D01*
Y1310692D01*
X159917Y1310983D01*
X159792Y1311233D01*
X159625Y1311442D01*
G01X157917Y1312708D02*
X157667Y1312958D01*
X157542Y1313250D01*
X157500Y1313583D01*
X157583Y1314000D01*
X157792Y1314292D01*
X158042Y1314375D01*
X158292Y1314333D01*
X158500Y1314167D01*
X158917Y1313333D01*
X159208Y1312958D01*
X159625Y1312708D01*
X160000Y1312625D01*
Y1314375D01*
G01Y1316517D02*
X159458Y1316600D01*
X159000Y1316725D01*
X158583Y1316892D01*
X158125Y1317100D01*
X157500Y1317433D01*
Y1315767D01*
G01X160000Y1319617D02*
X159458Y1319700D01*
X159000Y1319825D01*
X158583Y1319992D01*
X158125Y1320200D01*
X157500Y1320533D01*
Y1318867D01*
G01X150400Y1321400D02*
Y1332800D01*
G01X153400Y1331500D02*
X153067Y1331542D01*
X152775Y1331708D01*
X152525Y1331958D01*
X152358Y1332250D01*
X152275Y1332583D01*
Y1332917D01*
X152358Y1333250D01*
X152525Y1333542D01*
X152775Y1333792D01*
X153067Y1333958D01*
X153400Y1334000D01*
X153733Y1333958D01*
X154025Y1333792D01*
X154275Y1333542D01*
X154442Y1333250D01*
X154525Y1332917D01*
Y1332583D01*
X154442Y1332250D01*
X154275Y1331958D01*
X154025Y1331708D01*
X153733Y1331542D01*
X153400Y1331500D01*
G01X153733Y1332167D02*
X154233Y1331500D01*
G01X155708Y1332542D02*
X156000Y1332833D01*
X156250Y1333000D01*
X156583Y1333083D01*
X156875Y1333000D01*
X157083Y1332833D01*
X157250Y1332583D01*
X157292Y1332292D01*
X157250Y1332042D01*
X157083Y1331792D01*
X156833Y1331583D01*
X156542Y1331500D01*
X156208Y1331583D01*
X155917Y1331833D01*
X155750Y1332208D01*
X155708Y1332625D01*
X155792Y1333167D01*
X155917Y1333458D01*
X156125Y1333750D01*
X156417Y1333958D01*
X156708Y1334000D01*
X157000Y1333917D01*
X157208Y1333708D01*
G01X159600Y1331500D02*
X159892Y1331542D01*
X160225Y1331667D01*
X160433Y1331875D01*
X160517Y1332167D01*
X160433Y1332458D01*
X160183Y1332708D01*
X159808Y1332833D01*
X159392D01*
X159142Y1332917D01*
X158933Y1333125D01*
X158850Y1333417D01*
X158975Y1333708D01*
X159267Y1333917D01*
X159600Y1334000D01*
X159933Y1333917D01*
X160225Y1333708D01*
X160350Y1333417D01*
X160267Y1333125D01*
X160058Y1332917D01*
X159808Y1332833D01*
X159392D01*
X159017Y1332708D01*
X158767Y1332458D01*
X158683Y1332167D01*
X158767Y1331875D01*
X158975Y1331667D01*
X159308Y1331542D01*
X159600Y1331500D01*
G01X159000Y1350400D02*
X158958Y1350067D01*
X158792Y1349775D01*
X158542Y1349525D01*
X158250Y1349358D01*
X157917Y1349275D01*
X157583D01*
X157250Y1349358D01*
X156958Y1349525D01*
X156708Y1349775D01*
X156542Y1350067D01*
X156500Y1350400D01*
X156542Y1350733D01*
X156708Y1351025D01*
X156958Y1351275D01*
X157250Y1351442D01*
X157583Y1351525D01*
X157917D01*
X158250Y1351442D01*
X158542Y1351275D01*
X158792Y1351025D01*
X158958Y1350733D01*
X159000Y1350400D01*
G01X158333Y1350733D02*
X159000Y1351233D01*
G01Y1354000D02*
X156500D01*
X158292Y1352458D01*
Y1354542D01*
G01X158625Y1355683D02*
X158833Y1355933D01*
X158958Y1356225D01*
X159000Y1356600D01*
X158917Y1356975D01*
X158750Y1357267D01*
X158458Y1357475D01*
X158125Y1357517D01*
X157792Y1357433D01*
X157583Y1357225D01*
X157417Y1356933D01*
X157375Y1356642D01*
X157417Y1356350D01*
X157583Y1355975D01*
X156500Y1356100D01*
Y1357225D01*
G01X157164Y1371777D02*
Y1369277D01*
X158830D01*
G01X161930D02*
X160264D01*
Y1371777D01*
X161930D01*
G01X161264Y1370569D02*
X160264D01*
G01X163280Y1369277D02*
Y1371777D01*
X164114D01*
X164447Y1371652D01*
X164697Y1371485D01*
X164905Y1371235D01*
X165072Y1370944D01*
X165114Y1370527D01*
X165072Y1370110D01*
X164905Y1369819D01*
X164697Y1369569D01*
X164447Y1369402D01*
X164114Y1369277D01*
X163280D01*
G01X167214D02*
X167297Y1369819D01*
X167422Y1370277D01*
X167589Y1370694D01*
X167797Y1371152D01*
X168130Y1371777D01*
X166464D01*
G01X173023Y1382383D02*
Y1374783D01*
X161623D01*
Y1382383D01*
X173023D01*
G01X156100Y1592500D02*
Y1574500D01*
G01X159917Y1603000D02*
Y1608000D01*
X163083D01*
G01X161917Y1605583D02*
X159917D01*
G01X165267Y1604000D02*
X165767Y1603417D01*
X166433Y1603083D01*
X167183Y1603000D01*
X167850Y1603083D01*
X168517Y1603500D01*
X168933Y1604000D01*
X169017Y1604500D01*
X168850Y1605083D01*
X168267Y1605500D01*
X167683Y1605667D01*
X166933D01*
G01X167683D02*
X168183Y1605917D01*
X168600Y1606333D01*
X168767Y1606833D01*
X168600Y1607333D01*
X168183Y1607750D01*
X167433Y1608000D01*
X166683Y1607917D01*
X165933Y1607583D01*
G01X172700Y1603000D02*
Y1608000D01*
X171700Y1607000D01*
G01Y1603000D02*
X173700D01*
G01X178300Y1602833D02*
X178133Y1602917D01*
Y1603083D01*
X178300Y1603167D01*
X178467Y1603083D01*
Y1602917D01*
X178300Y1602833D01*
G01Y1605083D02*
X178133Y1605167D01*
Y1605333D01*
X178300Y1605417D01*
X178467Y1605333D01*
Y1605167D01*
X178300Y1605083D01*
G01X182067Y1604000D02*
X182567Y1603417D01*
X183233Y1603083D01*
X183983Y1603000D01*
X184650Y1603083D01*
X185317Y1603500D01*
X185733Y1604000D01*
X185817Y1604500D01*
X185650Y1605083D01*
X185067Y1605500D01*
X184483Y1605667D01*
X183733D01*
G01X184483D02*
X184983Y1605917D01*
X185400Y1606333D01*
X185567Y1606833D01*
X185400Y1607333D01*
X184983Y1607750D01*
X184233Y1608000D01*
X183483Y1607917D01*
X182733Y1607583D01*
G01X187417Y1603000D02*
X189500Y1608000D01*
X191583Y1603000D01*
G01X190833Y1604750D02*
X188167D01*
G01X193600Y1602833D02*
X196600Y1608000D01*
G01X200700Y1603000D02*
Y1608000D01*
X199700Y1607000D01*
G01Y1603000D02*
X201700D01*
G01X204467Y1603750D02*
X204967Y1603333D01*
X205550Y1603083D01*
X206300Y1603000D01*
X207050Y1603167D01*
X207633Y1603500D01*
X208050Y1604083D01*
X208133Y1604750D01*
X207967Y1605417D01*
X207550Y1605833D01*
X206967Y1606167D01*
X206383Y1606250D01*
X205800Y1606167D01*
X205050Y1605833D01*
X205300Y1608000D01*
X207550D01*
G01X209817D02*
X211900Y1603000D01*
X213983Y1608000D01*
G01X162999Y1666887D02*
Y1628087D01*
G01X150600Y1679200D02*
X154600D01*
Y1686600D01*
G01X165608Y1662500D02*
Y1665000D01*
X167192D01*
G01X166608Y1663792D02*
X165608D01*
G01X168708Y1664583D02*
X168958Y1664833D01*
X169250Y1664958D01*
X169583Y1665000D01*
X170000Y1664917D01*
X170292Y1664708D01*
X170375Y1664458D01*
X170333Y1664208D01*
X170167Y1664000D01*
X169333Y1663583D01*
X168958Y1663292D01*
X168708Y1662875D01*
X168625Y1662500D01*
X170375D01*
G01X171808Y1664583D02*
X172058Y1664833D01*
X172350Y1664958D01*
X172683Y1665000D01*
X173100Y1664917D01*
X173392Y1664708D01*
X173475Y1664458D01*
X173433Y1664208D01*
X173267Y1664000D01*
X172433Y1663583D01*
X172058Y1663292D01*
X171808Y1662875D01*
X171725Y1662500D01*
X173475D01*
G01X158900Y1674500D02*
X158567Y1674542D01*
X158275Y1674708D01*
X158025Y1674958D01*
X157858Y1675250D01*
X157775Y1675583D01*
Y1675917D01*
X157858Y1676250D01*
X158025Y1676542D01*
X158275Y1676792D01*
X158567Y1676958D01*
X158900Y1677000D01*
X159233Y1676958D01*
X159525Y1676792D01*
X159775Y1676542D01*
X159942Y1676250D01*
X160025Y1675917D01*
Y1675583D01*
X159942Y1675250D01*
X159775Y1674958D01*
X159525Y1674708D01*
X159233Y1674542D01*
X158900Y1674500D01*
G01X159233Y1675167D02*
X159733Y1674500D01*
G01X161208Y1675542D02*
X161500Y1675833D01*
X161750Y1676000D01*
X162083Y1676083D01*
X162375Y1676000D01*
X162583Y1675833D01*
X162750Y1675583D01*
X162792Y1675292D01*
X162750Y1675042D01*
X162583Y1674792D01*
X162333Y1674583D01*
X162042Y1674500D01*
X161708Y1674583D01*
X161417Y1674833D01*
X161250Y1675208D01*
X161208Y1675625D01*
X161292Y1676167D01*
X161417Y1676458D01*
X161625Y1676750D01*
X161917Y1676958D01*
X162208Y1677000D01*
X162500Y1676917D01*
X162708Y1676708D01*
G01X165017Y1674500D02*
X165100Y1675042D01*
X165225Y1675500D01*
X165392Y1675917D01*
X165600Y1676375D01*
X165933Y1677000D01*
X164267D01*
G01X155200Y1692800D02*
Y1678800D01*
G01D02*
X168200D01*
G01X152000Y1689017D02*
X149500D01*
Y1690058D01*
X149625Y1690392D01*
X149792Y1690600D01*
X150125Y1690683D01*
X150458Y1690600D01*
X150667Y1690350D01*
X150792Y1690058D01*
Y1689017D01*
G01Y1690058D02*
X152000Y1690683D01*
G01X151500Y1692033D02*
X151792Y1692283D01*
X151958Y1692617D01*
X152000Y1692992D01*
X151958Y1693325D01*
X151750Y1693658D01*
X151500Y1693867D01*
X151250Y1693908D01*
X150958Y1693825D01*
X150750Y1693533D01*
X150667Y1693242D01*
Y1692867D01*
G01Y1693242D02*
X150542Y1693492D01*
X150333Y1693700D01*
X150083Y1693783D01*
X149833Y1693700D01*
X149625Y1693492D01*
X149500Y1693117D01*
X149542Y1692742D01*
X149708Y1692367D01*
G01X151708Y1695342D02*
X151917Y1695633D01*
X152000Y1695967D01*
X151917Y1696300D01*
X151667Y1696592D01*
X151292Y1696800D01*
X150917Y1696883D01*
X150458D01*
X150083Y1696800D01*
X149750Y1696592D01*
X149583Y1696342D01*
X149500Y1696050D01*
X149583Y1695717D01*
X149750Y1695467D01*
X150000Y1695300D01*
X150333Y1695217D01*
X150625Y1695300D01*
X150917Y1695508D01*
X151083Y1695758D01*
X151125Y1696050D01*
X151042Y1696383D01*
X150833Y1696633D01*
X150458Y1696883D01*
G01X150958Y1698358D02*
X150667Y1698650D01*
X150500Y1698900D01*
X150417Y1699233D01*
X150500Y1699525D01*
X150667Y1699733D01*
X150917Y1699900D01*
X151208Y1699942D01*
X151458Y1699900D01*
X151708Y1699733D01*
X151917Y1699483D01*
X152000Y1699192D01*
X151917Y1698858D01*
X151667Y1698567D01*
X151292Y1698400D01*
X150875Y1698358D01*
X150333Y1698442D01*
X150042Y1698567D01*
X149750Y1698775D01*
X149542Y1699067D01*
X149500Y1699358D01*
X149583Y1699650D01*
X149792Y1699858D01*
G01X168200Y1692800D02*
X155200D01*
G01X154299Y1712113D02*
X156399Y1710313D01*
X154299Y1708113D01*
G01X154199Y1704513D02*
X173399D01*
Y1715713D01*
X154199D01*
Y1704513D01*
X154599D01*
G01X148513Y1736182D02*
Y1738682D01*
X149554D01*
X149888Y1738557D01*
X150096Y1738390D01*
X150179Y1738057D01*
X150096Y1737724D01*
X149846Y1737515D01*
X149554Y1737390D01*
X148513D01*
G01X149554D02*
X150179Y1736182D01*
G01X151654Y1738265D02*
X151904Y1738515D01*
X152196Y1738640D01*
X152529Y1738682D01*
X152946Y1738599D01*
X153238Y1738390D01*
X153321Y1738140D01*
X153279Y1737890D01*
X153113Y1737682D01*
X152279Y1737265D01*
X151904Y1736974D01*
X151654Y1736557D01*
X151571Y1736182D01*
X153321D01*
G01X156046D02*
Y1738682D01*
X154504Y1736890D01*
X156588D01*
G01X158563Y1736182D02*
X158646Y1736724D01*
X158771Y1737182D01*
X158938Y1737599D01*
X159146Y1738057D01*
X159479Y1738682D01*
X157813D01*
G01X148513Y1732182D02*
Y1734682D01*
X149554D01*
X149888Y1734557D01*
X150096Y1734390D01*
X150179Y1734057D01*
X150096Y1733724D01*
X149846Y1733515D01*
X149554Y1733390D01*
X148513D01*
G01X149554D02*
X150179Y1732182D01*
G01X151654Y1734265D02*
X151904Y1734515D01*
X152196Y1734640D01*
X152529Y1734682D01*
X152946Y1734599D01*
X153238Y1734390D01*
X153321Y1734140D01*
X153279Y1733890D01*
X153113Y1733682D01*
X152279Y1733265D01*
X151904Y1732974D01*
X151654Y1732557D01*
X151571Y1732182D01*
X153321D01*
G01X154629Y1732557D02*
X154879Y1732349D01*
X155171Y1732224D01*
X155546Y1732182D01*
X155921Y1732265D01*
X156213Y1732432D01*
X156421Y1732724D01*
X156463Y1733057D01*
X156379Y1733390D01*
X156171Y1733599D01*
X155879Y1733765D01*
X155588Y1733807D01*
X155296Y1733765D01*
X154921Y1733599D01*
X155046Y1734682D01*
X156171D01*
G01X157729Y1732682D02*
X157979Y1732390D01*
X158313Y1732224D01*
X158688Y1732182D01*
X159021Y1732224D01*
X159354Y1732432D01*
X159563Y1732682D01*
X159604Y1732932D01*
X159521Y1733224D01*
X159229Y1733432D01*
X158938Y1733515D01*
X158563D01*
G01X158938D02*
X159188Y1733640D01*
X159396Y1733849D01*
X159479Y1734099D01*
X159396Y1734349D01*
X159188Y1734557D01*
X158813Y1734682D01*
X158438Y1734640D01*
X158063Y1734474D01*
G01X161741Y1770698D02*
Y1768198D01*
X163407D01*
G01X166507D02*
X164841D01*
Y1770698D01*
X166507D01*
G01X165841Y1769490D02*
X164841D01*
G01X167857Y1768198D02*
Y1770698D01*
X168691D01*
X169024Y1770573D01*
X169274Y1770406D01*
X169482Y1770156D01*
X169649Y1769865D01*
X169691Y1769448D01*
X169649Y1769031D01*
X169482Y1768740D01*
X169274Y1768490D01*
X169024Y1768323D01*
X168691Y1768198D01*
X167857D01*
G01X171082Y1769240D02*
X171374Y1769531D01*
X171624Y1769698D01*
X171957Y1769781D01*
X172249Y1769698D01*
X172457Y1769531D01*
X172624Y1769281D01*
X172666Y1768990D01*
X172624Y1768740D01*
X172457Y1768490D01*
X172207Y1768281D01*
X171916Y1768198D01*
X171582Y1768281D01*
X171291Y1768531D01*
X171124Y1768906D01*
X171082Y1769323D01*
X171166Y1769865D01*
X171291Y1770156D01*
X171499Y1770448D01*
X171791Y1770656D01*
X172082Y1770698D01*
X172374Y1770615D01*
X172582Y1770406D01*
G01X173023Y1787894D02*
Y1780294D01*
X161623D01*
Y1787894D01*
X173023D01*
G01X152771Y1788909D02*
Y1784909D01*
X160171D01*
G01X152771D02*
Y1780909D01*
X160171D01*
G01X180499Y34567D02*
X177999D01*
Y35567D01*
X178124Y35900D01*
X178416Y36150D01*
X178749Y36233D01*
X179082Y36150D01*
X179332Y35942D01*
X179457Y35567D01*
Y34567D01*
G01X178207Y39417D02*
X178082Y39167D01*
X177999Y38875D01*
Y38542D01*
X178124Y38167D01*
X178332Y37875D01*
X178582Y37667D01*
X178999Y37500D01*
X179374Y37458D01*
X179749Y37542D01*
X179999Y37667D01*
X180249Y37917D01*
X180416Y38208D01*
X180499Y38500D01*
Y38792D01*
X180416Y39083D01*
X180291Y39333D01*
X180124Y39542D01*
G01X180499Y41600D02*
X177999D01*
X178499Y41100D01*
G01X180499D02*
Y42100D01*
G01X180124Y43783D02*
X180332Y44033D01*
X180457Y44325D01*
X180499Y44700D01*
X180416Y45075D01*
X180249Y45367D01*
X179957Y45575D01*
X179624Y45617D01*
X179291Y45533D01*
X179082Y45325D01*
X178916Y45033D01*
X178874Y44742D01*
X178916Y44450D01*
X179082Y44075D01*
X177999Y44200D01*
Y45325D01*
G01X183999Y34567D02*
X181499D01*
Y35567D01*
X181624Y35900D01*
X181916Y36150D01*
X182249Y36233D01*
X182582Y36150D01*
X182832Y35942D01*
X182957Y35567D01*
Y34567D01*
G01X181707Y39417D02*
X181582Y39167D01*
X181499Y38875D01*
Y38542D01*
X181624Y38167D01*
X181832Y37875D01*
X182082Y37667D01*
X182499Y37500D01*
X182874Y37458D01*
X183249Y37542D01*
X183499Y37667D01*
X183749Y37917D01*
X183916Y38208D01*
X183999Y38500D01*
Y38792D01*
X183916Y39083D01*
X183791Y39333D01*
X183624Y39542D01*
G01X181916Y40808D02*
X181666Y41058D01*
X181541Y41350D01*
X181499Y41683D01*
X181582Y42100D01*
X181791Y42392D01*
X182041Y42475D01*
X182291Y42433D01*
X182499Y42267D01*
X182916Y41433D01*
X183207Y41058D01*
X183624Y40808D01*
X183999Y40725D01*
Y42475D01*
G01X181499Y44700D02*
X181582Y44367D01*
X181791Y44117D01*
X182041Y43950D01*
X182374Y43825D01*
X182749Y43783D01*
X183124Y43825D01*
X183457Y43950D01*
X183707Y44117D01*
X183916Y44367D01*
X183999Y44700D01*
X183916Y45033D01*
X183707Y45283D01*
X183457Y45450D01*
X183124Y45575D01*
X182749Y45617D01*
X182374Y45575D01*
X182041Y45450D01*
X181791Y45283D01*
X181582Y45033D01*
X181499Y44700D01*
G01X175143Y48428D02*
Y50928D01*
X176143D01*
X176476Y50803D01*
X176726Y50511D01*
X176809Y50178D01*
X176726Y49845D01*
X176518Y49595D01*
X176143Y49470D01*
X175143D01*
G01X178243Y48428D02*
Y50928D01*
X179284D01*
X179618Y50803D01*
X179826Y50636D01*
X179909Y50303D01*
X179826Y49970D01*
X179576Y49761D01*
X179284Y49636D01*
X178243D01*
G01X179284D02*
X179909Y48428D01*
G01X181384Y50511D02*
X181634Y50761D01*
X181926Y50886D01*
X182259Y50928D01*
X182676Y50845D01*
X182968Y50636D01*
X183051Y50386D01*
X183009Y50136D01*
X182843Y49928D01*
X182009Y49511D01*
X181634Y49220D01*
X181384Y48803D01*
X181301Y48428D01*
X183051D01*
G01X185276Y50928D02*
X184943Y50845D01*
X184693Y50636D01*
X184526Y50386D01*
X184401Y50053D01*
X184359Y49678D01*
X184401Y49303D01*
X184526Y48970D01*
X184693Y48720D01*
X184943Y48511D01*
X185276Y48428D01*
X185609Y48511D01*
X185859Y48720D01*
X186026Y48970D01*
X186151Y49303D01*
X186193Y49678D01*
X186151Y50053D01*
X186026Y50386D01*
X185859Y50636D01*
X185609Y50845D01*
X185276Y50928D01*
G01X175189Y52572D02*
Y55072D01*
X176189D01*
X176522Y54947D01*
X176772Y54655D01*
X176855Y54322D01*
X176772Y53989D01*
X176564Y53739D01*
X176189Y53614D01*
X175189D01*
G01X178289Y52572D02*
Y55072D01*
X179330D01*
X179664Y54947D01*
X179872Y54780D01*
X179955Y54447D01*
X179872Y54114D01*
X179622Y53905D01*
X179330Y53780D01*
X178289D01*
G01X179330D02*
X179955Y52572D01*
G01X181305Y53072D02*
X181555Y52780D01*
X181889Y52614D01*
X182264Y52572D01*
X182597Y52614D01*
X182930Y52822D01*
X183139Y53072D01*
X183180Y53322D01*
X183097Y53614D01*
X182805Y53822D01*
X182514Y53905D01*
X182139D01*
G01X182514D02*
X182764Y54030D01*
X182972Y54239D01*
X183055Y54489D01*
X182972Y54739D01*
X182764Y54947D01*
X182389Y55072D01*
X182014Y55030D01*
X181639Y54864D01*
G01X184530Y54655D02*
X184780Y54905D01*
X185072Y55030D01*
X185405Y55072D01*
X185822Y54989D01*
X186114Y54780D01*
X186197Y54530D01*
X186155Y54280D01*
X185989Y54072D01*
X185155Y53655D01*
X184780Y53364D01*
X184530Y52947D01*
X184447Y52572D01*
X186197D01*
G01X176499Y34567D02*
X173999D01*
Y35567D01*
X174124Y35900D01*
X174416Y36150D01*
X174749Y36233D01*
X175082Y36150D01*
X175332Y35942D01*
X175457Y35567D01*
Y34567D01*
G01X176499Y37667D02*
X173999D01*
Y38708D01*
X174124Y39042D01*
X174291Y39250D01*
X174624Y39333D01*
X174957Y39250D01*
X175166Y39000D01*
X175291Y38708D01*
Y37667D01*
G01Y38708D02*
X176499Y39333D01*
G01X176124Y40683D02*
X176332Y40933D01*
X176457Y41225D01*
X176499Y41600D01*
X176416Y41975D01*
X176249Y42267D01*
X175957Y42475D01*
X175624Y42517D01*
X175291Y42433D01*
X175082Y42225D01*
X174916Y41933D01*
X174874Y41642D01*
X174916Y41350D01*
X175082Y40975D01*
X173999Y41100D01*
Y42225D01*
G01Y44700D02*
X174082Y44367D01*
X174291Y44117D01*
X174541Y43950D01*
X174874Y43825D01*
X175249Y43783D01*
X175624Y43825D01*
X175957Y43950D01*
X176207Y44117D01*
X176416Y44367D01*
X176499Y44700D01*
X176416Y45033D01*
X176207Y45283D01*
X175957Y45450D01*
X175624Y45575D01*
X175249Y45617D01*
X174874Y45575D01*
X174541Y45450D01*
X174291Y45283D01*
X174082Y45033D01*
X173999Y44700D01*
G01X175016Y64550D02*
Y67050D01*
X176016D01*
X176349Y66925D01*
X176599Y66633D01*
X176682Y66300D01*
X176599Y65967D01*
X176391Y65717D01*
X176016Y65592D01*
X175016D01*
G01X179866Y66842D02*
X179616Y66967D01*
X179324Y67050D01*
X178991D01*
X178616Y66925D01*
X178324Y66717D01*
X178116Y66467D01*
X177949Y66050D01*
X177907Y65675D01*
X177991Y65300D01*
X178116Y65050D01*
X178366Y64800D01*
X178657Y64633D01*
X178949Y64550D01*
X179241D01*
X179532Y64633D01*
X179782Y64758D01*
X179991Y64925D01*
G01X181257Y66633D02*
X181507Y66883D01*
X181799Y67008D01*
X182132Y67050D01*
X182549Y66967D01*
X182841Y66758D01*
X182924Y66508D01*
X182882Y66258D01*
X182716Y66050D01*
X181882Y65633D01*
X181507Y65342D01*
X181257Y64925D01*
X181174Y64550D01*
X182924D01*
G01X185149D02*
Y67050D01*
X184649Y66550D01*
G01Y64550D02*
X185649D01*
G01X175189Y56572D02*
Y59072D01*
X176189D01*
X176522Y58947D01*
X176772Y58655D01*
X176855Y58322D01*
X176772Y57989D01*
X176564Y57739D01*
X176189Y57614D01*
X175189D01*
G01X178289Y56572D02*
Y59072D01*
X179330D01*
X179664Y58947D01*
X179872Y58780D01*
X179955Y58447D01*
X179872Y58114D01*
X179622Y57905D01*
X179330Y57780D01*
X178289D01*
G01X179330D02*
X179955Y56572D01*
G01X181305Y57072D02*
X181555Y56780D01*
X181889Y56614D01*
X182264Y56572D01*
X182597Y56614D01*
X182930Y56822D01*
X183139Y57072D01*
X183180Y57322D01*
X183097Y57614D01*
X182805Y57822D01*
X182514Y57905D01*
X182139D01*
G01X182514D02*
X182764Y58030D01*
X182972Y58239D01*
X183055Y58489D01*
X182972Y58739D01*
X182764Y58947D01*
X182389Y59072D01*
X182014Y59030D01*
X181639Y58864D01*
G01X185322Y56572D02*
Y59072D01*
X184822Y58572D01*
G01Y56572D02*
X185822D01*
G01X172999Y69350D02*
X176999D01*
Y76750D01*
G01X175016Y60550D02*
Y63050D01*
X176016D01*
X176349Y62925D01*
X176599Y62633D01*
X176682Y62300D01*
X176599Y61967D01*
X176391Y61717D01*
X176016Y61592D01*
X175016D01*
G01X178116Y60550D02*
Y63050D01*
X179157D01*
X179491Y62925D01*
X179699Y62758D01*
X179782Y62425D01*
X179699Y62092D01*
X179449Y61883D01*
X179157Y61758D01*
X178116D01*
G01X179157D02*
X179782Y60550D01*
G01X181257Y62633D02*
X181507Y62883D01*
X181799Y63008D01*
X182132Y63050D01*
X182549Y62967D01*
X182841Y62758D01*
X182924Y62508D01*
X182882Y62258D01*
X182716Y62050D01*
X181882Y61633D01*
X181507Y61342D01*
X181257Y60925D01*
X181174Y60550D01*
X182924D01*
G01X185649D02*
Y63050D01*
X184107Y61258D01*
X186191D01*
G01X177426Y84428D02*
Y80428D01*
X184826D01*
G01X184872Y88572D02*
Y92572D01*
X177472D01*
G01X184872Y84572D02*
Y88572D01*
X177472D01*
G01X173999Y114750D02*
Y109250D01*
G01X174999D02*
Y114750D01*
G01X182999Y109250D02*
X174999D01*
G01X182999Y114750D02*
Y109250D01*
G01X183499Y115350D02*
X187499D01*
Y122750D01*
G01X173499Y128567D02*
X170999D01*
Y129567D01*
X171124Y129900D01*
X171416Y130150D01*
X171749Y130233D01*
X172082Y130150D01*
X172332Y129942D01*
X172457Y129567D01*
Y128567D01*
G01X171207Y133417D02*
X171082Y133167D01*
X170999Y132875D01*
Y132542D01*
X171124Y132167D01*
X171332Y131875D01*
X171582Y131667D01*
X171999Y131500D01*
X172374Y131458D01*
X172749Y131542D01*
X172999Y131667D01*
X173249Y131917D01*
X173416Y132208D01*
X173499Y132500D01*
Y132792D01*
X173416Y133083D01*
X173291Y133333D01*
X173124Y133542D01*
G01X171416Y134808D02*
X171166Y135058D01*
X171041Y135350D01*
X170999Y135683D01*
X171082Y136100D01*
X171291Y136392D01*
X171541Y136475D01*
X171791Y136433D01*
X171999Y136267D01*
X172416Y135433D01*
X172707Y135058D01*
X173124Y134808D01*
X173499Y134725D01*
Y136475D01*
G01X173124Y137783D02*
X173332Y138033D01*
X173457Y138325D01*
X173499Y138700D01*
X173416Y139075D01*
X173249Y139367D01*
X172957Y139575D01*
X172624Y139617D01*
X172291Y139533D01*
X172082Y139325D01*
X171916Y139033D01*
X171874Y138742D01*
X171916Y138450D01*
X172082Y138075D01*
X170999Y138200D01*
Y139325D01*
G01X173999Y126850D02*
Y121350D01*
G01X180499Y128567D02*
X177999D01*
Y129567D01*
X178124Y129900D01*
X178416Y130150D01*
X178749Y130233D01*
X179082Y130150D01*
X179332Y129942D01*
X179457Y129567D01*
Y128567D01*
G01X178207Y133417D02*
X178082Y133167D01*
X177999Y132875D01*
Y132542D01*
X178124Y132167D01*
X178332Y131875D01*
X178582Y131667D01*
X178999Y131500D01*
X179374Y131458D01*
X179749Y131542D01*
X179999Y131667D01*
X180249Y131917D01*
X180416Y132208D01*
X180499Y132500D01*
Y132792D01*
X180416Y133083D01*
X180291Y133333D01*
X180124Y133542D01*
G01X178416Y134808D02*
X178166Y135058D01*
X178041Y135350D01*
X177999Y135683D01*
X178082Y136100D01*
X178291Y136392D01*
X178541Y136475D01*
X178791Y136433D01*
X178999Y136267D01*
X179416Y135433D01*
X179707Y135058D01*
X180124Y134808D01*
X180499Y134725D01*
Y136475D01*
G01X179457Y137908D02*
X179166Y138200D01*
X178999Y138450D01*
X178916Y138783D01*
X178999Y139075D01*
X179166Y139283D01*
X179416Y139450D01*
X179707Y139492D01*
X179957Y139450D01*
X180207Y139283D01*
X180416Y139033D01*
X180499Y138742D01*
X180416Y138408D01*
X180166Y138117D01*
X179791Y137950D01*
X179374Y137908D01*
X178832Y137992D01*
X178541Y138117D01*
X178249Y138325D01*
X178041Y138617D01*
X177999Y138908D01*
X178082Y139200D01*
X178291Y139408D01*
G01X182999Y126850D02*
Y121350D01*
G01X174999Y126850D02*
X182999D01*
G01X174999Y121350D02*
Y126850D01*
G01X187499Y125067D02*
X184999D01*
Y126067D01*
X185124Y126400D01*
X185416Y126650D01*
X185749Y126733D01*
X186082Y126650D01*
X186332Y126442D01*
X186457Y126067D01*
Y125067D01*
G01X187499Y128167D02*
X184999D01*
Y129208D01*
X185124Y129542D01*
X185291Y129750D01*
X185624Y129833D01*
X185957Y129750D01*
X186166Y129500D01*
X186291Y129208D01*
Y128167D01*
G01Y129208D02*
X187499Y129833D01*
G01X185416Y131308D02*
X185166Y131558D01*
X185041Y131850D01*
X184999Y132183D01*
X185082Y132600D01*
X185291Y132892D01*
X185541Y132975D01*
X185791Y132933D01*
X185999Y132767D01*
X186416Y131933D01*
X186707Y131558D01*
X187124Y131308D01*
X187499Y131225D01*
Y132975D01*
G01Y135200D02*
X184999D01*
X185499Y134700D01*
G01X187499D02*
Y135700D01*
G01X174799Y158550D02*
Y154550D01*
X182199D01*
G01X180516Y146050D02*
Y148550D01*
X181557D01*
X181891Y148425D01*
X182099Y148258D01*
X182182Y147925D01*
X182099Y147592D01*
X181849Y147383D01*
X181557Y147258D01*
X180516D01*
G01X181557D02*
X182182Y146050D01*
G01X184949D02*
Y148550D01*
X183407Y146758D01*
X185491D01*
G01X186841Y146342D02*
X187132Y146133D01*
X187466Y146050D01*
X187799Y146133D01*
X188091Y146383D01*
X188299Y146758D01*
X188382Y147133D01*
Y147592D01*
X188299Y147967D01*
X188091Y148300D01*
X187841Y148467D01*
X187549Y148550D01*
X187216Y148467D01*
X186966Y148300D01*
X186799Y148050D01*
X186716Y147717D01*
X186799Y147425D01*
X187007Y147133D01*
X187257Y146967D01*
X187549Y146925D01*
X187882Y147008D01*
X188132Y147217D01*
X188382Y147592D01*
G01X189941Y146342D02*
X190232Y146133D01*
X190566Y146050D01*
X190899Y146133D01*
X191191Y146383D01*
X191399Y146758D01*
X191482Y147133D01*
Y147592D01*
X191399Y147967D01*
X191191Y148300D01*
X190941Y148467D01*
X190649Y148550D01*
X190316Y148467D01*
X190066Y148300D01*
X189899Y148050D01*
X189816Y147717D01*
X189899Y147425D01*
X190107Y147133D01*
X190357Y146967D01*
X190649Y146925D01*
X190982Y147008D01*
X191232Y147217D01*
X191482Y147592D01*
G01X188599Y150000D02*
Y154000D01*
X181199D01*
G01X182799Y154700D02*
X196799D01*
G01X182799Y167700D02*
Y154700D01*
G01X179016Y178550D02*
Y181050D01*
X180057D01*
X180391Y180925D01*
X180599Y180758D01*
X180682Y180425D01*
X180599Y180092D01*
X180349Y179883D01*
X180057Y179758D01*
X179016D01*
G01X180057D02*
X180682Y178550D01*
G01X182157Y180633D02*
X182407Y180883D01*
X182699Y181008D01*
X183032Y181050D01*
X183449Y180967D01*
X183741Y180758D01*
X183824Y180508D01*
X183782Y180258D01*
X183616Y180050D01*
X182782Y179633D01*
X182407Y179342D01*
X182157Y178925D01*
X182074Y178550D01*
X183824D01*
G01X185257Y180633D02*
X185507Y180883D01*
X185799Y181008D01*
X186132Y181050D01*
X186549Y180967D01*
X186841Y180758D01*
X186924Y180508D01*
X186882Y180258D01*
X186716Y180050D01*
X185882Y179633D01*
X185507Y179342D01*
X185257Y178925D01*
X185174Y178550D01*
X186924D01*
G01X188357Y179592D02*
X188649Y179883D01*
X188899Y180050D01*
X189232Y180133D01*
X189524Y180050D01*
X189732Y179883D01*
X189899Y179633D01*
X189941Y179342D01*
X189899Y179092D01*
X189732Y178842D01*
X189482Y178633D01*
X189191Y178550D01*
X188857Y178633D01*
X188566Y178883D01*
X188399Y179258D01*
X188357Y179675D01*
X188441Y180217D01*
X188566Y180508D01*
X188774Y180800D01*
X189066Y181008D01*
X189357Y181050D01*
X189649Y180967D01*
X189857Y180758D01*
G01X174799Y167050D02*
Y163050D01*
X182199D01*
G01X179016Y174550D02*
Y177050D01*
X180057D01*
X180391Y176925D01*
X180599Y176758D01*
X180682Y176425D01*
X180599Y176092D01*
X180349Y175883D01*
X180057Y175758D01*
X179016D01*
G01X180057D02*
X180682Y174550D01*
G01X182157Y176633D02*
X182407Y176883D01*
X182699Y177008D01*
X183032Y177050D01*
X183449Y176967D01*
X183741Y176758D01*
X183824Y176508D01*
X183782Y176258D01*
X183616Y176050D01*
X182782Y175633D01*
X182407Y175342D01*
X182157Y174925D01*
X182074Y174550D01*
X183824D01*
G01X185257Y176633D02*
X185507Y176883D01*
X185799Y177008D01*
X186132Y177050D01*
X186549Y176967D01*
X186841Y176758D01*
X186924Y176508D01*
X186882Y176258D01*
X186716Y176050D01*
X185882Y175633D01*
X185507Y175342D01*
X185257Y174925D01*
X185174Y174550D01*
X186924D01*
G01X189149D02*
X189441Y174592D01*
X189774Y174717D01*
X189982Y174925D01*
X190066Y175217D01*
X189982Y175508D01*
X189732Y175758D01*
X189357Y175883D01*
X188941D01*
X188691Y175967D01*
X188482Y176175D01*
X188399Y176467D01*
X188524Y176758D01*
X188816Y176967D01*
X189149Y177050D01*
X189482Y176967D01*
X189774Y176758D01*
X189899Y176467D01*
X189816Y176175D01*
X189607Y175967D01*
X189357Y175883D01*
X188941D01*
X188566Y175758D01*
X188316Y175508D01*
X188232Y175217D01*
X188316Y174925D01*
X188524Y174717D01*
X188857Y174592D01*
X189149Y174550D01*
G01X174799Y163050D02*
Y159050D01*
X182199D01*
G01X179016Y170050D02*
Y172550D01*
X180057D01*
X180391Y172425D01*
X180599Y172258D01*
X180682Y171925D01*
X180599Y171592D01*
X180349Y171383D01*
X180057Y171258D01*
X179016D01*
G01X180057D02*
X180682Y170050D01*
G01X182157Y172133D02*
X182407Y172383D01*
X182699Y172508D01*
X183032Y172550D01*
X183449Y172467D01*
X183741Y172258D01*
X183824Y172008D01*
X183782Y171758D01*
X183616Y171550D01*
X182782Y171133D01*
X182407Y170842D01*
X182157Y170425D01*
X182074Y170050D01*
X183824D01*
G01X185132Y170550D02*
X185382Y170258D01*
X185716Y170092D01*
X186091Y170050D01*
X186424Y170092D01*
X186757Y170300D01*
X186966Y170550D01*
X187007Y170800D01*
X186924Y171092D01*
X186632Y171300D01*
X186341Y171383D01*
X185966D01*
G01X186341D02*
X186591Y171508D01*
X186799Y171717D01*
X186882Y171967D01*
X186799Y172217D01*
X186591Y172425D01*
X186216Y172550D01*
X185841Y172508D01*
X185466Y172342D01*
G01X189149Y172550D02*
X188816Y172467D01*
X188566Y172258D01*
X188399Y172008D01*
X188274Y171675D01*
X188232Y171300D01*
X188274Y170925D01*
X188399Y170592D01*
X188566Y170342D01*
X188816Y170133D01*
X189149Y170050D01*
X189482Y170133D01*
X189732Y170342D01*
X189899Y170592D01*
X190024Y170925D01*
X190066Y171300D01*
X190024Y171675D01*
X189899Y172008D01*
X189732Y172258D01*
X189482Y172467D01*
X189149Y172550D01*
G01X196799Y167700D02*
X182799D01*
G01X168699Y429913D02*
Y441313D01*
G01X174517Y417500D02*
Y420000D01*
X175558D01*
X175892Y419875D01*
X176100Y419708D01*
X176183Y419375D01*
X176100Y419042D01*
X175850Y418833D01*
X175558Y418708D01*
X174517D01*
G01X175558D02*
X176183Y417500D01*
G01X178950D02*
Y420000D01*
X177408Y418208D01*
X179492D01*
G01X180758Y419583D02*
X181008Y419833D01*
X181300Y419958D01*
X181633Y420000D01*
X182050Y419917D01*
X182342Y419708D01*
X182425Y419458D01*
X182383Y419208D01*
X182217Y419000D01*
X181383Y418583D01*
X181008Y418292D01*
X180758Y417875D01*
X180675Y417500D01*
X182425D01*
G01X184650D02*
Y420000D01*
X184150Y419500D01*
G01Y417500D02*
X185150D01*
G01X167000Y426400D02*
Y422400D01*
X174400D01*
G01X178399Y448350D02*
Y429150D01*
X189599D01*
Y448350D01*
X178399D01*
G01X185999D02*
X183999Y446350D01*
X181999Y448350D01*
G01X173100Y449500D02*
Y472500D01*
G01X211900Y449500D02*
X173100D01*
G01X171900Y455300D02*
Y449800D01*
G01X173100Y472500D02*
X211900D01*
G01X171900Y467400D02*
Y461900D01*
G01X179200Y474000D02*
X196800D01*
G01X179200Y482000D02*
Y474000D01*
G01X187999Y501850D02*
X183999D01*
Y494450D01*
G01X183899Y501850D02*
X179899D01*
Y494450D01*
G01X186949Y483353D02*
X173549D01*
G01X186949Y493353D02*
Y483353D01*
G01X173549Y493353D02*
X186949D01*
G01X173549Y483353D02*
Y493353D01*
G01X196800Y482000D02*
X179200D01*
G01X172199Y515150D02*
X176199D01*
Y522550D01*
G01X172108Y504000D02*
Y506500D01*
X173692D01*
G01X173108Y505292D02*
X172108D01*
G01X175208Y506083D02*
X175458Y506333D01*
X175750Y506458D01*
X176083Y506500D01*
X176500Y506417D01*
X176792Y506208D01*
X176875Y505958D01*
X176833Y505708D01*
X176667Y505500D01*
X175833Y505083D01*
X175458Y504792D01*
X175208Y504375D01*
X175125Y504000D01*
X176875D01*
G01X179017D02*
X179100Y504542D01*
X179225Y505000D01*
X179392Y505417D01*
X179600Y505875D01*
X179933Y506500D01*
X178267D01*
G01X176399Y522850D02*
Y526850D01*
X168999D01*
G01X183000Y538046D02*
X184792D01*
X185167Y538213D01*
X185417Y538546D01*
X185500Y538963D01*
X185417Y539380D01*
X185167Y539713D01*
X184792Y539880D01*
X183000D01*
G01X185500Y542563D02*
X183000D01*
X184792Y541021D01*
Y543105D01*
G01X185500Y545080D02*
X184958Y545163D01*
X184500Y545288D01*
X184083Y545455D01*
X183625Y545663D01*
X183000Y545996D01*
Y544330D01*
G01X179787Y552115D02*
Y554615D01*
X180828D01*
X181162Y554490D01*
X181370Y554323D01*
X181453Y553990D01*
X181370Y553657D01*
X181120Y553448D01*
X180828Y553323D01*
X179787D01*
G01X180828D02*
X181453Y552115D01*
G01X184220D02*
Y554615D01*
X182678Y552823D01*
X184762D01*
G01X186112Y552407D02*
X186403Y552198D01*
X186737Y552115D01*
X187070Y552198D01*
X187362Y552448D01*
X187570Y552823D01*
X187653Y553198D01*
Y553657D01*
X187570Y554032D01*
X187362Y554365D01*
X187112Y554532D01*
X186820Y554615D01*
X186487Y554532D01*
X186237Y554365D01*
X186070Y554115D01*
X185987Y553782D01*
X186070Y553490D01*
X186278Y553198D01*
X186528Y553032D01*
X186820Y552990D01*
X187153Y553073D01*
X187403Y553282D01*
X187653Y553657D01*
G01X189920Y552115D02*
X190212Y552157D01*
X190545Y552282D01*
X190753Y552490D01*
X190837Y552782D01*
X190753Y553073D01*
X190503Y553323D01*
X190128Y553448D01*
X189712D01*
X189462Y553532D01*
X189253Y553740D01*
X189170Y554032D01*
X189295Y554323D01*
X189587Y554532D01*
X189920Y554615D01*
X190253Y554532D01*
X190545Y554323D01*
X190670Y554032D01*
X190587Y553740D01*
X190378Y553532D01*
X190128Y553448D01*
X189712D01*
X189337Y553323D01*
X189087Y553073D01*
X189003Y552782D01*
X189087Y552490D01*
X189295Y552282D01*
X189628Y552157D01*
X189920Y552115D01*
G01X175417Y539228D02*
X173417Y541228D01*
X175417Y543228D01*
G01X174799Y574050D02*
Y570050D01*
X182199D01*
G01X179516Y581550D02*
Y584050D01*
X180557D01*
X180891Y583925D01*
X181099Y583758D01*
X181182Y583425D01*
X181099Y583092D01*
X180849Y582883D01*
X180557Y582758D01*
X179516D01*
G01X180557D02*
X181182Y581550D01*
G01X182657Y583633D02*
X182907Y583883D01*
X183199Y584008D01*
X183532Y584050D01*
X183949Y583967D01*
X184241Y583758D01*
X184324Y583508D01*
X184282Y583258D01*
X184116Y583050D01*
X183282Y582633D01*
X182907Y582342D01*
X182657Y581925D01*
X182574Y581550D01*
X184324D01*
G01X186549D02*
Y584050D01*
X186049Y583550D01*
G01Y581550D02*
X187049D01*
G01X190149D02*
Y584050D01*
X188607Y582258D01*
X190691D01*
G01X174799Y570050D02*
Y566050D01*
X182199D01*
G01X179516Y577550D02*
Y580050D01*
X180557D01*
X180891Y579925D01*
X181099Y579758D01*
X181182Y579425D01*
X181099Y579092D01*
X180849Y578883D01*
X180557Y578758D01*
X179516D01*
G01X180557D02*
X181182Y577550D01*
G01X182657Y579633D02*
X182907Y579883D01*
X183199Y580008D01*
X183532Y580050D01*
X183949Y579967D01*
X184241Y579758D01*
X184324Y579508D01*
X184282Y579258D01*
X184116Y579050D01*
X183282Y578633D01*
X182907Y578342D01*
X182657Y577925D01*
X182574Y577550D01*
X184324D01*
G01X186549D02*
Y580050D01*
X186049Y579550D01*
G01Y577550D02*
X187049D01*
G01X188857Y578592D02*
X189149Y578883D01*
X189399Y579050D01*
X189732Y579133D01*
X190024Y579050D01*
X190232Y578883D01*
X190399Y578633D01*
X190441Y578342D01*
X190399Y578092D01*
X190232Y577842D01*
X189982Y577633D01*
X189691Y577550D01*
X189357Y577633D01*
X189066Y577883D01*
X188899Y578258D01*
X188857Y578675D01*
X188941Y579217D01*
X189066Y579508D01*
X189274Y579800D01*
X189566Y580008D01*
X189857Y580050D01*
X190149Y579967D01*
X190357Y579758D01*
G01X174799Y566050D02*
Y562050D01*
X182199D01*
G01X188599Y557300D02*
Y561300D01*
X181199D01*
G01X182799Y561900D02*
X196799D01*
G01X182799Y574900D02*
Y561900D01*
G01X196799Y574900D02*
X182799D01*
G01X179516Y585550D02*
Y588050D01*
X180557D01*
X180891Y587925D01*
X181099Y587758D01*
X181182Y587425D01*
X181099Y587092D01*
X180849Y586883D01*
X180557Y586758D01*
X179516D01*
G01X180557D02*
X181182Y585550D01*
G01X182657Y587633D02*
X182907Y587883D01*
X183199Y588008D01*
X183532Y588050D01*
X183949Y587967D01*
X184241Y587758D01*
X184324Y587508D01*
X184282Y587258D01*
X184116Y587050D01*
X183282Y586633D01*
X182907Y586342D01*
X182657Y585925D01*
X182574Y585550D01*
X184324D01*
G01X186549D02*
Y588050D01*
X186049Y587550D01*
G01Y585550D02*
X187049D01*
G01X188857Y587633D02*
X189107Y587883D01*
X189399Y588008D01*
X189732Y588050D01*
X190149Y587967D01*
X190441Y587758D01*
X190524Y587508D01*
X190482Y587258D01*
X190316Y587050D01*
X189482Y586633D01*
X189107Y586342D01*
X188857Y585925D01*
X188774Y585550D01*
X190524D01*
G01X184899Y810550D02*
X184566Y810592D01*
X184274Y810758D01*
X184024Y811008D01*
X183857Y811300D01*
X183774Y811633D01*
Y811967D01*
X183857Y812300D01*
X184024Y812592D01*
X184274Y812842D01*
X184566Y813008D01*
X184899Y813050D01*
X185232Y813008D01*
X185524Y812842D01*
X185774Y812592D01*
X185941Y812300D01*
X186024Y811967D01*
Y811633D01*
X185941Y811300D01*
X185774Y811008D01*
X185524Y810758D01*
X185232Y810592D01*
X184899Y810550D01*
G01X185232Y811217D02*
X185732Y810550D01*
G01X187207Y812633D02*
X187457Y812883D01*
X187749Y813008D01*
X188082Y813050D01*
X188499Y812967D01*
X188791Y812758D01*
X188874Y812508D01*
X188832Y812258D01*
X188666Y812050D01*
X187832Y811633D01*
X187457Y811342D01*
X187207Y810925D01*
X187124Y810550D01*
X188874D01*
G01X190307Y811592D02*
X190599Y811883D01*
X190849Y812050D01*
X191182Y812133D01*
X191474Y812050D01*
X191682Y811883D01*
X191849Y811633D01*
X191891Y811342D01*
X191849Y811092D01*
X191682Y810842D01*
X191432Y810633D01*
X191141Y810550D01*
X190807Y810633D01*
X190516Y810883D01*
X190349Y811258D01*
X190307Y811675D01*
X190391Y812217D01*
X190516Y812508D01*
X190724Y812800D01*
X191016Y813008D01*
X191307Y813050D01*
X191599Y812967D01*
X191807Y812758D01*
G01X171499Y794630D02*
X168999D01*
Y795671D01*
X169124Y796005D01*
X169291Y796213D01*
X169624Y796296D01*
X169957Y796213D01*
X170166Y795963D01*
X170291Y795671D01*
Y794630D01*
G01Y795671D02*
X171499Y796296D01*
G01Y799063D02*
X168999D01*
X170791Y797521D01*
Y799605D01*
G01X171499Y801580D02*
X170957Y801663D01*
X170499Y801788D01*
X170082Y801955D01*
X169624Y802163D01*
X168999Y802496D01*
Y800830D01*
G01Y804763D02*
X169082Y804430D01*
X169291Y804180D01*
X169541Y804013D01*
X169874Y803888D01*
X170249Y803846D01*
X170624Y803888D01*
X170957Y804013D01*
X171207Y804180D01*
X171416Y804430D01*
X171499Y804763D01*
X171416Y805096D01*
X171207Y805346D01*
X170957Y805513D01*
X170624Y805638D01*
X170249Y805680D01*
X169874Y805638D01*
X169541Y805513D01*
X169291Y805346D01*
X169082Y805096D01*
X168999Y804763D01*
G01X168499Y806913D02*
X172499D01*
Y814313D01*
G01X175009Y806402D02*
X176801D01*
X177176Y806569D01*
X177426Y806902D01*
X177509Y807319D01*
X177426Y807736D01*
X177176Y808069D01*
X176801Y808236D01*
X175009D01*
G01X177009Y809502D02*
X177301Y809752D01*
X177467Y810086D01*
X177509Y810461D01*
X177467Y810794D01*
X177259Y811127D01*
X177009Y811336D01*
X176759Y811377D01*
X176467Y811294D01*
X176259Y811002D01*
X176176Y810711D01*
Y810336D01*
G01Y810711D02*
X176051Y810961D01*
X175842Y811169D01*
X175592Y811252D01*
X175342Y811169D01*
X175134Y810961D01*
X175009Y810586D01*
X175051Y810211D01*
X175217Y809836D01*
G01X177217Y812811D02*
X177426Y813102D01*
X177509Y813436D01*
X177426Y813769D01*
X177176Y814061D01*
X176801Y814269D01*
X176426Y814352D01*
X175967D01*
X175592Y814269D01*
X175259Y814061D01*
X175092Y813811D01*
X175009Y813519D01*
X175092Y813186D01*
X175259Y812936D01*
X175509Y812769D01*
X175842Y812686D01*
X176134Y812769D01*
X176426Y812977D01*
X176592Y813227D01*
X176634Y813519D01*
X176551Y813852D01*
X176342Y814102D01*
X175967Y814352D01*
G01X178799Y839813D02*
Y828413D01*
G01D02*
X192199D01*
G01X186999Y814630D02*
X184499D01*
Y815671D01*
X184624Y816005D01*
X184791Y816213D01*
X185124Y816296D01*
X185457Y816213D01*
X185666Y815963D01*
X185791Y815671D01*
Y814630D01*
G01Y815671D02*
X186999Y816296D01*
G01X184916Y817771D02*
X184666Y818021D01*
X184541Y818313D01*
X184499Y818646D01*
X184582Y819063D01*
X184791Y819355D01*
X185041Y819438D01*
X185291Y819396D01*
X185499Y819230D01*
X185916Y818396D01*
X186207Y818021D01*
X186624Y817771D01*
X186999Y817688D01*
Y819438D01*
G01Y821580D02*
X186457Y821663D01*
X185999Y821788D01*
X185582Y821955D01*
X185124Y822163D01*
X184499Y822496D01*
Y820830D01*
G01X186624Y823846D02*
X186832Y824096D01*
X186957Y824388D01*
X186999Y824763D01*
X186916Y825138D01*
X186749Y825430D01*
X186457Y825638D01*
X186124Y825680D01*
X185791Y825596D01*
X185582Y825388D01*
X185416Y825096D01*
X185374Y824805D01*
X185416Y824513D01*
X185582Y824138D01*
X184499Y824263D01*
Y825388D01*
G01X178499Y838813D02*
X174499D01*
Y831413D01*
G01X170499D02*
X174499D01*
Y838813D01*
G01X174999Y830313D02*
Y816913D01*
G01X192199Y839813D02*
X178799D01*
G01X187999Y847813D02*
X183999D01*
Y840413D01*
G01Y848313D02*
Y853813D01*
G01X191999Y848313D02*
X183999D01*
G01X174999D02*
Y853813D01*
G01X182999Y848313D02*
X174999D01*
G01X182999Y853813D02*
Y848313D01*
G01X173999Y853813D02*
Y848313D01*
G01X186499Y866613D02*
Y879613D01*
G01X187499Y869813D02*
Y875313D01*
G01X195499Y869813D02*
X187499D01*
G01X183999Y865913D02*
X191999D01*
G01X183999Y860413D02*
Y865913D01*
G01X182999D02*
Y860413D01*
G01X174999Y865913D02*
X182999D01*
G01X174999Y860413D02*
Y865913D01*
G01X173999D02*
Y860413D01*
G01X187499Y887413D02*
X195499D01*
G01X187499Y881913D02*
Y887413D01*
G01X173499Y899413D02*
Y893913D01*
G01Y887313D02*
Y881813D01*
G01X176608Y883000D02*
Y885500D01*
X178192D01*
G01X177608Y884292D02*
X176608D01*
G01X179708Y885083D02*
X179958Y885333D01*
X180250Y885458D01*
X180583Y885500D01*
X181000Y885417D01*
X181292Y885208D01*
X181375Y884958D01*
X181333Y884708D01*
X181167Y884500D01*
X180333Y884083D01*
X179958Y883792D01*
X179708Y883375D01*
X179625Y883000D01*
X181375D01*
G01X182683Y883375D02*
X182933Y883167D01*
X183225Y883042D01*
X183600Y883000D01*
X183975Y883083D01*
X184267Y883250D01*
X184475Y883542D01*
X184517Y883875D01*
X184433Y884208D01*
X184225Y884417D01*
X183933Y884583D01*
X183642Y884625D01*
X183350Y884583D01*
X182975Y884417D01*
X183100Y885500D01*
X184225D01*
G01X175149Y898363D02*
Y888863D01*
X192849D01*
Y898363D01*
X175149D01*
G01X186499Y900113D02*
Y913113D01*
G01X176699Y914113D02*
Y918113D01*
X169299D01*
G01X177400Y929000D02*
Y915000D01*
G01D02*
X190400D01*
G01X200600Y914200D02*
Y907200D01*
X187200D01*
Y914200D01*
X200600D01*
G01X178200Y934100D02*
X189600D01*
G01X178200Y947500D02*
Y934100D01*
G01X169300Y924700D02*
Y920700D01*
X176700D01*
G01X178400Y933600D02*
Y929600D01*
X185800D01*
G01X176000Y926900D02*
X175958Y926567D01*
X175792Y926275D01*
X175542Y926025D01*
X175250Y925858D01*
X174917Y925775D01*
X174583D01*
X174250Y925858D01*
X173958Y926025D01*
X173708Y926275D01*
X173542Y926567D01*
X173500Y926900D01*
X173542Y927233D01*
X173708Y927525D01*
X173958Y927775D01*
X174250Y927942D01*
X174583Y928025D01*
X174917D01*
X175250Y927942D01*
X175542Y927775D01*
X175792Y927525D01*
X175958Y927233D01*
X176000Y926900D01*
G01X175333Y927233D02*
X176000Y927733D01*
G01Y929917D02*
X175458Y930000D01*
X175000Y930125D01*
X174583Y930292D01*
X174125Y930500D01*
X173500Y930833D01*
Y929167D01*
G01X176000Y933100D02*
X173500D01*
X174000Y932600D01*
G01X176000D02*
Y933600D01*
G01X190400Y929000D02*
X177400D01*
G01X189600Y947500D02*
X178200D01*
G01X187016Y956550D02*
Y959050D01*
X188057D01*
X188391Y958925D01*
X188599Y958758D01*
X188682Y958425D01*
X188599Y958092D01*
X188349Y957883D01*
X188057Y957758D01*
X187016D01*
G01X188057D02*
X188682Y956550D01*
G01X191449D02*
Y959050D01*
X189907Y957258D01*
X191991D01*
G01X193341Y956842D02*
X193632Y956633D01*
X193966Y956550D01*
X194299Y956633D01*
X194591Y956883D01*
X194799Y957258D01*
X194882Y957633D01*
Y958092D01*
X194799Y958467D01*
X194591Y958800D01*
X194341Y958967D01*
X194049Y959050D01*
X193716Y958967D01*
X193466Y958800D01*
X193299Y958550D01*
X193216Y958217D01*
X193299Y957925D01*
X193507Y957633D01*
X193757Y957467D01*
X194049Y957425D01*
X194382Y957508D01*
X194632Y957717D01*
X194882Y958092D01*
G01X197066Y956550D02*
X197149Y957092D01*
X197274Y957550D01*
X197441Y957967D01*
X197649Y958425D01*
X197982Y959050D01*
X196316D01*
G01X174549Y978550D02*
Y974550D01*
X181949D01*
G01X174549D02*
Y970550D01*
X181949D01*
G01X174799Y969550D02*
Y965550D01*
X182199D01*
G01X189099Y961100D02*
Y965100D01*
X181699D01*
G01X182799Y965600D02*
X196799D01*
G01X182799Y978600D02*
Y965600D01*
G01X196799Y978600D02*
X182799D01*
G01X176899Y1258613D02*
Y1235613D01*
G01X181107Y1244550D02*
Y1247050D01*
X182691D01*
G01X182107Y1245842D02*
X181107D01*
G01X184207Y1246633D02*
X184457Y1246883D01*
X184749Y1247008D01*
X185082Y1247050D01*
X185499Y1246967D01*
X185791Y1246758D01*
X185874Y1246508D01*
X185832Y1246258D01*
X185666Y1246050D01*
X184832Y1245633D01*
X184457Y1245342D01*
X184207Y1244925D01*
X184124Y1244550D01*
X185874D01*
G01X188599D02*
Y1247050D01*
X187057Y1245258D01*
X189141D01*
G01X167517Y1262500D02*
Y1265000D01*
X168558D01*
X168892Y1264875D01*
X169100Y1264708D01*
X169183Y1264375D01*
X169100Y1264042D01*
X168850Y1263833D01*
X168558Y1263708D01*
X167517D01*
G01X168558D02*
X169183Y1262500D01*
G01X170533Y1262875D02*
X170783Y1262667D01*
X171075Y1262542D01*
X171450Y1262500D01*
X171825Y1262583D01*
X172117Y1262750D01*
X172325Y1263042D01*
X172367Y1263375D01*
X172283Y1263708D01*
X172075Y1263917D01*
X171783Y1264083D01*
X171492Y1264125D01*
X171200Y1264083D01*
X170825Y1263917D01*
X170950Y1265000D01*
X172075D01*
G01X173633Y1263000D02*
X173883Y1262708D01*
X174217Y1262542D01*
X174592Y1262500D01*
X174925Y1262542D01*
X175258Y1262750D01*
X175467Y1263000D01*
X175508Y1263250D01*
X175425Y1263542D01*
X175133Y1263750D01*
X174842Y1263833D01*
X174467D01*
G01X174842D02*
X175092Y1263958D01*
X175300Y1264167D01*
X175383Y1264417D01*
X175300Y1264667D01*
X175092Y1264875D01*
X174717Y1265000D01*
X174342Y1264958D01*
X173967Y1264792D01*
G01X176733Y1262875D02*
X176983Y1262667D01*
X177275Y1262542D01*
X177650Y1262500D01*
X178025Y1262583D01*
X178317Y1262750D01*
X178525Y1263042D01*
X178567Y1263375D01*
X178483Y1263708D01*
X178275Y1263917D01*
X177983Y1264083D01*
X177692Y1264125D01*
X177400Y1264083D01*
X177025Y1263917D01*
X177150Y1265000D01*
X178275D01*
G01X179499Y1281950D02*
X179457Y1281617D01*
X179291Y1281325D01*
X179041Y1281075D01*
X178749Y1280908D01*
X178416Y1280825D01*
X178082D01*
X177749Y1280908D01*
X177457Y1281075D01*
X177207Y1281325D01*
X177041Y1281617D01*
X176999Y1281950D01*
X177041Y1282283D01*
X177207Y1282575D01*
X177457Y1282825D01*
X177749Y1282992D01*
X178082Y1283075D01*
X178416D01*
X178749Y1282992D01*
X179041Y1282825D01*
X179291Y1282575D01*
X179457Y1282283D01*
X179499Y1281950D01*
G01X178832Y1282283D02*
X179499Y1282783D01*
G01X177416Y1284258D02*
X177166Y1284508D01*
X177041Y1284800D01*
X176999Y1285133D01*
X177082Y1285550D01*
X177291Y1285842D01*
X177541Y1285925D01*
X177791Y1285883D01*
X177999Y1285717D01*
X178416Y1284883D01*
X178707Y1284508D01*
X179124Y1284258D01*
X179499Y1284175D01*
Y1285925D01*
G01X178999Y1287233D02*
X179291Y1287483D01*
X179457Y1287817D01*
X179499Y1288192D01*
X179457Y1288525D01*
X179249Y1288858D01*
X178999Y1289067D01*
X178749Y1289108D01*
X178457Y1289025D01*
X178249Y1288733D01*
X178166Y1288442D01*
Y1288067D01*
G01Y1288442D02*
X178041Y1288692D01*
X177832Y1288900D01*
X177582Y1288983D01*
X177332Y1288900D01*
X177124Y1288692D01*
X176999Y1288317D01*
X177041Y1287942D01*
X177207Y1287567D01*
G01X186500Y1355897D02*
X184000D01*
Y1356938D01*
X184125Y1357272D01*
X184292Y1357480D01*
X184625Y1357563D01*
X184958Y1357480D01*
X185167Y1357230D01*
X185292Y1356938D01*
Y1355897D01*
G01Y1356938D02*
X186500Y1357563D01*
G01Y1359830D02*
X184000D01*
X184500Y1359330D01*
G01X186500D02*
Y1360330D01*
G01Y1362930D02*
X186458Y1363222D01*
X186333Y1363555D01*
X186125Y1363763D01*
X185833Y1363847D01*
X185542Y1363763D01*
X185292Y1363513D01*
X185167Y1363138D01*
Y1362722D01*
X185083Y1362472D01*
X184875Y1362263D01*
X184583Y1362180D01*
X184292Y1362305D01*
X184083Y1362597D01*
X184000Y1362930D01*
X184083Y1363263D01*
X184292Y1363555D01*
X184583Y1363680D01*
X184875Y1363597D01*
X185083Y1363388D01*
X185167Y1363138D01*
Y1362722D01*
X185292Y1362347D01*
X185542Y1362097D01*
X185833Y1362013D01*
X186125Y1362097D01*
X186333Y1362305D01*
X186458Y1362638D01*
X186500Y1362930D01*
G01X186125Y1365113D02*
X186333Y1365363D01*
X186458Y1365655D01*
X186500Y1366030D01*
X186417Y1366405D01*
X186250Y1366697D01*
X185958Y1366905D01*
X185625Y1366947D01*
X185292Y1366863D01*
X185083Y1366655D01*
X184917Y1366363D01*
X184875Y1366072D01*
X184917Y1365780D01*
X185083Y1365405D01*
X184000Y1365530D01*
Y1366655D01*
G01X182400Y1355897D02*
X179900D01*
Y1356938D01*
X180025Y1357272D01*
X180192Y1357480D01*
X180525Y1357563D01*
X180858Y1357480D01*
X181067Y1357230D01*
X181192Y1356938D01*
Y1355897D01*
G01Y1356938D02*
X182400Y1357563D01*
G01Y1359830D02*
X179900D01*
X180400Y1359330D01*
G01X182400D02*
Y1360330D01*
G01Y1362930D02*
X182358Y1363222D01*
X182233Y1363555D01*
X182025Y1363763D01*
X181733Y1363847D01*
X181442Y1363763D01*
X181192Y1363513D01*
X181067Y1363138D01*
Y1362722D01*
X180983Y1362472D01*
X180775Y1362263D01*
X180483Y1362180D01*
X180192Y1362305D01*
X179983Y1362597D01*
X179900Y1362930D01*
X179983Y1363263D01*
X180192Y1363555D01*
X180483Y1363680D01*
X180775Y1363597D01*
X180983Y1363388D01*
X181067Y1363138D01*
Y1362722D01*
X181192Y1362347D01*
X181442Y1362097D01*
X181733Y1362013D01*
X182025Y1362097D01*
X182233Y1362305D01*
X182358Y1362638D01*
X182400Y1362930D01*
G01Y1365947D02*
X181858Y1366030D01*
X181400Y1366155D01*
X180983Y1366322D01*
X180525Y1366530D01*
X179900Y1366863D01*
Y1365197D01*
G01X182600Y1371100D02*
X186600D01*
Y1378500D01*
G01X178500Y1371100D02*
X182500D01*
Y1378500D01*
G01X187129Y1394630D02*
Y1397130D01*
X188170D01*
X188504Y1397005D01*
X188712Y1396838D01*
X188795Y1396505D01*
X188712Y1396172D01*
X188462Y1395963D01*
X188170Y1395838D01*
X187129D01*
G01X188170D02*
X188795Y1394630D01*
G01X191062D02*
Y1397130D01*
X190562Y1396630D01*
G01Y1394630D02*
X191562D01*
G01X194162D02*
X194454Y1394672D01*
X194787Y1394797D01*
X194995Y1395005D01*
X195079Y1395297D01*
X194995Y1395588D01*
X194745Y1395838D01*
X194370Y1395963D01*
X193954D01*
X193704Y1396047D01*
X193495Y1396255D01*
X193412Y1396547D01*
X193537Y1396838D01*
X193829Y1397047D01*
X194162Y1397130D01*
X194495Y1397047D01*
X194787Y1396838D01*
X194912Y1396547D01*
X194829Y1396255D01*
X194620Y1396047D01*
X194370Y1395963D01*
X193954D01*
X193579Y1395838D01*
X193329Y1395588D01*
X193245Y1395297D01*
X193329Y1395005D01*
X193537Y1394797D01*
X193870Y1394672D01*
X194162Y1394630D01*
G01X197762D02*
Y1397130D01*
X196220Y1395338D01*
X198304D01*
G01X187129Y1390630D02*
Y1393130D01*
X188170D01*
X188504Y1393005D01*
X188712Y1392838D01*
X188795Y1392505D01*
X188712Y1392172D01*
X188462Y1391963D01*
X188170Y1391838D01*
X187129D01*
G01X188170D02*
X188795Y1390630D01*
G01X191062D02*
Y1393130D01*
X190562Y1392630D01*
G01Y1390630D02*
X191562D01*
G01X194162D02*
X194454Y1390672D01*
X194787Y1390797D01*
X194995Y1391005D01*
X195079Y1391297D01*
X194995Y1391588D01*
X194745Y1391838D01*
X194370Y1391963D01*
X193954D01*
X193704Y1392047D01*
X193495Y1392255D01*
X193412Y1392547D01*
X193537Y1392838D01*
X193829Y1393047D01*
X194162Y1393130D01*
X194495Y1393047D01*
X194787Y1392838D01*
X194912Y1392547D01*
X194829Y1392255D01*
X194620Y1392047D01*
X194370Y1391963D01*
X193954D01*
X193579Y1391838D01*
X193329Y1391588D01*
X193245Y1391297D01*
X193329Y1391005D01*
X193537Y1390797D01*
X193870Y1390672D01*
X194162Y1390630D01*
G01X196470Y1391672D02*
X196762Y1391963D01*
X197012Y1392130D01*
X197345Y1392213D01*
X197637Y1392130D01*
X197845Y1391963D01*
X198012Y1391713D01*
X198054Y1391422D01*
X198012Y1391172D01*
X197845Y1390922D01*
X197595Y1390713D01*
X197304Y1390630D01*
X196970Y1390713D01*
X196679Y1390963D01*
X196512Y1391338D01*
X196470Y1391755D01*
X196554Y1392297D01*
X196679Y1392588D01*
X196887Y1392880D01*
X197179Y1393088D01*
X197470Y1393130D01*
X197762Y1393047D01*
X197970Y1392838D01*
G01X187129Y1386630D02*
Y1389130D01*
X188170D01*
X188504Y1389005D01*
X188712Y1388838D01*
X188795Y1388505D01*
X188712Y1388172D01*
X188462Y1387963D01*
X188170Y1387838D01*
X187129D01*
G01X188170D02*
X188795Y1386630D01*
G01X191062D02*
Y1389130D01*
X190562Y1388630D01*
G01Y1386630D02*
X191562D01*
G01X194162D02*
X194454Y1386672D01*
X194787Y1386797D01*
X194995Y1387005D01*
X195079Y1387297D01*
X194995Y1387588D01*
X194745Y1387838D01*
X194370Y1387963D01*
X193954D01*
X193704Y1388047D01*
X193495Y1388255D01*
X193412Y1388547D01*
X193537Y1388838D01*
X193829Y1389047D01*
X194162Y1389130D01*
X194495Y1389047D01*
X194787Y1388838D01*
X194912Y1388547D01*
X194829Y1388255D01*
X194620Y1388047D01*
X194370Y1387963D01*
X193954D01*
X193579Y1387838D01*
X193329Y1387588D01*
X193245Y1387297D01*
X193329Y1387005D01*
X193537Y1386797D01*
X193870Y1386672D01*
X194162Y1386630D01*
G01X197262D02*
X197554Y1386672D01*
X197887Y1386797D01*
X198095Y1387005D01*
X198179Y1387297D01*
X198095Y1387588D01*
X197845Y1387838D01*
X197470Y1387963D01*
X197054D01*
X196804Y1388047D01*
X196595Y1388255D01*
X196512Y1388547D01*
X196637Y1388838D01*
X196929Y1389047D01*
X197262Y1389130D01*
X197595Y1389047D01*
X197887Y1388838D01*
X198012Y1388547D01*
X197929Y1388255D01*
X197720Y1388047D01*
X197470Y1387963D01*
X197054D01*
X196679Y1387838D01*
X196429Y1387588D01*
X196345Y1387297D01*
X196429Y1387005D01*
X196637Y1386797D01*
X196970Y1386672D01*
X197262Y1386630D01*
G01X174482Y1620050D02*
Y1618258D01*
X174649Y1617883D01*
X174982Y1617633D01*
X175399Y1617550D01*
X175816Y1617633D01*
X176149Y1617883D01*
X176316Y1618258D01*
Y1620050D01*
G01X177582Y1618050D02*
X177832Y1617758D01*
X178166Y1617592D01*
X178541Y1617550D01*
X178874Y1617592D01*
X179207Y1617800D01*
X179416Y1618050D01*
X179457Y1618300D01*
X179374Y1618592D01*
X179082Y1618800D01*
X178791Y1618883D01*
X178416D01*
G01X178791D02*
X179041Y1619008D01*
X179249Y1619217D01*
X179332Y1619467D01*
X179249Y1619717D01*
X179041Y1619925D01*
X178666Y1620050D01*
X178291Y1620008D01*
X177916Y1619842D01*
G01X180807Y1619633D02*
X181057Y1619883D01*
X181349Y1620008D01*
X181682Y1620050D01*
X182099Y1619967D01*
X182391Y1619758D01*
X182474Y1619508D01*
X182432Y1619258D01*
X182266Y1619050D01*
X181432Y1618633D01*
X181057Y1618342D01*
X180807Y1617925D01*
X180724Y1617550D01*
X182474D01*
G01X176499Y1622313D02*
X178499Y1624313D01*
X180499Y1622313D01*
G01X184099D02*
Y1641513D01*
X172899D01*
Y1622313D01*
X184099D01*
G01X187000Y1658850D02*
X186958Y1658517D01*
X186792Y1658225D01*
X186542Y1657975D01*
X186250Y1657808D01*
X185917Y1657725D01*
X185583D01*
X185250Y1657808D01*
X184958Y1657975D01*
X184708Y1658225D01*
X184542Y1658517D01*
X184500Y1658850D01*
X184542Y1659183D01*
X184708Y1659475D01*
X184958Y1659725D01*
X185250Y1659892D01*
X185583Y1659975D01*
X185917D01*
X186250Y1659892D01*
X186542Y1659725D01*
X186792Y1659475D01*
X186958Y1659183D01*
X187000Y1658850D01*
G01X186333Y1659183D02*
X187000Y1659683D01*
G01X184917Y1661158D02*
X184667Y1661408D01*
X184542Y1661700D01*
X184500Y1662033D01*
X184583Y1662450D01*
X184792Y1662742D01*
X185042Y1662825D01*
X185292Y1662783D01*
X185500Y1662617D01*
X185917Y1661783D01*
X186208Y1661408D01*
X186625Y1661158D01*
X187000Y1661075D01*
Y1662825D01*
G01X184917Y1664258D02*
X184667Y1664508D01*
X184542Y1664800D01*
X184500Y1665133D01*
X184583Y1665550D01*
X184792Y1665842D01*
X185042Y1665925D01*
X185292Y1665883D01*
X185500Y1665717D01*
X185917Y1664883D01*
X186208Y1664508D01*
X186625Y1664258D01*
X187000Y1664175D01*
Y1665925D01*
G01X176999Y1656127D02*
Y1644727D01*
G01X190399Y1656127D02*
X176999D01*
G01Y1644727D02*
X190399D01*
G01X183000Y1658017D02*
X180500D01*
Y1659058D01*
X180625Y1659392D01*
X180792Y1659600D01*
X181125Y1659683D01*
X181458Y1659600D01*
X181667Y1659350D01*
X181792Y1659058D01*
Y1658017D01*
G01Y1659058D02*
X183000Y1659683D01*
G01X180917Y1661158D02*
X180667Y1661408D01*
X180542Y1661700D01*
X180500Y1662033D01*
X180583Y1662450D01*
X180792Y1662742D01*
X181042Y1662825D01*
X181292Y1662783D01*
X181500Y1662617D01*
X181917Y1661783D01*
X182208Y1661408D01*
X182625Y1661158D01*
X183000Y1661075D01*
Y1662825D01*
G01X182625Y1664133D02*
X182833Y1664383D01*
X182958Y1664675D01*
X183000Y1665050D01*
X182917Y1665425D01*
X182750Y1665717D01*
X182458Y1665925D01*
X182125Y1665967D01*
X181792Y1665883D01*
X181583Y1665675D01*
X181417Y1665383D01*
X181375Y1665092D01*
X181417Y1664800D01*
X181583Y1664425D01*
X180500Y1664550D01*
Y1665675D01*
G01X180917Y1667358D02*
X180667Y1667608D01*
X180542Y1667900D01*
X180500Y1668233D01*
X180583Y1668650D01*
X180792Y1668942D01*
X181042Y1669025D01*
X181292Y1668983D01*
X181500Y1668817D01*
X181917Y1667983D01*
X182208Y1667608D01*
X182625Y1667358D01*
X183000Y1667275D01*
Y1669025D01*
G01X176499Y1655063D02*
X172499D01*
Y1647663D01*
G01X185000Y1678400D02*
X184958Y1678067D01*
X184792Y1677775D01*
X184542Y1677525D01*
X184250Y1677358D01*
X183917Y1677275D01*
X183583D01*
X183250Y1677358D01*
X182958Y1677525D01*
X182708Y1677775D01*
X182542Y1678067D01*
X182500Y1678400D01*
X182542Y1678733D01*
X182708Y1679025D01*
X182958Y1679275D01*
X183250Y1679442D01*
X183583Y1679525D01*
X183917D01*
X184250Y1679442D01*
X184542Y1679275D01*
X184792Y1679025D01*
X184958Y1678733D01*
X185000Y1678400D01*
G01X184333Y1678733D02*
X185000Y1679233D01*
G01X183958Y1680708D02*
X183667Y1681000D01*
X183500Y1681250D01*
X183417Y1681583D01*
X183500Y1681875D01*
X183667Y1682083D01*
X183917Y1682250D01*
X184208Y1682292D01*
X184458Y1682250D01*
X184708Y1682083D01*
X184917Y1681833D01*
X185000Y1681542D01*
X184917Y1681208D01*
X184667Y1680917D01*
X184292Y1680750D01*
X183875Y1680708D01*
X183333Y1680792D01*
X183042Y1680917D01*
X182750Y1681125D01*
X182542Y1681417D01*
X182500Y1681708D01*
X182583Y1682000D01*
X182792Y1682208D01*
G01X183958Y1683808D02*
X183667Y1684100D01*
X183500Y1684350D01*
X183417Y1684683D01*
X183500Y1684975D01*
X183667Y1685183D01*
X183917Y1685350D01*
X184208Y1685392D01*
X184458Y1685350D01*
X184708Y1685183D01*
X184917Y1684933D01*
X185000Y1684642D01*
X184917Y1684308D01*
X184667Y1684017D01*
X184292Y1683850D01*
X183875Y1683808D01*
X183333Y1683892D01*
X183042Y1684017D01*
X182750Y1684225D01*
X182542Y1684517D01*
X182500Y1684808D01*
X182583Y1685100D01*
X182792Y1685308D01*
G01X169100Y1675400D02*
X180500D01*
G01X169100Y1688800D02*
Y1675400D01*
G01X180500D02*
Y1688800D01*
G01X168200Y1678800D02*
Y1692800D01*
G01X180500Y1688800D02*
X169100D01*
G01X178517Y1691500D02*
Y1694000D01*
X179558D01*
X179892Y1693875D01*
X180100Y1693708D01*
X180183Y1693375D01*
X180100Y1693042D01*
X179850Y1692833D01*
X179558Y1692708D01*
X178517D01*
G01X179558D02*
X180183Y1691500D01*
G01X181533Y1692000D02*
X181783Y1691708D01*
X182117Y1691542D01*
X182492Y1691500D01*
X182825Y1691542D01*
X183158Y1691750D01*
X183367Y1692000D01*
X183408Y1692250D01*
X183325Y1692542D01*
X183033Y1692750D01*
X182742Y1692833D01*
X182367D01*
G01X182742D02*
X182992Y1692958D01*
X183200Y1693167D01*
X183283Y1693417D01*
X183200Y1693667D01*
X182992Y1693875D01*
X182617Y1694000D01*
X182242Y1693958D01*
X181867Y1693792D01*
G01X184842Y1691792D02*
X185133Y1691583D01*
X185467Y1691500D01*
X185800Y1691583D01*
X186092Y1691833D01*
X186300Y1692208D01*
X186383Y1692583D01*
Y1693042D01*
X186300Y1693417D01*
X186092Y1693750D01*
X185842Y1693917D01*
X185550Y1694000D01*
X185217Y1693917D01*
X184967Y1693750D01*
X184800Y1693500D01*
X184717Y1693167D01*
X184800Y1692875D01*
X185008Y1692583D01*
X185258Y1692417D01*
X185550Y1692375D01*
X185883Y1692458D01*
X186133Y1692667D01*
X186383Y1693042D01*
G01X188567Y1691500D02*
X188650Y1692042D01*
X188775Y1692500D01*
X188942Y1692917D01*
X189150Y1693375D01*
X189483Y1694000D01*
X187817D01*
G01X176200Y1689200D02*
Y1693200D01*
X168800D01*
G01X178900Y1715500D02*
X178567Y1715542D01*
X178275Y1715708D01*
X178025Y1715958D01*
X177858Y1716250D01*
X177775Y1716583D01*
Y1716917D01*
X177858Y1717250D01*
X178025Y1717542D01*
X178275Y1717792D01*
X178567Y1717958D01*
X178900Y1718000D01*
X179233Y1717958D01*
X179525Y1717792D01*
X179775Y1717542D01*
X179942Y1717250D01*
X180025Y1716917D01*
Y1716583D01*
X179942Y1716250D01*
X179775Y1715958D01*
X179525Y1715708D01*
X179233Y1715542D01*
X178900Y1715500D01*
G01X179233Y1716167D02*
X179733Y1715500D01*
G01X181208Y1717583D02*
X181458Y1717833D01*
X181750Y1717958D01*
X182083Y1718000D01*
X182500Y1717917D01*
X182792Y1717708D01*
X182875Y1717458D01*
X182833Y1717208D01*
X182667Y1717000D01*
X181833Y1716583D01*
X181458Y1716292D01*
X181208Y1715875D01*
X181125Y1715500D01*
X182875D01*
G01X185100D02*
Y1718000D01*
X184600Y1717500D01*
G01Y1715500D02*
X185600D01*
G01X178516Y1766050D02*
Y1768550D01*
X179557D01*
X179891Y1768425D01*
X180099Y1768258D01*
X180182Y1767925D01*
X180099Y1767592D01*
X179849Y1767383D01*
X179557Y1767258D01*
X178516D01*
G01X179557D02*
X180182Y1766050D01*
G01X182949D02*
Y1768550D01*
X181407Y1766758D01*
X183491D01*
G01X184841Y1766342D02*
X185132Y1766133D01*
X185466Y1766050D01*
X185799Y1766133D01*
X186091Y1766383D01*
X186299Y1766758D01*
X186382Y1767133D01*
Y1767592D01*
X186299Y1767967D01*
X186091Y1768300D01*
X185841Y1768467D01*
X185549Y1768550D01*
X185216Y1768467D01*
X184966Y1768300D01*
X184799Y1768050D01*
X184716Y1767717D01*
X184799Y1767425D01*
X185007Y1767133D01*
X185257Y1766967D01*
X185549Y1766925D01*
X185882Y1767008D01*
X186132Y1767217D01*
X186382Y1767592D01*
G01X187732Y1766550D02*
X187982Y1766258D01*
X188316Y1766092D01*
X188691Y1766050D01*
X189024Y1766092D01*
X189357Y1766300D01*
X189566Y1766550D01*
X189607Y1766800D01*
X189524Y1767092D01*
X189232Y1767300D01*
X188941Y1767383D01*
X188566D01*
G01X188941D02*
X189191Y1767508D01*
X189399Y1767717D01*
X189482Y1767967D01*
X189399Y1768217D01*
X189191Y1768425D01*
X188816Y1768550D01*
X188441Y1768508D01*
X188066Y1768342D01*
G01X175364Y1788613D02*
Y1784613D01*
X182764D01*
G01X175364D02*
Y1780613D01*
X182764D01*
G01X175364D02*
Y1776613D01*
X182764D01*
G01X188099Y1771200D02*
Y1775200D01*
X180699D01*
G01X183299Y1776000D02*
X197299D01*
G01X183299Y1789000D02*
Y1776000D01*
G01X179581Y1801113D02*
Y1803613D01*
X180622D01*
X180956Y1803488D01*
X181164Y1803321D01*
X181247Y1802988D01*
X181164Y1802655D01*
X180914Y1802446D01*
X180622Y1802321D01*
X179581D01*
G01X180622D02*
X181247Y1801113D01*
G01X183514D02*
Y1803613D01*
X183014Y1803113D01*
G01Y1801113D02*
X184014D01*
G01X186531D02*
X186614Y1801655D01*
X186739Y1802113D01*
X186906Y1802530D01*
X187114Y1802988D01*
X187447Y1803613D01*
X185781D01*
G01X189714D02*
X189381Y1803530D01*
X189131Y1803321D01*
X188964Y1803071D01*
X188839Y1802738D01*
X188797Y1802363D01*
X188839Y1801988D01*
X188964Y1801655D01*
X189131Y1801405D01*
X189381Y1801196D01*
X189714Y1801113D01*
X190047Y1801196D01*
X190297Y1801405D01*
X190464Y1801655D01*
X190589Y1801988D01*
X190631Y1802363D01*
X190589Y1802738D01*
X190464Y1803071D01*
X190297Y1803321D01*
X190047Y1803530D01*
X189714Y1803613D01*
G01X179581Y1797113D02*
Y1799613D01*
X180622D01*
X180956Y1799488D01*
X181164Y1799321D01*
X181247Y1798988D01*
X181164Y1798655D01*
X180914Y1798446D01*
X180622Y1798321D01*
X179581D01*
G01X180622D02*
X181247Y1797113D01*
G01X183514D02*
Y1799613D01*
X183014Y1799113D01*
G01Y1797113D02*
X184014D01*
G01X186531D02*
X186614Y1797655D01*
X186739Y1798113D01*
X186906Y1798530D01*
X187114Y1798988D01*
X187447Y1799613D01*
X185781D01*
G01X188922Y1799196D02*
X189172Y1799446D01*
X189464Y1799571D01*
X189797Y1799613D01*
X190214Y1799530D01*
X190506Y1799321D01*
X190589Y1799071D01*
X190547Y1798821D01*
X190381Y1798613D01*
X189547Y1798196D01*
X189172Y1797905D01*
X188922Y1797488D01*
X188839Y1797113D01*
X190589D01*
G01X179581Y1793113D02*
Y1795613D01*
X180622D01*
X180956Y1795488D01*
X181164Y1795321D01*
X181247Y1794988D01*
X181164Y1794655D01*
X180914Y1794446D01*
X180622Y1794321D01*
X179581D01*
G01X180622D02*
X181247Y1793113D01*
G01X183514D02*
Y1795613D01*
X183014Y1795113D01*
G01Y1793113D02*
X184014D01*
G01X186531D02*
X186614Y1793655D01*
X186739Y1794113D01*
X186906Y1794530D01*
X187114Y1794988D01*
X187447Y1795613D01*
X185781D01*
G01X190214Y1793113D02*
Y1795613D01*
X188672Y1793821D01*
X190756D01*
G01X197299Y1789000D02*
X183299D01*
G01X209066Y30050D02*
Y32550D01*
X210066D01*
X210399Y32425D01*
X210649Y32133D01*
X210732Y31800D01*
X210649Y31467D01*
X210441Y31217D01*
X210066Y31092D01*
X209066D01*
G01X212166Y32550D02*
Y30050D01*
X213832D01*
G01X215182Y30550D02*
X215432Y30258D01*
X215766Y30092D01*
X216141Y30050D01*
X216474Y30092D01*
X216807Y30300D01*
X217016Y30550D01*
X217057Y30800D01*
X216974Y31092D01*
X216682Y31300D01*
X216391Y31383D01*
X216016D01*
G01X216391D02*
X216641Y31508D01*
X216849Y31717D01*
X216932Y31967D01*
X216849Y32217D01*
X216641Y32425D01*
X216266Y32550D01*
X215891Y32508D01*
X215516Y32342D01*
G01X202699Y34450D02*
X225299D01*
G01X202699Y44650D02*
Y34450D01*
G01X225299Y44650D02*
X202699D01*
G01Y34450D02*
X225299D01*
G01X202699Y44650D02*
Y34450D01*
G01X225299Y44650D02*
X202699D01*
G01X206066Y53550D02*
Y56050D01*
X207066D01*
X207399Y55925D01*
X207649Y55633D01*
X207732Y55300D01*
X207649Y54967D01*
X207441Y54717D01*
X207066Y54592D01*
X206066D01*
G01X209082Y56050D02*
Y54258D01*
X209249Y53883D01*
X209582Y53633D01*
X209999Y53550D01*
X210416Y53633D01*
X210749Y53883D01*
X210916Y54258D01*
Y56050D01*
G01X212307Y55633D02*
X212557Y55883D01*
X212849Y56008D01*
X213182Y56050D01*
X213599Y55967D01*
X213891Y55758D01*
X213974Y55508D01*
X213932Y55258D01*
X213766Y55050D01*
X212932Y54633D01*
X212557Y54342D01*
X212307Y53925D01*
X212224Y53550D01*
X213974D01*
G01X196826Y63528D02*
Y58528D01*
X201826D01*
G01X197833Y64654D02*
X194833D01*
G01X190380Y93913D02*
X192880D01*
G01X190380Y92955D02*
Y94871D01*
G01X192880Y96180D02*
X190380D01*
Y97180D01*
X190505Y97513D01*
X190797Y97763D01*
X191130Y97846D01*
X191463Y97763D01*
X191713Y97555D01*
X191838Y97180D01*
Y96180D01*
G01X190797Y99321D02*
X190547Y99571D01*
X190422Y99863D01*
X190380Y100196D01*
X190463Y100613D01*
X190672Y100905D01*
X190922Y100988D01*
X191172Y100946D01*
X191380Y100780D01*
X191797Y99946D01*
X192088Y99571D01*
X192505Y99321D01*
X192880Y99238D01*
Y100988D01*
G01X192380Y102296D02*
X192672Y102546D01*
X192838Y102880D01*
X192880Y103255D01*
X192838Y103588D01*
X192630Y103921D01*
X192380Y104130D01*
X192130Y104171D01*
X191838Y104088D01*
X191630Y103796D01*
X191547Y103505D01*
Y103130D01*
G01Y103505D02*
X191422Y103755D01*
X191213Y103963D01*
X190963Y104046D01*
X190713Y103963D01*
X190505Y103755D01*
X190380Y103380D01*
X190422Y103005D01*
X190588Y102630D01*
G01X197833Y74497D02*
X195833D01*
G01X202499Y105567D02*
X199999D01*
Y106567D01*
X200124Y106900D01*
X200416Y107150D01*
X200749Y107233D01*
X201082Y107150D01*
X201332Y106942D01*
X201457Y106567D01*
Y105567D01*
G01X202499Y108667D02*
X199999D01*
Y109708D01*
X200124Y110042D01*
X200291Y110250D01*
X200624Y110333D01*
X200957Y110250D01*
X201166Y110000D01*
X201291Y109708D01*
Y108667D01*
G01Y109708D02*
X202499Y110333D01*
G01Y112600D02*
X199999D01*
X200499Y112100D01*
G01X202499D02*
Y113100D01*
G01Y115617D02*
X201957Y115700D01*
X201499Y115825D01*
X201082Y115992D01*
X200624Y116200D01*
X199999Y116533D01*
Y114867D01*
G01X199499Y95850D02*
X203499D01*
Y103250D01*
G01X198499Y105567D02*
X195999D01*
Y106567D01*
X196124Y106900D01*
X196416Y107150D01*
X196749Y107233D01*
X197082Y107150D01*
X197332Y106942D01*
X197457Y106567D01*
Y105567D01*
G01X198499Y108667D02*
X195999D01*
Y109708D01*
X196124Y110042D01*
X196291Y110250D01*
X196624Y110333D01*
X196957Y110250D01*
X197166Y110000D01*
X197291Y109708D01*
Y108667D01*
G01Y109708D02*
X198499Y110333D01*
G01X196416Y111808D02*
X196166Y112058D01*
X196041Y112350D01*
X195999Y112683D01*
X196082Y113100D01*
X196291Y113392D01*
X196541Y113475D01*
X196791Y113433D01*
X196999Y113267D01*
X197416Y112433D01*
X197707Y112058D01*
X198124Y111808D01*
X198499Y111725D01*
Y113475D01*
G01X197999Y114783D02*
X198291Y115033D01*
X198457Y115367D01*
X198499Y115742D01*
X198457Y116075D01*
X198249Y116408D01*
X197999Y116617D01*
X197749Y116658D01*
X197457Y116575D01*
X197249Y116283D01*
X197166Y115992D01*
Y115617D01*
G01Y115992D02*
X197041Y116242D01*
X196832Y116450D01*
X196582Y116533D01*
X196332Y116450D01*
X196124Y116242D01*
X195999Y115867D01*
X196041Y115492D01*
X196207Y115117D01*
G01X199499Y103250D02*
X195499D01*
Y95850D01*
G01X206499Y105567D02*
X203999D01*
Y106567D01*
X204124Y106900D01*
X204416Y107150D01*
X204749Y107233D01*
X205082Y107150D01*
X205332Y106942D01*
X205457Y106567D01*
Y105567D01*
G01X206499Y108667D02*
X203999D01*
Y109708D01*
X204124Y110042D01*
X204291Y110250D01*
X204624Y110333D01*
X204957Y110250D01*
X205166Y110000D01*
X205291Y109708D01*
Y108667D01*
G01Y109708D02*
X206499Y110333D01*
G01X204416Y111808D02*
X204166Y112058D01*
X204041Y112350D01*
X203999Y112683D01*
X204082Y113100D01*
X204291Y113392D01*
X204541Y113475D01*
X204791Y113433D01*
X204999Y113267D01*
X205416Y112433D01*
X205707Y112058D01*
X206124Y111808D01*
X206499Y111725D01*
Y113475D01*
G01X206124Y114783D02*
X206332Y115033D01*
X206457Y115325D01*
X206499Y115700D01*
X206416Y116075D01*
X206249Y116367D01*
X205957Y116575D01*
X205624Y116617D01*
X205291Y116533D01*
X205082Y116325D01*
X204916Y116033D01*
X204874Y115742D01*
X204916Y115450D01*
X205082Y115075D01*
X203999Y115200D01*
Y116325D01*
G01X207499Y103250D02*
X203499D01*
Y95850D01*
G01X210499Y105567D02*
X207999D01*
Y106567D01*
X208124Y106900D01*
X208416Y107150D01*
X208749Y107233D01*
X209082Y107150D01*
X209332Y106942D01*
X209457Y106567D01*
Y105567D01*
G01X210499Y108667D02*
X207999D01*
Y109708D01*
X208124Y110042D01*
X208291Y110250D01*
X208624Y110333D01*
X208957Y110250D01*
X209166Y110000D01*
X209291Y109708D01*
Y108667D01*
G01Y109708D02*
X210499Y110333D01*
G01X208416Y111808D02*
X208166Y112058D01*
X208041Y112350D01*
X207999Y112683D01*
X208082Y113100D01*
X208291Y113392D01*
X208541Y113475D01*
X208791Y113433D01*
X208999Y113267D01*
X209416Y112433D01*
X209707Y112058D01*
X210124Y111808D01*
X210499Y111725D01*
Y113475D01*
G01Y115617D02*
X209957Y115700D01*
X209499Y115825D01*
X209082Y115992D01*
X208624Y116200D01*
X207999Y116533D01*
Y114867D01*
G01X207499Y95850D02*
X211499D01*
Y103250D01*
G01X206499Y158450D02*
X206457Y158117D01*
X206291Y157825D01*
X206041Y157575D01*
X205749Y157408D01*
X205416Y157325D01*
X205082D01*
X204749Y157408D01*
X204457Y157575D01*
X204207Y157825D01*
X204041Y158117D01*
X203999Y158450D01*
X204041Y158783D01*
X204207Y159075D01*
X204457Y159325D01*
X204749Y159492D01*
X205082Y159575D01*
X205416D01*
X205749Y159492D01*
X206041Y159325D01*
X206291Y159075D01*
X206457Y158783D01*
X206499Y158450D01*
G01X205832Y158783D02*
X206499Y159283D01*
G01Y162050D02*
X203999D01*
X205791Y160508D01*
Y162592D01*
G01X205999Y163733D02*
X206291Y163983D01*
X206457Y164317D01*
X206499Y164692D01*
X206457Y165025D01*
X206249Y165358D01*
X205999Y165567D01*
X205749Y165608D01*
X205457Y165525D01*
X205249Y165233D01*
X205166Y164942D01*
Y164567D01*
G01Y164942D02*
X205041Y165192D01*
X204832Y165400D01*
X204582Y165483D01*
X204332Y165400D01*
X204124Y165192D01*
X203999Y164817D01*
X204041Y164442D01*
X204207Y164067D01*
G01X196799Y154700D02*
Y167700D01*
G01X211965Y242750D02*
X221965D01*
G01Y235750D02*
X211965D01*
G01X216965D02*
Y242750D01*
G01X211965Y232317D02*
X221965D01*
Y228983D01*
X221465Y227650D01*
X220798Y226650D01*
X219798Y225817D01*
X218631Y225150D01*
X216965Y224983D01*
X215298Y225150D01*
X214132Y225817D01*
X213131Y226650D01*
X212465Y227650D01*
X211965Y228983D01*
Y232317D01*
G01Y221717D02*
X221965D01*
Y218383D01*
X221465Y217050D01*
X220798Y216050D01*
X219798Y215217D01*
X218631Y214550D01*
X216965Y214383D01*
X215298Y214550D01*
X214132Y215217D01*
X213131Y216050D01*
X212465Y217050D01*
X211965Y218383D01*
Y221717D01*
G01X213131Y210283D02*
X212298Y209117D01*
X211965Y207783D01*
X212298Y206450D01*
X213298Y205283D01*
X214798Y204450D01*
X216298Y204117D01*
X218132D01*
X219632Y204450D01*
X220965Y205283D01*
X221632Y206283D01*
X221965Y207450D01*
X221632Y208784D01*
X220965Y209783D01*
X219965Y210450D01*
X218631Y210783D01*
X217465Y210450D01*
X216298Y209617D01*
X215631Y208617D01*
X215465Y207450D01*
X215798Y206117D01*
X216632Y205117D01*
X218132Y204117D01*
G01X201517Y299500D02*
Y302000D01*
X202558D01*
X202892Y301875D01*
X203100Y301708D01*
X203183Y301375D01*
X203100Y301042D01*
X202850Y300833D01*
X202558Y300708D01*
X201517D01*
G01X202558D02*
X203183Y299500D01*
G01X204658Y301583D02*
X204908Y301833D01*
X205200Y301958D01*
X205533Y302000D01*
X205950Y301917D01*
X206242Y301708D01*
X206325Y301458D01*
X206283Y301208D01*
X206117Y301000D01*
X205283Y300583D01*
X204908Y300292D01*
X204658Y299875D01*
X204575Y299500D01*
X206325D01*
G01X207633Y300000D02*
X207883Y299708D01*
X208217Y299542D01*
X208592Y299500D01*
X208925Y299542D01*
X209258Y299750D01*
X209467Y300000D01*
X209508Y300250D01*
X209425Y300542D01*
X209133Y300750D01*
X208842Y300833D01*
X208467D01*
G01X208842D02*
X209092Y300958D01*
X209300Y301167D01*
X209383Y301417D01*
X209300Y301667D01*
X209092Y301875D01*
X208717Y302000D01*
X208342Y301958D01*
X207967Y301792D01*
G01X212150Y299500D02*
Y302000D01*
X210608Y300208D01*
X212692D01*
G01X206708Y312267D02*
X206583Y312017D01*
X206500Y311725D01*
Y311392D01*
X206625Y311017D01*
X206833Y310725D01*
X207083Y310517D01*
X207500Y310350D01*
X207875Y310308D01*
X208250Y310392D01*
X208500Y310517D01*
X208750Y310767D01*
X208917Y311058D01*
X209000Y311350D01*
Y311642D01*
X208917Y311933D01*
X208792Y312183D01*
X208625Y312392D01*
G01X206917Y313658D02*
X206667Y313908D01*
X206542Y314200D01*
X206500Y314533D01*
X206583Y314950D01*
X206792Y315242D01*
X207042Y315325D01*
X207292Y315283D01*
X207500Y315117D01*
X207917Y314283D01*
X208208Y313908D01*
X208625Y313658D01*
X209000Y313575D01*
Y315325D01*
G01X208625Y316633D02*
X208833Y316883D01*
X208958Y317175D01*
X209000Y317550D01*
X208917Y317925D01*
X208750Y318217D01*
X208458Y318425D01*
X208125Y318467D01*
X207792Y318383D01*
X207583Y318175D01*
X207417Y317883D01*
X207375Y317592D01*
X207417Y317300D01*
X207583Y316925D01*
X206500Y317050D01*
Y318175D01*
G01Y320650D02*
X206583Y320317D01*
X206792Y320067D01*
X207042Y319900D01*
X207375Y319775D01*
X207750Y319733D01*
X208125Y319775D01*
X208458Y319900D01*
X208708Y320067D01*
X208917Y320317D01*
X209000Y320650D01*
X208917Y320983D01*
X208708Y321233D01*
X208458Y321400D01*
X208125Y321525D01*
X207750Y321567D01*
X207375Y321525D01*
X207042Y321400D01*
X206792Y321233D01*
X206583Y320983D01*
X206500Y320650D01*
G01X203195Y331051D02*
Y333551D01*
X204236D01*
X204570Y333426D01*
X204778Y333259D01*
X204861Y332926D01*
X204778Y332593D01*
X204528Y332384D01*
X204236Y332259D01*
X203195D01*
G01X204236D02*
X204861Y331051D01*
G01X206336Y333134D02*
X206586Y333384D01*
X206878Y333509D01*
X207211Y333551D01*
X207628Y333468D01*
X207920Y333259D01*
X208003Y333009D01*
X207961Y332759D01*
X207795Y332551D01*
X206961Y332134D01*
X206586Y331843D01*
X206336Y331426D01*
X206253Y331051D01*
X208003D01*
G01X209311Y331551D02*
X209561Y331259D01*
X209895Y331093D01*
X210270Y331051D01*
X210603Y331093D01*
X210936Y331301D01*
X211145Y331551D01*
X211186Y331801D01*
X211103Y332093D01*
X210811Y332301D01*
X210520Y332384D01*
X210145D01*
G01X210520D02*
X210770Y332509D01*
X210978Y332718D01*
X211061Y332968D01*
X210978Y333218D01*
X210770Y333426D01*
X210395Y333551D01*
X210020Y333509D01*
X209645Y333343D01*
G01X212536Y332093D02*
X212828Y332384D01*
X213078Y332551D01*
X213411Y332634D01*
X213703Y332551D01*
X213911Y332384D01*
X214078Y332134D01*
X214120Y331843D01*
X214078Y331593D01*
X213911Y331343D01*
X213661Y331134D01*
X213370Y331051D01*
X213036Y331134D01*
X212745Y331384D01*
X212578Y331759D01*
X212536Y332176D01*
X212620Y332718D01*
X212745Y333009D01*
X212953Y333301D01*
X213245Y333509D01*
X213536Y333551D01*
X213828Y333468D01*
X214036Y333259D01*
G01X200499Y433033D02*
X202291D01*
X202666Y433200D01*
X202916Y433533D01*
X202999Y433950D01*
X202916Y434367D01*
X202666Y434700D01*
X202291Y434867D01*
X200499D01*
G01X202999Y437550D02*
X200499D01*
X202291Y436008D01*
Y438092D01*
G01X202999Y440150D02*
X200499D01*
X200999Y439650D01*
G01X202999D02*
Y440650D01*
G01X196800Y474000D02*
Y482000D01*
G01X206708Y495267D02*
X206583Y495017D01*
X206500Y494725D01*
Y494392D01*
X206625Y494017D01*
X206833Y493725D01*
X207083Y493517D01*
X207500Y493350D01*
X207875Y493308D01*
X208250Y493392D01*
X208500Y493517D01*
X208750Y493767D01*
X208917Y494058D01*
X209000Y494350D01*
Y494642D01*
X208917Y494933D01*
X208792Y495183D01*
X208625Y495392D01*
G01X208500Y496533D02*
X208792Y496783D01*
X208958Y497117D01*
X209000Y497492D01*
X208958Y497825D01*
X208750Y498158D01*
X208500Y498367D01*
X208250Y498408D01*
X207958Y498325D01*
X207750Y498033D01*
X207667Y497742D01*
Y497367D01*
G01Y497742D02*
X207542Y497992D01*
X207333Y498200D01*
X207083Y498283D01*
X206833Y498200D01*
X206625Y497992D01*
X206500Y497617D01*
X206542Y497242D01*
X206708Y496867D01*
G01X206500Y500550D02*
X206583Y500217D01*
X206792Y499967D01*
X207042Y499800D01*
X207375Y499675D01*
X207750Y499633D01*
X208125Y499675D01*
X208458Y499800D01*
X208708Y499967D01*
X208917Y500217D01*
X209000Y500550D01*
X208917Y500883D01*
X208708Y501133D01*
X208458Y501300D01*
X208125Y501425D01*
X207750Y501467D01*
X207375Y501425D01*
X207042Y501300D01*
X206792Y501133D01*
X206583Y500883D01*
X206500Y500550D01*
G01X208708Y502942D02*
X208917Y503233D01*
X209000Y503567D01*
X208917Y503900D01*
X208667Y504192D01*
X208292Y504400D01*
X207917Y504483D01*
X207458D01*
X207083Y504400D01*
X206750Y504192D01*
X206583Y503942D01*
X206500Y503650D01*
X206583Y503317D01*
X206750Y503067D01*
X207000Y502900D01*
X207333Y502817D01*
X207625Y502900D01*
X207917Y503108D01*
X208083Y503358D01*
X208125Y503650D01*
X208042Y503983D01*
X207833Y504233D01*
X207458Y504483D01*
G01X204500Y494017D02*
X202000D01*
Y495058D01*
X202125Y495392D01*
X202292Y495600D01*
X202625Y495683D01*
X202958Y495600D01*
X203167Y495350D01*
X203292Y495058D01*
Y494017D01*
G01Y495058D02*
X204500Y495683D01*
G01X204125Y497033D02*
X204333Y497283D01*
X204458Y497575D01*
X204500Y497950D01*
X204417Y498325D01*
X204250Y498617D01*
X203958Y498825D01*
X203625Y498867D01*
X203292Y498783D01*
X203083Y498575D01*
X202917Y498283D01*
X202875Y497992D01*
X202917Y497700D01*
X203083Y497325D01*
X202000Y497450D01*
Y498575D01*
G01Y501050D02*
X202083Y500717D01*
X202292Y500467D01*
X202542Y500300D01*
X202875Y500175D01*
X203250Y500133D01*
X203625Y500175D01*
X203958Y500300D01*
X204208Y500467D01*
X204417Y500717D01*
X204500Y501050D01*
X204417Y501383D01*
X204208Y501633D01*
X203958Y501800D01*
X203625Y501925D01*
X203250Y501967D01*
X202875Y501925D01*
X202542Y501800D01*
X202292Y501633D01*
X202083Y501383D01*
X202000Y501050D01*
G01X203458Y503358D02*
X203167Y503650D01*
X203000Y503900D01*
X202917Y504233D01*
X203000Y504525D01*
X203167Y504733D01*
X203417Y504900D01*
X203708Y504942D01*
X203958Y504900D01*
X204208Y504733D01*
X204417Y504483D01*
X204500Y504192D01*
X204417Y503858D01*
X204167Y503567D01*
X203792Y503400D01*
X203375Y503358D01*
X202833Y503442D01*
X202542Y503567D01*
X202250Y503775D01*
X202042Y504067D01*
X202000Y504358D01*
X202083Y504650D01*
X202292Y504858D01*
G01X200500Y494017D02*
X198000D01*
Y495058D01*
X198125Y495392D01*
X198292Y495600D01*
X198625Y495683D01*
X198958Y495600D01*
X199167Y495350D01*
X199292Y495058D01*
Y494017D01*
G01Y495058D02*
X200500Y495683D01*
G01X200125Y497033D02*
X200333Y497283D01*
X200458Y497575D01*
X200500Y497950D01*
X200417Y498325D01*
X200250Y498617D01*
X199958Y498825D01*
X199625Y498867D01*
X199292Y498783D01*
X199083Y498575D01*
X198917Y498283D01*
X198875Y497992D01*
X198917Y497700D01*
X199083Y497325D01*
X198000Y497450D01*
Y498575D01*
G01Y501050D02*
X198083Y500717D01*
X198292Y500467D01*
X198542Y500300D01*
X198875Y500175D01*
X199250Y500133D01*
X199625Y500175D01*
X199958Y500300D01*
X200208Y500467D01*
X200417Y500717D01*
X200500Y501050D01*
X200417Y501383D01*
X200208Y501633D01*
X199958Y501800D01*
X199625Y501925D01*
X199250Y501967D01*
X198875Y501925D01*
X198542Y501800D01*
X198292Y501633D01*
X198083Y501383D01*
X198000Y501050D01*
G01X200125Y503233D02*
X200333Y503483D01*
X200458Y503775D01*
X200500Y504150D01*
X200417Y504525D01*
X200250Y504817D01*
X199958Y505025D01*
X199625Y505067D01*
X199292Y504983D01*
X199083Y504775D01*
X198917Y504483D01*
X198875Y504192D01*
X198917Y503900D01*
X199083Y503525D01*
X198000Y503650D01*
Y504775D01*
G01X189483Y491500D02*
Y489708D01*
X189650Y489333D01*
X189983Y489083D01*
X190400Y489000D01*
X190817Y489083D01*
X191150Y489333D01*
X191317Y489708D01*
Y491500D01*
G01X194000Y489000D02*
Y491500D01*
X192458Y489708D01*
X194542D01*
G01X196600Y491500D02*
X196267Y491417D01*
X196017Y491208D01*
X195850Y490958D01*
X195725Y490625D01*
X195683Y490250D01*
X195725Y489875D01*
X195850Y489542D01*
X196017Y489292D01*
X196267Y489083D01*
X196600Y489000D01*
X196933Y489083D01*
X197183Y489292D01*
X197350Y489542D01*
X197475Y489875D01*
X197517Y490250D01*
X197475Y490625D01*
X197350Y490958D01*
X197183Y491208D01*
X196933Y491417D01*
X196600Y491500D01*
G01X200017Y477500D02*
Y480000D01*
X201058D01*
X201392Y479875D01*
X201600Y479708D01*
X201683Y479375D01*
X201600Y479042D01*
X201350Y478833D01*
X201058Y478708D01*
X200017D01*
G01X201058D02*
X201683Y477500D01*
G01X203033Y477875D02*
X203283Y477667D01*
X203575Y477542D01*
X203950Y477500D01*
X204325Y477583D01*
X204617Y477750D01*
X204825Y478042D01*
X204867Y478375D01*
X204783Y478708D01*
X204575Y478917D01*
X204283Y479083D01*
X203992Y479125D01*
X203700Y479083D01*
X203325Y478917D01*
X203450Y480000D01*
X204575D01*
G01X206133Y478000D02*
X206383Y477708D01*
X206717Y477542D01*
X207092Y477500D01*
X207425Y477542D01*
X207758Y477750D01*
X207967Y478000D01*
X208008Y478250D01*
X207925Y478542D01*
X207633Y478750D01*
X207342Y478833D01*
X206967D01*
G01X207342D02*
X207592Y478958D01*
X207800Y479167D01*
X207883Y479417D01*
X207800Y479667D01*
X207592Y479875D01*
X207217Y480000D01*
X206842Y479958D01*
X206467Y479792D01*
G01X209442Y477792D02*
X209733Y477583D01*
X210067Y477500D01*
X210400Y477583D01*
X210692Y477833D01*
X210900Y478208D01*
X210983Y478583D01*
Y479042D01*
X210900Y479417D01*
X210692Y479750D01*
X210442Y479917D01*
X210150Y480000D01*
X209817Y479917D01*
X209567Y479750D01*
X209400Y479500D01*
X209317Y479167D01*
X209400Y478875D01*
X209608Y478583D01*
X209858Y478417D01*
X210150Y478375D01*
X210483Y478458D01*
X210733Y478667D01*
X210983Y479042D01*
G01X212999Y551550D02*
Y541550D01*
G01X209166Y551550D02*
X216832D01*
G01X226932Y541550D02*
X220266D01*
Y551550D01*
X226932D01*
G01X224266Y546717D02*
X220266D01*
G01X229866Y541550D02*
Y551550D01*
X234199Y543217D01*
X238532Y551550D01*
Y541550D01*
G01X241466D02*
Y551550D01*
X245466D01*
X246799Y551050D01*
X247799Y549883D01*
X248132Y548550D01*
X247799Y547217D01*
X246966Y546217D01*
X245466Y545716D01*
X241466D01*
G01X250399Y538217D02*
X260399D01*
G01X262499Y542883D02*
X263832Y542050D01*
X265332Y541550D01*
X266666D01*
X267999Y542050D01*
X268999Y542883D01*
X269499Y544050D01*
X269166Y545216D01*
X268332Y546217D01*
X266832Y546883D01*
X264832Y547217D01*
X263666Y547883D01*
X263166Y549050D01*
X263499Y550217D01*
X264332Y551050D01*
X265499Y551550D01*
X266666D01*
X267832Y551217D01*
X268832Y550383D01*
G01X279932Y541550D02*
X273266D01*
Y551550D01*
X279932D01*
G01X277266Y546717D02*
X273266D01*
G01X283366Y541550D02*
Y551550D01*
X291032Y541550D01*
Y551550D01*
G01X294299Y542883D02*
X295632Y542050D01*
X297132Y541550D01*
X298466D01*
X299799Y542050D01*
X300799Y542883D01*
X301299Y544050D01*
X300966Y545216D01*
X300132Y546217D01*
X298632Y546883D01*
X296632Y547217D01*
X295466Y547883D01*
X294966Y549050D01*
X295299Y550217D01*
X296132Y551050D01*
X297299Y551550D01*
X298466D01*
X299632Y551217D01*
X300632Y550383D01*
G01X308399Y541550D02*
X307065Y541717D01*
X305899Y542383D01*
X304899Y543383D01*
X304232Y544550D01*
X303899Y545883D01*
Y547217D01*
X304232Y548550D01*
X304899Y549717D01*
X305899Y550717D01*
X307065Y551383D01*
X308399Y551550D01*
X309732Y551383D01*
X310899Y550717D01*
X311899Y549717D01*
X312566Y548550D01*
X312899Y547217D01*
Y545883D01*
X312566Y544550D01*
X311899Y543383D01*
X310899Y542383D01*
X309732Y541717D01*
X308399Y541550D01*
G01X315666D02*
Y551550D01*
X319832D01*
X321166Y551050D01*
X321999Y550383D01*
X322332Y549050D01*
X321999Y547717D01*
X320999Y546883D01*
X319832Y546383D01*
X315666D01*
G01X319832D02*
X322332Y541550D01*
G01X326432Y549883D02*
X327432Y550883D01*
X328599Y551383D01*
X329932Y551550D01*
X331599Y551217D01*
X332766Y550383D01*
X333099Y549383D01*
X332932Y548383D01*
X332266Y547550D01*
X328932Y545883D01*
X327432Y544717D01*
X326432Y543050D01*
X326099Y541550D01*
X333099D01*
G01X188299Y526113D02*
X190399Y524313D01*
X188299Y522113D01*
G01X188199Y518513D02*
X207399D01*
Y529713D01*
X188199D01*
Y518513D01*
X188599D01*
G01X209499Y562550D02*
Y572550D01*
G01X216499D02*
Y562550D01*
G01Y567550D02*
X209499D01*
G01X219932Y562550D02*
Y572550D01*
X223266D01*
X224599Y572050D01*
X225599Y571383D01*
X226432Y570383D01*
X227099Y569216D01*
X227266Y567550D01*
X227099Y565883D01*
X226432Y564717D01*
X225599Y563716D01*
X224599Y563050D01*
X223266Y562550D01*
X219932D01*
G01X230532D02*
Y572550D01*
X233866D01*
X235199Y572050D01*
X236199Y571383D01*
X237032Y570383D01*
X237699Y569216D01*
X237866Y567550D01*
X237699Y565883D01*
X237032Y564717D01*
X236199Y563716D01*
X235199Y563050D01*
X233866Y562550D01*
X230532D01*
G01X244799D02*
X245966Y562717D01*
X247299Y563217D01*
X248132Y564050D01*
X248466Y565217D01*
X248132Y566383D01*
X247132Y567383D01*
X245632Y567883D01*
X243966D01*
X242966Y568217D01*
X242132Y569050D01*
X241799Y570217D01*
X242299Y571383D01*
X243465Y572217D01*
X244799Y572550D01*
X246132Y572217D01*
X247299Y571383D01*
X247799Y570217D01*
X247466Y569050D01*
X246632Y568217D01*
X245632Y567883D01*
X243966D01*
X242466Y567383D01*
X241466Y566383D01*
X241132Y565217D01*
X241466Y564050D01*
X242299Y563217D01*
X243632Y562717D01*
X244799Y562550D01*
G01X250399Y559217D02*
X260399D01*
G01X262666Y572550D02*
Y562550D01*
X269332D01*
G01X279932D02*
X273266D01*
Y572550D01*
X279932D01*
G01X277266Y567717D02*
X273266D01*
G01X283532Y562550D02*
Y572550D01*
X286866D01*
X288199Y572050D01*
X289199Y571383D01*
X290032Y570383D01*
X290699Y569216D01*
X290866Y567550D01*
X290699Y565883D01*
X290032Y564717D01*
X289199Y563716D01*
X288199Y563050D01*
X286866Y562550D01*
X283532D01*
G01X201494Y553598D02*
X201452Y553265D01*
X201286Y552973D01*
X201036Y552723D01*
X200744Y552556D01*
X200411Y552473D01*
X200077D01*
X199744Y552556D01*
X199452Y552723D01*
X199202Y552973D01*
X199036Y553265D01*
X198994Y553598D01*
X199036Y553931D01*
X199202Y554223D01*
X199452Y554473D01*
X199744Y554640D01*
X200077Y554723D01*
X200411D01*
X200744Y554640D01*
X201036Y554473D01*
X201286Y554223D01*
X201452Y553931D01*
X201494Y553598D01*
G01X200827Y553931D02*
X201494Y554431D01*
G01Y557198D02*
X198994D01*
X200786Y555656D01*
Y557740D01*
G01X199411Y559006D02*
X199161Y559256D01*
X199036Y559548D01*
X198994Y559881D01*
X199077Y560298D01*
X199286Y560590D01*
X199536Y560673D01*
X199786Y560631D01*
X199994Y560465D01*
X200411Y559631D01*
X200702Y559256D01*
X201119Y559006D01*
X201494Y558923D01*
Y560673D01*
G01X196799Y561900D02*
Y574900D01*
G01X206417Y651500D02*
Y656500D01*
X209583D01*
G01X208417Y654083D02*
X206417D01*
G01X213600Y651500D02*
Y656500D01*
X212600Y655500D01*
G01Y651500D02*
X214600D01*
G01X219033D02*
X219200Y652583D01*
X219450Y653500D01*
X219783Y654333D01*
X220200Y655250D01*
X220867Y656500D01*
X217533D01*
G01X224800Y651333D02*
X224633Y651417D01*
Y651583D01*
X224800Y651667D01*
X224967Y651583D01*
Y651417D01*
X224800Y651333D01*
G01Y653583D02*
X224633Y653667D01*
Y653833D01*
X224800Y653917D01*
X224967Y653833D01*
Y653667D01*
X224800Y653583D01*
G01X228817Y655667D02*
X229317Y656167D01*
X229900Y656417D01*
X230567Y656500D01*
X231400Y656333D01*
X231983Y655917D01*
X232150Y655417D01*
X232067Y654917D01*
X231733Y654500D01*
X230067Y653667D01*
X229317Y653083D01*
X228817Y652250D01*
X228650Y651500D01*
X232150D01*
G01X233917D02*
X236000Y656500D01*
X238083Y651500D01*
G01X237333Y653250D02*
X234667D01*
G01X240100Y651333D02*
X243100Y656500D01*
G01X245617Y653583D02*
X246200Y654167D01*
X246700Y654500D01*
X247367Y654667D01*
X247950Y654500D01*
X248367Y654167D01*
X248700Y653667D01*
X248783Y653083D01*
X248700Y652583D01*
X248367Y652083D01*
X247867Y651667D01*
X247283Y651500D01*
X246617Y651667D01*
X246033Y652167D01*
X245700Y652917D01*
X245617Y653750D01*
X245783Y654833D01*
X246033Y655417D01*
X246450Y656000D01*
X247033Y656417D01*
X247617Y656500D01*
X248200Y656333D01*
X248617Y655917D01*
G01X250717Y656500D02*
X252800Y651500D01*
X254883Y656500D01*
G01X201517Y684500D02*
Y687000D01*
X202558D01*
X202892Y686875D01*
X203100Y686708D01*
X203183Y686375D01*
X203100Y686042D01*
X202850Y685833D01*
X202558Y685708D01*
X201517D01*
G01X202558D02*
X203183Y684500D01*
G01X204533Y685000D02*
X204783Y684708D01*
X205117Y684542D01*
X205492Y684500D01*
X205825Y684542D01*
X206158Y684750D01*
X206367Y685000D01*
X206408Y685250D01*
X206325Y685542D01*
X206033Y685750D01*
X205742Y685833D01*
X205367D01*
G01X205742D02*
X205992Y685958D01*
X206200Y686167D01*
X206283Y686417D01*
X206200Y686667D01*
X205992Y686875D01*
X205617Y687000D01*
X205242Y686958D01*
X204867Y686792D01*
G01X207842Y684792D02*
X208133Y684583D01*
X208467Y684500D01*
X208800Y684583D01*
X209092Y684833D01*
X209300Y685208D01*
X209383Y685583D01*
Y686042D01*
X209300Y686417D01*
X209092Y686750D01*
X208842Y686917D01*
X208550Y687000D01*
X208217Y686917D01*
X207967Y686750D01*
X207800Y686500D01*
X207717Y686167D01*
X207800Y685875D01*
X208008Y685583D01*
X208258Y685417D01*
X208550Y685375D01*
X208883Y685458D01*
X209133Y685667D01*
X209383Y686042D01*
G01X210733Y685000D02*
X210983Y684708D01*
X211317Y684542D01*
X211692Y684500D01*
X212025Y684542D01*
X212358Y684750D01*
X212567Y685000D01*
X212608Y685250D01*
X212525Y685542D01*
X212233Y685750D01*
X211942Y685833D01*
X211567D01*
G01X211942D02*
X212192Y685958D01*
X212400Y686167D01*
X212483Y686417D01*
X212400Y686667D01*
X212192Y686875D01*
X211817Y687000D01*
X211442Y686958D01*
X211067Y686792D01*
G01X205000Y697517D02*
X202500D01*
Y698558D01*
X202625Y698892D01*
X202792Y699100D01*
X203125Y699183D01*
X203458Y699100D01*
X203667Y698850D01*
X203792Y698558D01*
Y697517D01*
G01Y698558D02*
X205000Y699183D01*
G01X202917Y700658D02*
X202667Y700908D01*
X202542Y701200D01*
X202500Y701533D01*
X202583Y701950D01*
X202792Y702242D01*
X203042Y702325D01*
X203292Y702283D01*
X203500Y702117D01*
X203917Y701283D01*
X204208Y700908D01*
X204625Y700658D01*
X205000Y700575D01*
Y702325D01*
G01Y704550D02*
X202500D01*
X203000Y704050D01*
G01X205000D02*
Y705050D01*
G01Y707650D02*
X204958Y707942D01*
X204833Y708275D01*
X204625Y708483D01*
X204333Y708567D01*
X204042Y708483D01*
X203792Y708233D01*
X203667Y707858D01*
Y707442D01*
X203583Y707192D01*
X203375Y706983D01*
X203083Y706900D01*
X202792Y707025D01*
X202583Y707317D01*
X202500Y707650D01*
X202583Y707983D01*
X202792Y708275D01*
X203083Y708400D01*
X203375Y708317D01*
X203583Y708108D01*
X203667Y707858D01*
Y707442D01*
X203792Y707067D01*
X204042Y706817D01*
X204333Y706733D01*
X204625Y706817D01*
X204833Y707025D01*
X204958Y707358D01*
X205000Y707650D01*
G01X201517Y688500D02*
Y691000D01*
X202558D01*
X202892Y690875D01*
X203100Y690708D01*
X203183Y690375D01*
X203100Y690042D01*
X202850Y689833D01*
X202558Y689708D01*
X201517D01*
G01X202558D02*
X203183Y688500D01*
G01X204658Y690583D02*
X204908Y690833D01*
X205200Y690958D01*
X205533Y691000D01*
X205950Y690917D01*
X206242Y690708D01*
X206325Y690458D01*
X206283Y690208D01*
X206117Y690000D01*
X205283Y689583D01*
X204908Y689292D01*
X204658Y688875D01*
X204575Y688500D01*
X206325D01*
G01X208550D02*
Y691000D01*
X208050Y690500D01*
G01Y688500D02*
X209050D01*
G01X211567D02*
X211650Y689042D01*
X211775Y689500D01*
X211942Y689917D01*
X212150Y690375D01*
X212483Y691000D01*
X210817D01*
G01X208707Y718817D02*
X208582Y718567D01*
X208499Y718275D01*
Y717942D01*
X208624Y717567D01*
X208832Y717275D01*
X209082Y717067D01*
X209499Y716900D01*
X209874Y716858D01*
X210249Y716942D01*
X210499Y717067D01*
X210749Y717317D01*
X210916Y717608D01*
X210999Y717900D01*
Y718192D01*
X210916Y718483D01*
X210791Y718733D01*
X210624Y718942D01*
G01X208916Y720208D02*
X208666Y720458D01*
X208541Y720750D01*
X208499Y721083D01*
X208582Y721500D01*
X208791Y721792D01*
X209041Y721875D01*
X209291Y721833D01*
X209499Y721667D01*
X209916Y720833D01*
X210207Y720458D01*
X210624Y720208D01*
X210999Y720125D01*
Y721875D01*
G01X210499Y723183D02*
X210791Y723433D01*
X210957Y723767D01*
X210999Y724142D01*
X210957Y724475D01*
X210749Y724808D01*
X210499Y725017D01*
X210249Y725058D01*
X209957Y724975D01*
X209749Y724683D01*
X209666Y724392D01*
Y724017D01*
G01Y724392D02*
X209541Y724642D01*
X209332Y724850D01*
X209082Y724933D01*
X208832Y724850D01*
X208624Y724642D01*
X208499Y724267D01*
X208541Y723892D01*
X208707Y723517D01*
G01X209957Y726408D02*
X209666Y726700D01*
X209499Y726950D01*
X209416Y727283D01*
X209499Y727575D01*
X209666Y727783D01*
X209916Y727950D01*
X210207Y727992D01*
X210457Y727950D01*
X210707Y727783D01*
X210916Y727533D01*
X210999Y727242D01*
X210916Y726908D01*
X210666Y726617D01*
X210291Y726450D01*
X209874Y726408D01*
X209332Y726492D01*
X209041Y726617D01*
X208749Y726825D01*
X208541Y727117D01*
X208499Y727408D01*
X208582Y727700D01*
X208791Y727908D01*
G01X202131Y730789D02*
Y733289D01*
X203172D01*
X203506Y733164D01*
X203714Y732997D01*
X203797Y732664D01*
X203714Y732331D01*
X203464Y732122D01*
X203172Y731997D01*
X202131D01*
G01X203172D02*
X203797Y730789D01*
G01X205272Y732872D02*
X205522Y733122D01*
X205814Y733247D01*
X206147Y733289D01*
X206564Y733206D01*
X206856Y732997D01*
X206939Y732747D01*
X206897Y732497D01*
X206731Y732289D01*
X205897Y731872D01*
X205522Y731581D01*
X205272Y731164D01*
X205189Y730789D01*
X206939D01*
G01X208372Y732872D02*
X208622Y733122D01*
X208914Y733247D01*
X209247Y733289D01*
X209664Y733206D01*
X209956Y732997D01*
X210039Y732747D01*
X209997Y732497D01*
X209831Y732289D01*
X208997Y731872D01*
X208622Y731581D01*
X208372Y731164D01*
X208289Y730789D01*
X210039D01*
G01X211347Y731289D02*
X211597Y730997D01*
X211931Y730831D01*
X212306Y730789D01*
X212639Y730831D01*
X212972Y731039D01*
X213181Y731289D01*
X213222Y731539D01*
X213139Y731831D01*
X212847Y732039D01*
X212556Y732122D01*
X212181D01*
G01X212556D02*
X212806Y732247D01*
X213014Y732456D01*
X213097Y732706D01*
X213014Y732956D01*
X212806Y733164D01*
X212431Y733289D01*
X212056Y733247D01*
X211681Y733081D01*
G01X196517Y812000D02*
Y814500D01*
X197558D01*
X197892Y814375D01*
X198100Y814208D01*
X198183Y813875D01*
X198100Y813542D01*
X197850Y813333D01*
X197558Y813208D01*
X196517D01*
G01X197558D02*
X198183Y812000D01*
G01X200950D02*
Y814500D01*
X199408Y812708D01*
X201492D01*
G01X202758Y814083D02*
X203008Y814333D01*
X203300Y814458D01*
X203633Y814500D01*
X204050Y814417D01*
X204342Y814208D01*
X204425Y813958D01*
X204383Y813708D01*
X204217Y813500D01*
X203383Y813083D01*
X203008Y812792D01*
X202758Y812375D01*
X202675Y812000D01*
X204425D01*
G01X206650Y814500D02*
X206317Y814417D01*
X206067Y814208D01*
X205900Y813958D01*
X205775Y813625D01*
X205733Y813250D01*
X205775Y812875D01*
X205900Y812542D01*
X206067Y812292D01*
X206317Y812083D01*
X206650Y812000D01*
X206983Y812083D01*
X207233Y812292D01*
X207400Y812542D01*
X207525Y812875D01*
X207567Y813250D01*
X207525Y813625D01*
X207400Y813958D01*
X207233Y814208D01*
X206983Y814417D01*
X206650Y814500D01*
G01X192199Y828413D02*
Y839813D01*
G01X191499Y814630D02*
X188999D01*
Y815671D01*
X189124Y816005D01*
X189291Y816213D01*
X189624Y816296D01*
X189957Y816213D01*
X190166Y815963D01*
X190291Y815671D01*
Y814630D01*
G01Y815671D02*
X191499Y816296D01*
G01X189416Y817771D02*
X189166Y818021D01*
X189041Y818313D01*
X188999Y818646D01*
X189082Y819063D01*
X189291Y819355D01*
X189541Y819438D01*
X189791Y819396D01*
X189999Y819230D01*
X190416Y818396D01*
X190707Y818021D01*
X191124Y817771D01*
X191499Y817688D01*
Y819438D01*
G01Y821580D02*
X190957Y821663D01*
X190499Y821788D01*
X190082Y821955D01*
X189624Y822163D01*
X188999Y822496D01*
Y820830D01*
G01X191499Y824763D02*
X191457Y825055D01*
X191332Y825388D01*
X191124Y825596D01*
X190832Y825680D01*
X190541Y825596D01*
X190291Y825346D01*
X190166Y824971D01*
Y824555D01*
X190082Y824305D01*
X189874Y824096D01*
X189582Y824013D01*
X189291Y824138D01*
X189082Y824430D01*
X188999Y824763D01*
X189082Y825096D01*
X189291Y825388D01*
X189582Y825513D01*
X189874Y825430D01*
X190082Y825221D01*
X190166Y824971D01*
Y824555D01*
X190291Y824180D01*
X190541Y823930D01*
X190832Y823846D01*
X191124Y823930D01*
X191332Y824138D01*
X191457Y824471D01*
X191499Y824763D01*
G01X193400Y825000D02*
Y821000D01*
X200800D01*
G01X202899Y846913D02*
Y827713D01*
X214099D01*
Y846913D01*
X202899D01*
G01X192499Y847813D02*
X188499D01*
Y840413D01*
G01X210499Y846913D02*
X208499Y844913D01*
X206499Y846913D01*
G01X197099Y848113D02*
Y871113D01*
G01X235899Y848113D02*
X197099D01*
G01X191999Y853813D02*
Y848313D01*
G01X197099Y871113D02*
X235899D01*
G01X195499Y875313D02*
Y869813D01*
G01X191999Y865913D02*
Y860413D01*
G01X202500Y872200D02*
X220100D01*
G01X202500Y880200D02*
Y872200D01*
G01X207999Y903713D02*
X203999D01*
Y896313D01*
G01X211999Y903713D02*
X207999D01*
Y896313D01*
G01X200999Y881850D02*
Y895250D01*
G01X210999Y881850D02*
X200999D01*
G01Y895250D02*
X210999D01*
G01X195708Y891267D02*
X195583Y891017D01*
X195500Y890725D01*
Y890392D01*
X195625Y890017D01*
X195833Y889725D01*
X196083Y889517D01*
X196500Y889350D01*
X196875Y889308D01*
X197250Y889392D01*
X197500Y889517D01*
X197750Y889767D01*
X197917Y890058D01*
X198000Y890350D01*
Y890642D01*
X197917Y890933D01*
X197792Y891183D01*
X197625Y891392D01*
G01X197500Y892533D02*
X197792Y892783D01*
X197958Y893117D01*
X198000Y893492D01*
X197958Y893825D01*
X197750Y894158D01*
X197500Y894367D01*
X197250Y894408D01*
X196958Y894325D01*
X196750Y894033D01*
X196667Y893742D01*
Y893367D01*
G01Y893742D02*
X196542Y893992D01*
X196333Y894200D01*
X196083Y894283D01*
X195833Y894200D01*
X195625Y893992D01*
X195500Y893617D01*
X195542Y893242D01*
X195708Y892867D01*
G01X195500Y896550D02*
X195583Y896217D01*
X195792Y895967D01*
X196042Y895800D01*
X196375Y895675D01*
X196750Y895633D01*
X197125Y895675D01*
X197458Y895800D01*
X197708Y895967D01*
X197917Y896217D01*
X198000Y896550D01*
X197917Y896883D01*
X197708Y897133D01*
X197458Y897300D01*
X197125Y897425D01*
X196750Y897467D01*
X196375Y897425D01*
X196042Y897300D01*
X195792Y897133D01*
X195583Y896883D01*
X195500Y896550D01*
G01X195917Y898858D02*
X195667Y899108D01*
X195542Y899400D01*
X195500Y899733D01*
X195583Y900150D01*
X195792Y900442D01*
X196042Y900525D01*
X196292Y900483D01*
X196500Y900317D01*
X196917Y899483D01*
X197208Y899108D01*
X197625Y898858D01*
X198000Y898775D01*
Y900525D01*
G01X195499Y887413D02*
Y881913D01*
G01X220100Y880200D02*
X202500D01*
G01X190400Y915000D02*
Y929000D01*
G01X189017Y903000D02*
Y905500D01*
X190058D01*
X190392Y905375D01*
X190600Y905208D01*
X190683Y904875D01*
X190600Y904542D01*
X190350Y904333D01*
X190058Y904208D01*
X189017D01*
G01X190058D02*
X190683Y903000D01*
G01X192033Y903375D02*
X192283Y903167D01*
X192575Y903042D01*
X192950Y903000D01*
X193325Y903083D01*
X193617Y903250D01*
X193825Y903542D01*
X193867Y903875D01*
X193783Y904208D01*
X193575Y904417D01*
X193283Y904583D01*
X192992Y904625D01*
X192700Y904583D01*
X192325Y904417D01*
X192450Y905500D01*
X193575D01*
G01X195133Y903500D02*
X195383Y903208D01*
X195717Y903042D01*
X196092Y903000D01*
X196425Y903042D01*
X196758Y903250D01*
X196967Y903500D01*
X197008Y903750D01*
X196925Y904042D01*
X196633Y904250D01*
X196342Y904333D01*
X195967D01*
G01X196342D02*
X196592Y904458D01*
X196800Y904667D01*
X196883Y904917D01*
X196800Y905167D01*
X196592Y905375D01*
X196217Y905500D01*
X195842Y905458D01*
X195467Y905292D01*
G01X198358Y904042D02*
X198650Y904333D01*
X198900Y904500D01*
X199233Y904583D01*
X199525Y904500D01*
X199733Y904333D01*
X199900Y904083D01*
X199942Y903792D01*
X199900Y903542D01*
X199733Y903292D01*
X199483Y903083D01*
X199192Y903000D01*
X198858Y903083D01*
X198567Y903333D01*
X198400Y903708D01*
X198358Y904125D01*
X198442Y904667D01*
X198567Y904958D01*
X198775Y905250D01*
X199067Y905458D01*
X199358Y905500D01*
X199650Y905417D01*
X199858Y905208D01*
G01X192900Y940500D02*
X192567Y940542D01*
X192275Y940708D01*
X192025Y940958D01*
X191858Y941250D01*
X191775Y941583D01*
Y941917D01*
X191858Y942250D01*
X192025Y942542D01*
X192275Y942792D01*
X192567Y942958D01*
X192900Y943000D01*
X193233Y942958D01*
X193525Y942792D01*
X193775Y942542D01*
X193942Y942250D01*
X194025Y941917D01*
Y941583D01*
X193942Y941250D01*
X193775Y940958D01*
X193525Y940708D01*
X193233Y940542D01*
X192900Y940500D01*
G01X193233Y941167D02*
X193733Y940500D01*
G01X195917D02*
X196000Y941042D01*
X196125Y941500D01*
X196292Y941917D01*
X196500Y942375D01*
X196833Y943000D01*
X195167D01*
G01X199100D02*
X198767Y942917D01*
X198517Y942708D01*
X198350Y942458D01*
X198225Y942125D01*
X198183Y941750D01*
X198225Y941375D01*
X198350Y941042D01*
X198517Y940792D01*
X198767Y940583D01*
X199100Y940500D01*
X199433Y940583D01*
X199683Y940792D01*
X199850Y941042D01*
X199975Y941375D01*
X200017Y941750D01*
X199975Y942125D01*
X199850Y942458D01*
X199683Y942708D01*
X199433Y942917D01*
X199100Y943000D01*
G01X189600Y934100D02*
Y947500D01*
G01X190017Y930000D02*
Y932500D01*
X191058D01*
X191392Y932375D01*
X191600Y932208D01*
X191683Y931875D01*
X191600Y931542D01*
X191350Y931333D01*
X191058Y931208D01*
X190017D01*
G01X191058D02*
X191683Y930000D01*
G01X194450D02*
Y932500D01*
X192908Y930708D01*
X194992D01*
G01X197050Y932500D02*
X196717Y932417D01*
X196467Y932208D01*
X196300Y931958D01*
X196175Y931625D01*
X196133Y931250D01*
X196175Y930875D01*
X196300Y930542D01*
X196467Y930292D01*
X196717Y930083D01*
X197050Y930000D01*
X197383Y930083D01*
X197633Y930292D01*
X197800Y930542D01*
X197925Y930875D01*
X197967Y931250D01*
X197925Y931625D01*
X197800Y931958D01*
X197633Y932208D01*
X197383Y932417D01*
X197050Y932500D01*
G01X200150Y930000D02*
Y932500D01*
X199650Y932000D01*
G01Y930000D02*
X200650D01*
G01X208499Y969050D02*
Y979050D01*
G01X215499D02*
Y969050D01*
G01Y974050D02*
X208499D01*
G01X218932Y969050D02*
Y979050D01*
X222266D01*
X223599Y978550D01*
X224599Y977883D01*
X225432Y976883D01*
X226099Y975716D01*
X226266Y974050D01*
X226099Y972383D01*
X225432Y971217D01*
X224599Y970216D01*
X223599Y969550D01*
X222266Y969050D01*
X218932D01*
G01X229532D02*
Y979050D01*
X232866D01*
X234199Y978550D01*
X235199Y977883D01*
X236032Y976883D01*
X236699Y975716D01*
X236866Y974050D01*
X236699Y972383D01*
X236032Y971217D01*
X235199Y970216D01*
X234199Y969550D01*
X232866Y969050D01*
X229532D01*
G01X243466D02*
X243799Y971217D01*
X244299Y973050D01*
X244966Y974717D01*
X245799Y976550D01*
X247132Y979050D01*
X240466D01*
G01X249399Y965717D02*
X259399D01*
G01X261666Y979050D02*
Y969050D01*
X268332D01*
G01X278932D02*
X272266D01*
Y979050D01*
X278932D01*
G01X276266Y974217D02*
X272266D01*
G01X282532Y969050D02*
Y979050D01*
X285866D01*
X287199Y978550D01*
X288199Y977883D01*
X289032Y976883D01*
X289699Y975716D01*
X289866Y974050D01*
X289699Y972383D01*
X289032Y971217D01*
X288199Y970216D01*
X287199Y969550D01*
X285866Y969050D01*
X282532D01*
G01X200896Y977183D02*
X200854Y976850D01*
X200688Y976558D01*
X200438Y976308D01*
X200146Y976141D01*
X199813Y976058D01*
X199479D01*
X199146Y976141D01*
X198854Y976308D01*
X198604Y976558D01*
X198438Y976850D01*
X198396Y977183D01*
X198438Y977516D01*
X198604Y977808D01*
X198854Y978058D01*
X199146Y978225D01*
X199479Y978308D01*
X199813D01*
X200146Y978225D01*
X200438Y978058D01*
X200688Y977808D01*
X200854Y977516D01*
X200896Y977183D01*
G01X200229Y977516D02*
X200896Y978016D01*
G01Y980783D02*
X198396D01*
X200188Y979241D01*
Y981325D01*
G01X200896Y983383D02*
X198396D01*
X198896Y982883D01*
G01X200896D02*
Y983883D01*
G01X196799Y965600D02*
Y978600D01*
G01X208708Y1069267D02*
X208583Y1069017D01*
X208500Y1068725D01*
Y1068392D01*
X208625Y1068017D01*
X208833Y1067725D01*
X209083Y1067517D01*
X209500Y1067350D01*
X209875Y1067308D01*
X210250Y1067392D01*
X210500Y1067517D01*
X210750Y1067767D01*
X210917Y1068058D01*
X211000Y1068350D01*
Y1068642D01*
X210917Y1068933D01*
X210792Y1069183D01*
X210625Y1069392D01*
G01X208917Y1070658D02*
X208667Y1070908D01*
X208542Y1071200D01*
X208500Y1071533D01*
X208583Y1071950D01*
X208792Y1072242D01*
X209042Y1072325D01*
X209292Y1072283D01*
X209500Y1072117D01*
X209917Y1071283D01*
X210208Y1070908D01*
X210625Y1070658D01*
X211000Y1070575D01*
Y1072325D01*
G01X208917Y1073758D02*
X208667Y1074008D01*
X208542Y1074300D01*
X208500Y1074633D01*
X208583Y1075050D01*
X208792Y1075342D01*
X209042Y1075425D01*
X209292Y1075383D01*
X209500Y1075217D01*
X209917Y1074383D01*
X210208Y1074008D01*
X210625Y1073758D01*
X211000Y1073675D01*
Y1075425D01*
G01X208917Y1076858D02*
X208667Y1077108D01*
X208542Y1077400D01*
X208500Y1077733D01*
X208583Y1078150D01*
X208792Y1078442D01*
X209042Y1078525D01*
X209292Y1078483D01*
X209500Y1078317D01*
X209917Y1077483D01*
X210208Y1077108D01*
X210625Y1076858D01*
X211000Y1076775D01*
Y1078525D01*
G01X207000Y1067517D02*
X204500D01*
Y1068558D01*
X204625Y1068892D01*
X204792Y1069100D01*
X205125Y1069183D01*
X205458Y1069100D01*
X205667Y1068850D01*
X205792Y1068558D01*
Y1067517D01*
G01Y1068558D02*
X207000Y1069183D01*
G01X204917Y1070658D02*
X204667Y1070908D01*
X204542Y1071200D01*
X204500Y1071533D01*
X204583Y1071950D01*
X204792Y1072242D01*
X205042Y1072325D01*
X205292Y1072283D01*
X205500Y1072117D01*
X205917Y1071283D01*
X206208Y1070908D01*
X206625Y1070658D01*
X207000Y1070575D01*
Y1072325D01*
G01X204500Y1074550D02*
X204583Y1074217D01*
X204792Y1073967D01*
X205042Y1073800D01*
X205375Y1073675D01*
X205750Y1073633D01*
X206125Y1073675D01*
X206458Y1073800D01*
X206708Y1073967D01*
X206917Y1074217D01*
X207000Y1074550D01*
X206917Y1074883D01*
X206708Y1075133D01*
X206458Y1075300D01*
X206125Y1075425D01*
X205750Y1075467D01*
X205375Y1075425D01*
X205042Y1075300D01*
X204792Y1075133D01*
X204583Y1074883D01*
X204500Y1074550D01*
G01X207000Y1077650D02*
X206958Y1077942D01*
X206833Y1078275D01*
X206625Y1078483D01*
X206333Y1078567D01*
X206042Y1078483D01*
X205792Y1078233D01*
X205667Y1077858D01*
Y1077442D01*
X205583Y1077192D01*
X205375Y1076983D01*
X205083Y1076900D01*
X204792Y1077025D01*
X204583Y1077317D01*
X204500Y1077650D01*
X204583Y1077983D01*
X204792Y1078275D01*
X205083Y1078400D01*
X205375Y1078317D01*
X205583Y1078108D01*
X205667Y1077858D01*
Y1077442D01*
X205792Y1077067D01*
X206042Y1076817D01*
X206333Y1076733D01*
X206625Y1076817D01*
X206833Y1077025D01*
X206958Y1077358D01*
X207000Y1077650D01*
G01X190416Y1257550D02*
Y1262550D01*
X193582D01*
G01X192416Y1260133D02*
X190416D01*
G01X196016Y1261717D02*
X196516Y1262217D01*
X197099Y1262467D01*
X197766Y1262550D01*
X198599Y1262383D01*
X199182Y1261967D01*
X199349Y1261467D01*
X199266Y1260967D01*
X198932Y1260550D01*
X197266Y1259717D01*
X196516Y1259133D01*
X196016Y1258300D01*
X195849Y1257550D01*
X199349D01*
G01X204199D02*
Y1262550D01*
X201116Y1258967D01*
X205282D01*
G01X208799Y1257383D02*
X208632Y1257467D01*
Y1257633D01*
X208799Y1257717D01*
X208966Y1257633D01*
Y1257467D01*
X208799Y1257383D01*
G01Y1259633D02*
X208632Y1259717D01*
Y1259883D01*
X208799Y1259967D01*
X208966Y1259883D01*
Y1259717D01*
X208799Y1259633D01*
G01X212566Y1258550D02*
X213066Y1257967D01*
X213732Y1257633D01*
X214482Y1257550D01*
X215149Y1257633D01*
X215816Y1258050D01*
X216232Y1258550D01*
X216316Y1259050D01*
X216149Y1259633D01*
X215566Y1260050D01*
X214982Y1260217D01*
X214232D01*
G01X214982D02*
X215482Y1260467D01*
X215899Y1260883D01*
X216066Y1261383D01*
X215899Y1261883D01*
X215482Y1262300D01*
X214732Y1262550D01*
X213982Y1262467D01*
X213232Y1262133D01*
G01X217916Y1257550D02*
X219999Y1262550D01*
X222082Y1257550D01*
G01X221332Y1259300D02*
X218666D01*
G01X224099Y1257383D02*
X227099Y1262550D01*
G01X231199Y1257550D02*
Y1262550D01*
X230199Y1261550D01*
G01Y1257550D02*
X232199D01*
G01X234966Y1258300D02*
X235466Y1257883D01*
X236049Y1257633D01*
X236799Y1257550D01*
X237549Y1257717D01*
X238132Y1258050D01*
X238549Y1258633D01*
X238632Y1259300D01*
X238466Y1259967D01*
X238049Y1260383D01*
X237466Y1260717D01*
X236882Y1260800D01*
X236299Y1260717D01*
X235549Y1260383D01*
X235799Y1262550D01*
X238049D01*
G01X240316D02*
X242399Y1257550D01*
X244482Y1262550D01*
G01X190416Y1266550D02*
Y1271550D01*
X193582D01*
G01X192416Y1269133D02*
X190416D01*
G01X196016Y1270717D02*
X196516Y1271217D01*
X197099Y1271467D01*
X197766Y1271550D01*
X198599Y1271383D01*
X199182Y1270967D01*
X199349Y1270467D01*
X199266Y1269967D01*
X198932Y1269550D01*
X197266Y1268717D01*
X196516Y1268133D01*
X196016Y1267300D01*
X195849Y1266550D01*
X199349D01*
G01X201366Y1267550D02*
X201866Y1266967D01*
X202532Y1266633D01*
X203282Y1266550D01*
X203949Y1266633D01*
X204616Y1267050D01*
X205032Y1267550D01*
X205116Y1268050D01*
X204949Y1268633D01*
X204366Y1269050D01*
X203782Y1269217D01*
X203032D01*
G01X203782D02*
X204282Y1269467D01*
X204699Y1269883D01*
X204866Y1270383D01*
X204699Y1270883D01*
X204282Y1271300D01*
X203532Y1271550D01*
X202782Y1271467D01*
X202032Y1271133D01*
G01X208799Y1266383D02*
X208632Y1266467D01*
Y1266633D01*
X208799Y1266717D01*
X208966Y1266633D01*
Y1266467D01*
X208799Y1266383D01*
G01Y1268633D02*
X208632Y1268717D01*
Y1268883D01*
X208799Y1268967D01*
X208966Y1268883D01*
Y1268717D01*
X208799Y1268633D01*
G01X212816Y1270717D02*
X213316Y1271217D01*
X213899Y1271467D01*
X214566Y1271550D01*
X215399Y1271383D01*
X215982Y1270967D01*
X216149Y1270467D01*
X216066Y1269967D01*
X215732Y1269550D01*
X214066Y1268717D01*
X213316Y1268133D01*
X212816Y1267300D01*
X212649Y1266550D01*
X216149D01*
G01X217916D02*
X219999Y1271550D01*
X222082Y1266550D01*
G01X221332Y1268300D02*
X218666D01*
G01X224099Y1266383D02*
X227099Y1271550D01*
G01X229616Y1268633D02*
X230199Y1269217D01*
X230699Y1269550D01*
X231366Y1269717D01*
X231949Y1269550D01*
X232366Y1269217D01*
X232699Y1268717D01*
X232782Y1268133D01*
X232699Y1267633D01*
X232366Y1267133D01*
X231866Y1266717D01*
X231282Y1266550D01*
X230616Y1266717D01*
X230032Y1267217D01*
X229699Y1267967D01*
X229616Y1268800D01*
X229782Y1269883D01*
X230032Y1270467D01*
X230449Y1271050D01*
X231032Y1271467D01*
X231616Y1271550D01*
X232199Y1271383D01*
X232616Y1270967D01*
G01X234716Y1271550D02*
X236799Y1266550D01*
X238882Y1271550D01*
G01X194504Y1361361D02*
Y1363861D01*
X195545D01*
X195879Y1363736D01*
X196087Y1363569D01*
X196170Y1363236D01*
X196087Y1362903D01*
X195837Y1362694D01*
X195545Y1362569D01*
X194504D01*
G01X195545D02*
X196170Y1361361D01*
G01X198937D02*
Y1363861D01*
X197395Y1362069D01*
X199479D01*
G01X200829Y1361653D02*
X201120Y1361444D01*
X201454Y1361361D01*
X201787Y1361444D01*
X202079Y1361694D01*
X202287Y1362069D01*
X202370Y1362444D01*
Y1362903D01*
X202287Y1363278D01*
X202079Y1363611D01*
X201829Y1363778D01*
X201537Y1363861D01*
X201204Y1363778D01*
X200954Y1363611D01*
X200787Y1363361D01*
X200704Y1363028D01*
X200787Y1362736D01*
X200995Y1362444D01*
X201245Y1362278D01*
X201537Y1362236D01*
X201870Y1362319D01*
X202120Y1362528D01*
X202370Y1362903D01*
G01X203845Y1362403D02*
X204137Y1362694D01*
X204387Y1362861D01*
X204720Y1362944D01*
X205012Y1362861D01*
X205220Y1362694D01*
X205387Y1362444D01*
X205429Y1362153D01*
X205387Y1361903D01*
X205220Y1361653D01*
X204970Y1361444D01*
X204679Y1361361D01*
X204345Y1361444D01*
X204054Y1361694D01*
X203887Y1362069D01*
X203845Y1362486D01*
X203929Y1363028D01*
X204054Y1363319D01*
X204262Y1363611D01*
X204554Y1363819D01*
X204845Y1363861D01*
X205137Y1363778D01*
X205345Y1363569D01*
G01X189299Y1383050D02*
Y1379050D01*
X196699D01*
G01X189299D02*
Y1375050D01*
X196699D01*
G01X189299D02*
Y1371050D01*
X196699D01*
G01X204599Y1365400D02*
Y1369400D01*
X197199D01*
G01X197299Y1370300D02*
X211299D01*
G01X197299Y1383300D02*
Y1370300D01*
G01X211299Y1383300D02*
X197299D01*
G01X208765Y1467950D02*
X218765D01*
G01Y1460950D02*
X208765D01*
G01X213765D02*
Y1467950D01*
G01X208765Y1457517D02*
X218765D01*
Y1454183D01*
X218265Y1452850D01*
X217598Y1451850D01*
X216598Y1451017D01*
X215431Y1450350D01*
X213765Y1450183D01*
X212098Y1450350D01*
X210932Y1451017D01*
X209931Y1451850D01*
X209265Y1452850D01*
X208765Y1454183D01*
Y1457517D01*
G01Y1446917D02*
X218765D01*
Y1443583D01*
X218265Y1442250D01*
X217598Y1441250D01*
X216598Y1440417D01*
X215431Y1439750D01*
X213765Y1439583D01*
X212098Y1439750D01*
X210932Y1440417D01*
X209931Y1441250D01*
X209265Y1442250D01*
X208765Y1443583D01*
Y1446917D01*
G01X212931Y1435817D02*
X214098Y1434650D01*
X214765Y1433650D01*
X215098Y1432317D01*
X214765Y1431150D01*
X214098Y1430317D01*
X213098Y1429650D01*
X211932Y1429483D01*
X210932Y1429650D01*
X209931Y1430317D01*
X209098Y1431317D01*
X208765Y1432483D01*
X209098Y1433817D01*
X210098Y1434983D01*
X211598Y1435650D01*
X213265Y1435817D01*
X215431Y1435483D01*
X216598Y1434983D01*
X217765Y1434150D01*
X218598Y1432983D01*
X218765Y1431817D01*
X218432Y1430650D01*
X217598Y1429817D01*
G01X206707Y1526317D02*
X206582Y1526067D01*
X206499Y1525775D01*
Y1525442D01*
X206624Y1525067D01*
X206832Y1524775D01*
X207082Y1524567D01*
X207499Y1524400D01*
X207874Y1524358D01*
X208249Y1524442D01*
X208499Y1524567D01*
X208749Y1524817D01*
X208916Y1525108D01*
X208999Y1525400D01*
Y1525692D01*
X208916Y1525983D01*
X208791Y1526233D01*
X208624Y1526442D01*
G01X206916Y1527708D02*
X206666Y1527958D01*
X206541Y1528250D01*
X206499Y1528583D01*
X206582Y1529000D01*
X206791Y1529292D01*
X207041Y1529375D01*
X207291Y1529333D01*
X207499Y1529167D01*
X207916Y1528333D01*
X208207Y1527958D01*
X208624Y1527708D01*
X208999Y1527625D01*
Y1529375D01*
G01X206499Y1531600D02*
X206582Y1531267D01*
X206791Y1531017D01*
X207041Y1530850D01*
X207374Y1530725D01*
X207749Y1530683D01*
X208124Y1530725D01*
X208457Y1530850D01*
X208707Y1531017D01*
X208916Y1531267D01*
X208999Y1531600D01*
X208916Y1531933D01*
X208707Y1532183D01*
X208457Y1532350D01*
X208124Y1532475D01*
X207749Y1532517D01*
X207374Y1532475D01*
X207041Y1532350D01*
X206791Y1532183D01*
X206582Y1531933D01*
X206499Y1531600D01*
G01X208624Y1533783D02*
X208832Y1534033D01*
X208957Y1534325D01*
X208999Y1534700D01*
X208916Y1535075D01*
X208749Y1535367D01*
X208457Y1535575D01*
X208124Y1535617D01*
X207791Y1535533D01*
X207582Y1535325D01*
X207416Y1535033D01*
X207374Y1534742D01*
X207416Y1534450D01*
X207582Y1534075D01*
X206499Y1534200D01*
Y1535325D01*
G01X201517Y1516500D02*
Y1519000D01*
X202558D01*
X202892Y1518875D01*
X203100Y1518708D01*
X203183Y1518375D01*
X203100Y1518042D01*
X202850Y1517833D01*
X202558Y1517708D01*
X201517D01*
G01X202558D02*
X203183Y1516500D01*
G01X205450D02*
Y1519000D01*
X204950Y1518500D01*
G01Y1516500D02*
X205950D01*
G01X207842Y1516792D02*
X208133Y1516583D01*
X208467Y1516500D01*
X208800Y1516583D01*
X209092Y1516833D01*
X209300Y1517208D01*
X209383Y1517583D01*
Y1518042D01*
X209300Y1518417D01*
X209092Y1518750D01*
X208842Y1518917D01*
X208550Y1519000D01*
X208217Y1518917D01*
X207967Y1518750D01*
X207800Y1518500D01*
X207717Y1518167D01*
X207800Y1517875D01*
X208008Y1517583D01*
X208258Y1517417D01*
X208550Y1517375D01*
X208883Y1517458D01*
X209133Y1517667D01*
X209383Y1518042D01*
G01X211650Y1519000D02*
X211317Y1518917D01*
X211067Y1518708D01*
X210900Y1518458D01*
X210775Y1518125D01*
X210733Y1517750D01*
X210775Y1517375D01*
X210900Y1517042D01*
X211067Y1516792D01*
X211317Y1516583D01*
X211650Y1516500D01*
X211983Y1516583D01*
X212233Y1516792D01*
X212400Y1517042D01*
X212525Y1517375D01*
X212567Y1517750D01*
X212525Y1518125D01*
X212400Y1518458D01*
X212233Y1518708D01*
X211983Y1518917D01*
X211650Y1519000D01*
G01X202051Y1539176D02*
Y1541676D01*
X203092D01*
X203426Y1541551D01*
X203634Y1541384D01*
X203717Y1541051D01*
X203634Y1540718D01*
X203384Y1540509D01*
X203092Y1540384D01*
X202051D01*
G01X203092D02*
X203717Y1539176D01*
G01X205984D02*
Y1541676D01*
X205484Y1541176D01*
G01Y1539176D02*
X206484D01*
G01X208376Y1539468D02*
X208667Y1539259D01*
X209001Y1539176D01*
X209334Y1539259D01*
X209626Y1539509D01*
X209834Y1539884D01*
X209917Y1540259D01*
Y1540718D01*
X209834Y1541093D01*
X209626Y1541426D01*
X209376Y1541593D01*
X209084Y1541676D01*
X208751Y1541593D01*
X208501Y1541426D01*
X208334Y1541176D01*
X208251Y1540843D01*
X208334Y1540551D01*
X208542Y1540259D01*
X208792Y1540093D01*
X209084Y1540051D01*
X209417Y1540134D01*
X209667Y1540343D01*
X209917Y1540718D01*
G01X211267Y1539551D02*
X211517Y1539343D01*
X211809Y1539218D01*
X212184Y1539176D01*
X212559Y1539259D01*
X212851Y1539426D01*
X213059Y1539718D01*
X213101Y1540051D01*
X213017Y1540384D01*
X212809Y1540593D01*
X212517Y1540759D01*
X212226Y1540801D01*
X211934Y1540759D01*
X211559Y1540593D01*
X211684Y1541676D01*
X212809D01*
G01X202566Y1633613D02*
Y1636113D01*
X203607D01*
X203941Y1635988D01*
X204149Y1635821D01*
X204232Y1635488D01*
X204149Y1635155D01*
X203899Y1634946D01*
X203607Y1634821D01*
X202566D01*
G01X203607D02*
X204232Y1633613D01*
G01X205707Y1635696D02*
X205957Y1635946D01*
X206249Y1636071D01*
X206582Y1636113D01*
X206999Y1636030D01*
X207291Y1635821D01*
X207374Y1635571D01*
X207332Y1635321D01*
X207166Y1635113D01*
X206332Y1634696D01*
X205957Y1634405D01*
X205707Y1633988D01*
X205624Y1633613D01*
X207374D01*
G01X210099D02*
Y1636113D01*
X208557Y1634321D01*
X210641D01*
G01X212699Y1633613D02*
X212991Y1633655D01*
X213324Y1633780D01*
X213532Y1633988D01*
X213616Y1634280D01*
X213532Y1634571D01*
X213282Y1634821D01*
X212907Y1634946D01*
X212491D01*
X212241Y1635030D01*
X212032Y1635238D01*
X211949Y1635530D01*
X212074Y1635821D01*
X212366Y1636030D01*
X212699Y1636113D01*
X213032Y1636030D01*
X213324Y1635821D01*
X213449Y1635530D01*
X213366Y1635238D01*
X213157Y1635030D01*
X212907Y1634946D01*
X212491D01*
X212116Y1634821D01*
X211866Y1634571D01*
X211782Y1634280D01*
X211866Y1633988D01*
X212074Y1633780D01*
X212407Y1633655D01*
X212699Y1633613D01*
G01X193349Y1637113D02*
Y1633113D01*
X200749D01*
G01X202566Y1629113D02*
Y1631613D01*
X203607D01*
X203941Y1631488D01*
X204149Y1631321D01*
X204232Y1630988D01*
X204149Y1630655D01*
X203899Y1630446D01*
X203607Y1630321D01*
X202566D01*
G01X203607D02*
X204232Y1629113D01*
G01X205707Y1631196D02*
X205957Y1631446D01*
X206249Y1631571D01*
X206582Y1631613D01*
X206999Y1631530D01*
X207291Y1631321D01*
X207374Y1631071D01*
X207332Y1630821D01*
X207166Y1630613D01*
X206332Y1630196D01*
X205957Y1629905D01*
X205707Y1629488D01*
X205624Y1629113D01*
X207374D01*
G01X210099D02*
Y1631613D01*
X208557Y1629821D01*
X210641D01*
G01X211991Y1629405D02*
X212282Y1629196D01*
X212616Y1629113D01*
X212949Y1629196D01*
X213241Y1629446D01*
X213449Y1629821D01*
X213532Y1630196D01*
Y1630655D01*
X213449Y1631030D01*
X213241Y1631363D01*
X212991Y1631530D01*
X212699Y1631613D01*
X212366Y1631530D01*
X212116Y1631363D01*
X211949Y1631113D01*
X211866Y1630780D01*
X211949Y1630488D01*
X212157Y1630196D01*
X212407Y1630030D01*
X212699Y1629988D01*
X213032Y1630071D01*
X213282Y1630280D01*
X213532Y1630655D01*
G01X193349Y1632613D02*
Y1628613D01*
X200749D01*
G01X190399Y1644727D02*
Y1656127D01*
G01X191000Y1658017D02*
X188500D01*
Y1659058D01*
X188625Y1659392D01*
X188792Y1659600D01*
X189125Y1659683D01*
X189458Y1659600D01*
X189667Y1659350D01*
X189792Y1659058D01*
Y1658017D01*
G01Y1659058D02*
X191000Y1659683D01*
G01Y1662450D02*
X188500D01*
X190292Y1660908D01*
Y1662992D01*
G01X191000Y1665050D02*
X188500D01*
X189000Y1664550D01*
G01X191000D02*
Y1665550D01*
G01Y1668150D02*
X190958Y1668442D01*
X190833Y1668775D01*
X190625Y1668983D01*
X190333Y1669067D01*
X190042Y1668983D01*
X189792Y1668733D01*
X189667Y1668358D01*
Y1667942D01*
X189583Y1667692D01*
X189375Y1667483D01*
X189083Y1667400D01*
X188792Y1667525D01*
X188583Y1667817D01*
X188500Y1668150D01*
X188583Y1668483D01*
X188792Y1668775D01*
X189083Y1668900D01*
X189375Y1668817D01*
X189583Y1668608D01*
X189667Y1668358D01*
Y1667942D01*
X189792Y1667567D01*
X190042Y1667317D01*
X190333Y1667233D01*
X190625Y1667317D01*
X190833Y1667525D01*
X190958Y1667858D01*
X191000Y1668150D01*
G01X190800Y1649100D02*
X194800D01*
Y1656500D01*
G01X190916Y1682050D02*
Y1687050D01*
X194082D01*
G01X192916Y1684633D02*
X190916D01*
G01X196516Y1686217D02*
X197016Y1686717D01*
X197599Y1686967D01*
X198266Y1687050D01*
X199099Y1686883D01*
X199682Y1686467D01*
X199849Y1685967D01*
X199766Y1685467D01*
X199432Y1685050D01*
X197766Y1684217D01*
X197016Y1683633D01*
X196516Y1682800D01*
X196349Y1682050D01*
X199849D01*
G01X203699D02*
Y1687050D01*
X202699Y1686050D01*
G01Y1682050D02*
X204699D01*
G01X209299Y1681883D02*
X209132Y1681967D01*
Y1682133D01*
X209299Y1682217D01*
X209466Y1682133D01*
Y1681967D01*
X209299Y1681883D01*
G01Y1684133D02*
X209132Y1684217D01*
Y1684383D01*
X209299Y1684467D01*
X209466Y1684383D01*
Y1684217D01*
X209299Y1684133D01*
G01X213316Y1686217D02*
X213816Y1686717D01*
X214399Y1686967D01*
X215066Y1687050D01*
X215899Y1686883D01*
X216482Y1686467D01*
X216649Y1685967D01*
X216566Y1685467D01*
X216232Y1685050D01*
X214566Y1684217D01*
X213816Y1683633D01*
X213316Y1682800D01*
X213149Y1682050D01*
X216649D01*
G01X218416D02*
X220499Y1687050D01*
X222582Y1682050D01*
G01X221832Y1683800D02*
X219166D01*
G01X224599Y1681883D02*
X227599Y1687050D01*
G01X230116Y1684133D02*
X230699Y1684717D01*
X231199Y1685050D01*
X231866Y1685217D01*
X232449Y1685050D01*
X232866Y1684717D01*
X233199Y1684217D01*
X233282Y1683633D01*
X233199Y1683133D01*
X232866Y1682633D01*
X232366Y1682217D01*
X231782Y1682050D01*
X231116Y1682217D01*
X230532Y1682717D01*
X230199Y1683467D01*
X230116Y1684300D01*
X230282Y1685383D01*
X230532Y1685967D01*
X230949Y1686550D01*
X231532Y1686967D01*
X232116Y1687050D01*
X232699Y1686883D01*
X233116Y1686467D01*
G01X235216Y1687050D02*
X237299Y1682050D01*
X239382Y1687050D01*
G01X190916Y1673550D02*
Y1678550D01*
X194082D01*
G01X192916Y1676133D02*
X190916D01*
G01X196516Y1677717D02*
X197016Y1678217D01*
X197599Y1678467D01*
X198266Y1678550D01*
X199099Y1678383D01*
X199682Y1677967D01*
X199849Y1677467D01*
X199766Y1676967D01*
X199432Y1676550D01*
X197766Y1675717D01*
X197016Y1675133D01*
X196516Y1674300D01*
X196349Y1673550D01*
X199849D01*
G01X202116Y1677717D02*
X202616Y1678217D01*
X203199Y1678467D01*
X203866Y1678550D01*
X204699Y1678383D01*
X205282Y1677967D01*
X205449Y1677467D01*
X205366Y1676967D01*
X205032Y1676550D01*
X203366Y1675717D01*
X202616Y1675133D01*
X202116Y1674300D01*
X201949Y1673550D01*
X205449D01*
G01X209299Y1673383D02*
X209132Y1673467D01*
Y1673633D01*
X209299Y1673717D01*
X209466Y1673633D01*
Y1673467D01*
X209299Y1673383D01*
G01Y1675633D02*
X209132Y1675717D01*
Y1675883D01*
X209299Y1675967D01*
X209466Y1675883D01*
Y1675717D01*
X209299Y1675633D01*
G01X213066Y1674550D02*
X213566Y1673967D01*
X214232Y1673633D01*
X214982Y1673550D01*
X215649Y1673633D01*
X216316Y1674050D01*
X216732Y1674550D01*
X216816Y1675050D01*
X216649Y1675633D01*
X216066Y1676050D01*
X215482Y1676217D01*
X214732D01*
G01X215482D02*
X215982Y1676467D01*
X216399Y1676883D01*
X216566Y1677383D01*
X216399Y1677883D01*
X215982Y1678300D01*
X215232Y1678550D01*
X214482Y1678467D01*
X213732Y1678133D01*
G01X218416Y1673550D02*
X220499Y1678550D01*
X222582Y1673550D01*
G01X221832Y1675300D02*
X219166D01*
G01X224599Y1673383D02*
X227599Y1678550D01*
G01X231699Y1673550D02*
Y1678550D01*
X230699Y1677550D01*
G01Y1673550D02*
X232699D01*
G01X235466Y1674300D02*
X235966Y1673883D01*
X236549Y1673633D01*
X237299Y1673550D01*
X238049Y1673717D01*
X238632Y1674050D01*
X239049Y1674633D01*
X239132Y1675300D01*
X238966Y1675967D01*
X238549Y1676383D01*
X237966Y1676717D01*
X237382Y1676800D01*
X236799Y1676717D01*
X236049Y1676383D01*
X236299Y1678550D01*
X238549D01*
G01X240816D02*
X242899Y1673550D01*
X244982Y1678550D01*
G01X199899Y1771550D02*
X199566Y1771592D01*
X199274Y1771758D01*
X199024Y1772008D01*
X198857Y1772300D01*
X198774Y1772633D01*
Y1772967D01*
X198857Y1773300D01*
X199024Y1773592D01*
X199274Y1773842D01*
X199566Y1774008D01*
X199899Y1774050D01*
X200232Y1774008D01*
X200524Y1773842D01*
X200774Y1773592D01*
X200941Y1773300D01*
X201024Y1772967D01*
Y1772633D01*
X200941Y1772300D01*
X200774Y1772008D01*
X200524Y1771758D01*
X200232Y1771592D01*
X199899Y1771550D01*
G01X200232Y1772217D02*
X200732Y1771550D01*
G01X202082Y1772050D02*
X202332Y1771758D01*
X202666Y1771592D01*
X203041Y1771550D01*
X203374Y1771592D01*
X203707Y1771800D01*
X203916Y1772050D01*
X203957Y1772300D01*
X203874Y1772592D01*
X203582Y1772800D01*
X203291Y1772883D01*
X202916D01*
G01X203291D02*
X203541Y1773008D01*
X203749Y1773217D01*
X203832Y1773467D01*
X203749Y1773717D01*
X203541Y1773925D01*
X203166Y1774050D01*
X202791Y1774008D01*
X202416Y1773842D01*
G01X205391Y1771842D02*
X205682Y1771633D01*
X206016Y1771550D01*
X206349Y1771633D01*
X206641Y1771883D01*
X206849Y1772258D01*
X206932Y1772633D01*
Y1773092D01*
X206849Y1773467D01*
X206641Y1773800D01*
X206391Y1773967D01*
X206099Y1774050D01*
X205766Y1773967D01*
X205516Y1773800D01*
X205349Y1773550D01*
X205266Y1773217D01*
X205349Y1772925D01*
X205557Y1772633D01*
X205807Y1772467D01*
X206099Y1772425D01*
X206432Y1772508D01*
X206682Y1772717D01*
X206932Y1773092D01*
G01X197299Y1776000D02*
Y1789000D01*
G01X211831Y1867850D02*
X221831D01*
G01Y1860850D02*
X211831D01*
G01X216831D02*
Y1867850D01*
G01X211831Y1857417D02*
X221831D01*
Y1854083D01*
X221331Y1852750D01*
X220664Y1851750D01*
X219664Y1850917D01*
X218497Y1850250D01*
X216831Y1850083D01*
X215164Y1850250D01*
X213998Y1850917D01*
X212997Y1851750D01*
X212331Y1852750D01*
X211831Y1854083D01*
Y1857417D01*
G01Y1846817D02*
X221831D01*
Y1843483D01*
X221331Y1842150D01*
X220664Y1841150D01*
X219664Y1840317D01*
X218497Y1839650D01*
X216831Y1839483D01*
X215164Y1839650D01*
X213998Y1840317D01*
X212997Y1841150D01*
X212331Y1842150D01*
X211831Y1843483D01*
Y1846817D01*
G01X213331Y1836217D02*
X212498Y1835217D01*
X211998Y1834050D01*
X211831Y1832550D01*
X212164Y1831050D01*
X212831Y1829883D01*
X213998Y1829050D01*
X215331Y1828883D01*
X216664Y1829217D01*
X217498Y1830050D01*
X218164Y1831217D01*
X218331Y1832383D01*
X218164Y1833550D01*
X217498Y1835050D01*
X221831Y1834550D01*
Y1830050D01*
G01X209208Y1889767D02*
X209083Y1889517D01*
X209000Y1889225D01*
Y1888892D01*
X209125Y1888517D01*
X209333Y1888225D01*
X209583Y1888017D01*
X210000Y1887850D01*
X210375Y1887808D01*
X210750Y1887892D01*
X211000Y1888017D01*
X211250Y1888267D01*
X211417Y1888558D01*
X211500Y1888850D01*
Y1889142D01*
X211417Y1889433D01*
X211292Y1889683D01*
X211125Y1889892D01*
G01X211500Y1891950D02*
X209000D01*
X209500Y1891450D01*
G01X211500D02*
Y1892450D01*
G01X211208Y1894342D02*
X211417Y1894633D01*
X211500Y1894967D01*
X211417Y1895300D01*
X211167Y1895592D01*
X210792Y1895800D01*
X210417Y1895883D01*
X209958D01*
X209583Y1895800D01*
X209250Y1895592D01*
X209083Y1895342D01*
X209000Y1895050D01*
X209083Y1894717D01*
X209250Y1894467D01*
X209500Y1894300D01*
X209833Y1894217D01*
X210125Y1894300D01*
X210417Y1894508D01*
X210583Y1894758D01*
X210625Y1895050D01*
X210542Y1895383D01*
X210333Y1895633D01*
X209958Y1895883D01*
G01X209000Y1898150D02*
X209083Y1897817D01*
X209292Y1897567D01*
X209542Y1897400D01*
X209875Y1897275D01*
X210250Y1897233D01*
X210625Y1897275D01*
X210958Y1897400D01*
X211208Y1897567D01*
X211417Y1897817D01*
X211500Y1898150D01*
X211417Y1898483D01*
X211208Y1898733D01*
X210958Y1898900D01*
X210625Y1899025D01*
X210250Y1899067D01*
X209875Y1899025D01*
X209542Y1898900D01*
X209292Y1898733D01*
X209083Y1898483D01*
X209000Y1898150D01*
G01X203500Y1888017D02*
X201000D01*
Y1889058D01*
X201125Y1889392D01*
X201292Y1889600D01*
X201625Y1889683D01*
X201958Y1889600D01*
X202167Y1889350D01*
X202292Y1889058D01*
Y1888017D01*
G01Y1889058D02*
X203500Y1889683D01*
G01Y1891950D02*
X201000D01*
X201500Y1891450D01*
G01X203500D02*
Y1892450D01*
G01Y1894967D02*
X202958Y1895050D01*
X202500Y1895175D01*
X202083Y1895342D01*
X201625Y1895550D01*
X201000Y1895883D01*
Y1894217D01*
G01X202458Y1897358D02*
X202167Y1897650D01*
X202000Y1897900D01*
X201917Y1898233D01*
X202000Y1898525D01*
X202167Y1898733D01*
X202417Y1898900D01*
X202708Y1898942D01*
X202958Y1898900D01*
X203208Y1898733D01*
X203417Y1898483D01*
X203500Y1898192D01*
X203417Y1897858D01*
X203167Y1897567D01*
X202792Y1897400D01*
X202375Y1897358D01*
X201833Y1897442D01*
X201542Y1897567D01*
X201250Y1897775D01*
X201042Y1898067D01*
X201000Y1898358D01*
X201083Y1898650D01*
X201292Y1898858D01*
G01X207500Y1888017D02*
X205000D01*
Y1889058D01*
X205125Y1889392D01*
X205292Y1889600D01*
X205625Y1889683D01*
X205958Y1889600D01*
X206167Y1889350D01*
X206292Y1889058D01*
Y1888017D01*
G01Y1889058D02*
X207500Y1889683D01*
G01Y1891950D02*
X205000D01*
X205500Y1891450D01*
G01X207500D02*
Y1892450D01*
G01Y1894967D02*
X206958Y1895050D01*
X206500Y1895175D01*
X206083Y1895342D01*
X205625Y1895550D01*
X205000Y1895883D01*
Y1894217D01*
G01X207500Y1898067D02*
X206958Y1898150D01*
X206500Y1898275D01*
X206083Y1898442D01*
X205625Y1898650D01*
X205000Y1898983D01*
Y1897317D01*
G01X202707Y1921817D02*
X202582Y1921567D01*
X202499Y1921275D01*
Y1920942D01*
X202624Y1920567D01*
X202832Y1920275D01*
X203082Y1920067D01*
X203499Y1919900D01*
X203874Y1919858D01*
X204249Y1919942D01*
X204499Y1920067D01*
X204749Y1920317D01*
X204916Y1920608D01*
X204999Y1920900D01*
Y1921192D01*
X204916Y1921483D01*
X204791Y1921733D01*
X204624Y1921942D01*
G01X204999Y1924000D02*
X202499D01*
X202999Y1923500D01*
G01X204999D02*
Y1924500D01*
G01Y1927100D02*
X204957Y1927392D01*
X204832Y1927725D01*
X204624Y1927933D01*
X204332Y1928017D01*
X204041Y1927933D01*
X203791Y1927683D01*
X203666Y1927308D01*
Y1926892D01*
X203582Y1926642D01*
X203374Y1926433D01*
X203082Y1926350D01*
X202791Y1926475D01*
X202582Y1926767D01*
X202499Y1927100D01*
X202582Y1927433D01*
X202791Y1927725D01*
X203082Y1927850D01*
X203374Y1927767D01*
X203582Y1927558D01*
X203666Y1927308D01*
Y1926892D01*
X203791Y1926517D01*
X204041Y1926267D01*
X204332Y1926183D01*
X204624Y1926267D01*
X204832Y1926475D01*
X204957Y1926808D01*
X204999Y1927100D01*
G01Y1930200D02*
X204957Y1930492D01*
X204832Y1930825D01*
X204624Y1931033D01*
X204332Y1931117D01*
X204041Y1931033D01*
X203791Y1930783D01*
X203666Y1930408D01*
Y1929992D01*
X203582Y1929742D01*
X203374Y1929533D01*
X203082Y1929450D01*
X202791Y1929575D01*
X202582Y1929867D01*
X202499Y1930200D01*
X202582Y1930533D01*
X202791Y1930825D01*
X203082Y1930950D01*
X203374Y1930867D01*
X203582Y1930658D01*
X203666Y1930408D01*
Y1929992D01*
X203791Y1929617D01*
X204041Y1929367D01*
X204332Y1929283D01*
X204624Y1929367D01*
X204832Y1929575D01*
X204957Y1929908D01*
X204999Y1930200D01*
G01X206708Y1921767D02*
X206583Y1921517D01*
X206500Y1921225D01*
Y1920892D01*
X206625Y1920517D01*
X206833Y1920225D01*
X207083Y1920017D01*
X207500Y1919850D01*
X207875Y1919808D01*
X208250Y1919892D01*
X208500Y1920017D01*
X208750Y1920267D01*
X208917Y1920558D01*
X209000Y1920850D01*
Y1921142D01*
X208917Y1921433D01*
X208792Y1921683D01*
X208625Y1921892D01*
G01X209000Y1923950D02*
X206500D01*
X207000Y1923450D01*
G01X209000D02*
Y1924450D01*
G01Y1927050D02*
X208958Y1927342D01*
X208833Y1927675D01*
X208625Y1927883D01*
X208333Y1927967D01*
X208042Y1927883D01*
X207792Y1927633D01*
X207667Y1927258D01*
Y1926842D01*
X207583Y1926592D01*
X207375Y1926383D01*
X207083Y1926300D01*
X206792Y1926425D01*
X206583Y1926717D01*
X206500Y1927050D01*
X206583Y1927383D01*
X206792Y1927675D01*
X207083Y1927800D01*
X207375Y1927717D01*
X207583Y1927508D01*
X207667Y1927258D01*
Y1926842D01*
X207792Y1926467D01*
X208042Y1926217D01*
X208333Y1926133D01*
X208625Y1926217D01*
X208833Y1926425D01*
X208958Y1926758D01*
X209000Y1927050D01*
G01X208708Y1929442D02*
X208917Y1929733D01*
X209000Y1930067D01*
X208917Y1930400D01*
X208667Y1930692D01*
X208292Y1930900D01*
X207917Y1930983D01*
X207458D01*
X207083Y1930900D01*
X206750Y1930692D01*
X206583Y1930442D01*
X206500Y1930150D01*
X206583Y1929817D01*
X206750Y1929567D01*
X207000Y1929400D01*
X207333Y1929317D01*
X207625Y1929400D01*
X207917Y1929608D01*
X208083Y1929858D01*
X208125Y1930150D01*
X208042Y1930483D01*
X207833Y1930733D01*
X207458Y1930983D01*
G01X208499Y1937567D02*
X205999D01*
Y1938608D01*
X206124Y1938942D01*
X206291Y1939150D01*
X206624Y1939233D01*
X206957Y1939150D01*
X207166Y1938900D01*
X207291Y1938608D01*
Y1937567D01*
G01Y1938608D02*
X208499Y1939233D01*
G01Y1941500D02*
X205999D01*
X206499Y1941000D01*
G01X208499D02*
Y1942000D01*
G01Y1944517D02*
X207957Y1944600D01*
X207499Y1944725D01*
X207082Y1944892D01*
X206624Y1945100D01*
X205999Y1945433D01*
Y1943767D01*
G01X208499Y1947700D02*
X208457Y1947992D01*
X208332Y1948325D01*
X208124Y1948533D01*
X207832Y1948617D01*
X207541Y1948533D01*
X207291Y1948283D01*
X207166Y1947908D01*
Y1947492D01*
X207082Y1947242D01*
X206874Y1947033D01*
X206582Y1946950D01*
X206291Y1947075D01*
X206082Y1947367D01*
X205999Y1947700D01*
X206082Y1948033D01*
X206291Y1948325D01*
X206582Y1948450D01*
X206874Y1948367D01*
X207082Y1948158D01*
X207166Y1947908D01*
Y1947492D01*
X207291Y1947117D01*
X207541Y1946867D01*
X207832Y1946783D01*
X208124Y1946867D01*
X208332Y1947075D01*
X208457Y1947408D01*
X208499Y1947700D01*
G01X225299Y34450D02*
Y44650D01*
G01Y34450D02*
Y44650D01*
G01X219526Y58528D02*
X224526D01*
Y63528D01*
G01X223519Y68591D02*
X225519D01*
G01X235572Y90572D02*
Y94572D01*
X228172D01*
G01X211735Y90552D02*
Y88052D01*
G01X210777Y90552D02*
X212693D01*
G01X214002Y88052D02*
Y90552D01*
X215002D01*
X215335Y90427D01*
X215585Y90135D01*
X215668Y89802D01*
X215585Y89469D01*
X215377Y89219D01*
X215002Y89094D01*
X214002D01*
G01X217143Y90135D02*
X217393Y90385D01*
X217685Y90510D01*
X218018Y90552D01*
X218435Y90469D01*
X218727Y90260D01*
X218810Y90010D01*
X218768Y89760D01*
X218602Y89552D01*
X217768Y89135D01*
X217393Y88844D01*
X217143Y88427D01*
X217060Y88052D01*
X218810D01*
G01X221035Y90552D02*
X220702Y90469D01*
X220452Y90260D01*
X220285Y90010D01*
X220160Y89677D01*
X220118Y89302D01*
X220160Y88927D01*
X220285Y88594D01*
X220452Y88344D01*
X220702Y88135D01*
X221035Y88052D01*
X221368Y88135D01*
X221618Y88344D01*
X221785Y88594D01*
X221910Y88927D01*
X221952Y89302D01*
X221910Y89677D01*
X221785Y90010D01*
X221618Y90260D01*
X221368Y90469D01*
X221035Y90552D01*
G01X224526Y81528D02*
Y86528D01*
X219526D01*
G01X223519Y78434D02*
X226519D01*
G01X214499Y105567D02*
X211999D01*
Y106567D01*
X212124Y106900D01*
X212416Y107150D01*
X212749Y107233D01*
X213082Y107150D01*
X213332Y106942D01*
X213457Y106567D01*
Y105567D01*
G01X212207Y110417D02*
X212082Y110167D01*
X211999Y109875D01*
Y109542D01*
X212124Y109167D01*
X212332Y108875D01*
X212582Y108667D01*
X212999Y108500D01*
X213374Y108458D01*
X213749Y108542D01*
X213999Y108667D01*
X214249Y108917D01*
X214416Y109208D01*
X214499Y109500D01*
Y109792D01*
X214416Y110083D01*
X214291Y110333D01*
X214124Y110542D01*
G01X214499Y112600D02*
X211999D01*
X212499Y112100D01*
G01X214499D02*
Y113100D01*
G01X214207Y114992D02*
X214416Y115283D01*
X214499Y115617D01*
X214416Y115950D01*
X214166Y116242D01*
X213791Y116450D01*
X213416Y116533D01*
X212957D01*
X212582Y116450D01*
X212249Y116242D01*
X212082Y115992D01*
X211999Y115700D01*
X212082Y115367D01*
X212249Y115117D01*
X212499Y114950D01*
X212832Y114867D01*
X213124Y114950D01*
X213416Y115158D01*
X213582Y115408D01*
X213624Y115700D01*
X213541Y116033D01*
X213332Y116283D01*
X212957Y116533D01*
G01X228299Y103050D02*
Y99050D01*
X235699D01*
G01Y103050D02*
Y107050D01*
X228299D01*
G01X226389Y109072D02*
Y111572D01*
X227389D01*
X227722Y111447D01*
X227972Y111155D01*
X228055Y110822D01*
X227972Y110489D01*
X227764Y110239D01*
X227389Y110114D01*
X226389D01*
G01X229489Y109072D02*
Y111572D01*
X230530D01*
X230864Y111447D01*
X231072Y111280D01*
X231155Y110947D01*
X231072Y110614D01*
X230822Y110405D01*
X230530Y110280D01*
X229489D01*
G01X230530D02*
X231155Y109072D01*
G01X232630Y111155D02*
X232880Y111405D01*
X233172Y111530D01*
X233505Y111572D01*
X233922Y111489D01*
X234214Y111280D01*
X234297Y111030D01*
X234255Y110780D01*
X234089Y110572D01*
X233255Y110155D01*
X232880Y109864D01*
X232630Y109447D01*
X232547Y109072D01*
X234297D01*
G01X236522D02*
X236814Y109114D01*
X237147Y109239D01*
X237355Y109447D01*
X237439Y109739D01*
X237355Y110030D01*
X237105Y110280D01*
X236730Y110405D01*
X236314D01*
X236064Y110489D01*
X235855Y110697D01*
X235772Y110989D01*
X235897Y111280D01*
X236189Y111489D01*
X236522Y111572D01*
X236855Y111489D01*
X237147Y111280D01*
X237272Y110989D01*
X237189Y110697D01*
X236980Y110489D01*
X236730Y110405D01*
X236314D01*
X235939Y110280D01*
X235689Y110030D01*
X235605Y109739D01*
X235689Y109447D01*
X235897Y109239D01*
X236230Y109114D01*
X236522Y109072D01*
G01X218499Y105567D02*
X215999D01*
Y106567D01*
X216124Y106900D01*
X216416Y107150D01*
X216749Y107233D01*
X217082Y107150D01*
X217332Y106942D01*
X217457Y106567D01*
Y105567D01*
G01X218499Y108667D02*
X215999D01*
Y109708D01*
X216124Y110042D01*
X216291Y110250D01*
X216624Y110333D01*
X216957Y110250D01*
X217166Y110000D01*
X217291Y109708D01*
Y108667D01*
G01Y109708D02*
X218499Y110333D01*
G01X216416Y111808D02*
X216166Y112058D01*
X216041Y112350D01*
X215999Y112683D01*
X216082Y113100D01*
X216291Y113392D01*
X216541Y113475D01*
X216791Y113433D01*
X216999Y113267D01*
X217416Y112433D01*
X217707Y112058D01*
X218124Y111808D01*
X218499Y111725D01*
Y113475D01*
G01X218207Y114992D02*
X218416Y115283D01*
X218499Y115617D01*
X218416Y115950D01*
X218166Y116242D01*
X217791Y116450D01*
X217416Y116533D01*
X216957D01*
X216582Y116450D01*
X216249Y116242D01*
X216082Y115992D01*
X215999Y115700D01*
X216082Y115367D01*
X216249Y115117D01*
X216499Y114950D01*
X216832Y114867D01*
X217124Y114950D01*
X217416Y115158D01*
X217582Y115408D01*
X217624Y115700D01*
X217541Y116033D01*
X217332Y116283D01*
X216957Y116533D01*
G01X215499Y95850D02*
X219499D01*
Y103250D01*
G01X226516Y113550D02*
Y116050D01*
X227516D01*
X227849Y115925D01*
X228099Y115633D01*
X228182Y115300D01*
X228099Y114967D01*
X227891Y114717D01*
X227516Y114592D01*
X226516D01*
G01X229616Y113550D02*
Y116050D01*
X230657D01*
X230991Y115925D01*
X231199Y115758D01*
X231282Y115425D01*
X231199Y115092D01*
X230949Y114883D01*
X230657Y114758D01*
X229616D01*
G01X230657D02*
X231282Y113550D01*
G01X232632Y114050D02*
X232882Y113758D01*
X233216Y113592D01*
X233591Y113550D01*
X233924Y113592D01*
X234257Y113800D01*
X234466Y114050D01*
X234507Y114300D01*
X234424Y114592D01*
X234132Y114800D01*
X233841Y114883D01*
X233466D01*
G01X233841D02*
X234091Y115008D01*
X234299Y115217D01*
X234382Y115467D01*
X234299Y115717D01*
X234091Y115925D01*
X233716Y116050D01*
X233341Y116008D01*
X232966Y115842D01*
G01X236649Y116050D02*
X236316Y115967D01*
X236066Y115758D01*
X235899Y115508D01*
X235774Y115175D01*
X235732Y114800D01*
X235774Y114425D01*
X235899Y114092D01*
X236066Y113842D01*
X236316Y113633D01*
X236649Y113550D01*
X236982Y113633D01*
X237232Y113842D01*
X237399Y114092D01*
X237524Y114425D01*
X237566Y114800D01*
X237524Y115175D01*
X237399Y115508D01*
X237232Y115758D01*
X236982Y115967D01*
X236649Y116050D01*
G01X228299Y99050D02*
Y95050D01*
X235699D01*
G01X226516Y117550D02*
Y120050D01*
X227516D01*
X227849Y119925D01*
X228099Y119633D01*
X228182Y119300D01*
X228099Y118967D01*
X227891Y118717D01*
X227516Y118592D01*
X226516D01*
G01X229616Y117550D02*
Y120050D01*
X230657D01*
X230991Y119925D01*
X231199Y119758D01*
X231282Y119425D01*
X231199Y119092D01*
X230949Y118883D01*
X230657Y118758D01*
X229616D01*
G01X230657D02*
X231282Y117550D01*
G01X233549D02*
Y120050D01*
X233049Y119550D01*
G01Y117550D02*
X234049D01*
G01X236649D02*
X236941Y117592D01*
X237274Y117717D01*
X237482Y117925D01*
X237566Y118217D01*
X237482Y118508D01*
X237232Y118758D01*
X236857Y118883D01*
X236441D01*
X236191Y118967D01*
X235982Y119175D01*
X235899Y119467D01*
X236024Y119758D01*
X236316Y119967D01*
X236649Y120050D01*
X236982Y119967D01*
X237274Y119758D01*
X237399Y119467D01*
X237316Y119175D01*
X237107Y118967D01*
X236857Y118883D01*
X236441D01*
X236066Y118758D01*
X235816Y118508D01*
X235732Y118217D01*
X235816Y117925D01*
X236024Y117717D01*
X236357Y117592D01*
X236649Y117550D01*
G01X226516Y121550D02*
Y124050D01*
X227516D01*
X227849Y123925D01*
X228099Y123633D01*
X228182Y123300D01*
X228099Y122967D01*
X227891Y122717D01*
X227516Y122592D01*
X226516D01*
G01X229616Y121550D02*
Y124050D01*
X230657D01*
X230991Y123925D01*
X231199Y123758D01*
X231282Y123425D01*
X231199Y123092D01*
X230949Y122883D01*
X230657Y122758D01*
X229616D01*
G01X230657D02*
X231282Y121550D01*
G01X232757Y123633D02*
X233007Y123883D01*
X233299Y124008D01*
X233632Y124050D01*
X234049Y123967D01*
X234341Y123758D01*
X234424Y123508D01*
X234382Y123258D01*
X234216Y123050D01*
X233382Y122633D01*
X233007Y122342D01*
X232757Y121925D01*
X232674Y121550D01*
X234424D01*
G01X235857Y123633D02*
X236107Y123883D01*
X236399Y124008D01*
X236732Y124050D01*
X237149Y123967D01*
X237441Y123758D01*
X237524Y123508D01*
X237482Y123258D01*
X237316Y123050D01*
X236482Y122633D01*
X236107Y122342D01*
X235857Y121925D01*
X235774Y121550D01*
X237524D01*
G01X214999Y156050D02*
Y166050D01*
G01X221999D02*
Y156050D01*
G01Y161050D02*
X214999D01*
G01X225432Y156050D02*
Y166050D01*
X228766D01*
X230099Y165550D01*
X231099Y164883D01*
X231932Y163883D01*
X232599Y162716D01*
X232766Y161050D01*
X232599Y159383D01*
X231932Y158217D01*
X231099Y157216D01*
X230099Y156550D01*
X228766Y156050D01*
X225432D01*
G01X236032D02*
Y166050D01*
X239366D01*
X240699Y165550D01*
X241699Y164883D01*
X242532Y163883D01*
X243199Y162716D01*
X243366Y161050D01*
X243199Y159383D01*
X242532Y158217D01*
X241699Y157216D01*
X240699Y156550D01*
X239366Y156050D01*
X236032D01*
G01X247466Y157216D02*
X248632Y156383D01*
X249966Y156050D01*
X251299Y156383D01*
X252466Y157383D01*
X253299Y158883D01*
X253632Y160383D01*
Y162217D01*
X253299Y163717D01*
X252466Y165050D01*
X251466Y165717D01*
X250299Y166050D01*
X248965Y165717D01*
X247966Y165050D01*
X247299Y164050D01*
X246966Y162716D01*
X247299Y161550D01*
X248132Y160383D01*
X249132Y159716D01*
X250299Y159550D01*
X251632Y159883D01*
X252632Y160717D01*
X253632Y162217D01*
G01X255899Y152717D02*
X265899D01*
G01X268166Y166050D02*
Y156050D01*
X274832D01*
G01X285432D02*
X278766D01*
Y166050D01*
X285432D01*
G01X282766Y161217D02*
X278766D01*
G01X289032Y156050D02*
Y166050D01*
X292366D01*
X293699Y165550D01*
X294699Y164883D01*
X295532Y163883D01*
X296199Y162716D01*
X296366Y161050D01*
X296199Y159383D01*
X295532Y158217D01*
X294699Y157216D01*
X293699Y156550D01*
X292366Y156050D01*
X289032D01*
G01X224517Y257000D02*
Y259500D01*
X225558D01*
X225892Y259375D01*
X226100Y259208D01*
X226183Y258875D01*
X226100Y258542D01*
X225850Y258333D01*
X225558Y258208D01*
X224517D01*
G01X225558D02*
X226183Y257000D01*
G01X227658Y259083D02*
X227908Y259333D01*
X228200Y259458D01*
X228533Y259500D01*
X228950Y259417D01*
X229242Y259208D01*
X229325Y258958D01*
X229283Y258708D01*
X229117Y258500D01*
X228283Y258083D01*
X227908Y257792D01*
X227658Y257375D01*
X227575Y257000D01*
X229325D01*
G01X230633Y257500D02*
X230883Y257208D01*
X231217Y257042D01*
X231592Y257000D01*
X231925Y257042D01*
X232258Y257250D01*
X232467Y257500D01*
X232508Y257750D01*
X232425Y258042D01*
X232133Y258250D01*
X231842Y258333D01*
X231467D01*
G01X231842D02*
X232092Y258458D01*
X232300Y258667D01*
X232383Y258917D01*
X232300Y259167D01*
X232092Y259375D01*
X231717Y259500D01*
X231342Y259458D01*
X230967Y259292D01*
G01X233733Y257375D02*
X233983Y257167D01*
X234275Y257042D01*
X234650Y257000D01*
X235025Y257083D01*
X235317Y257250D01*
X235525Y257542D01*
X235567Y257875D01*
X235483Y258208D01*
X235275Y258417D01*
X234983Y258583D01*
X234692Y258625D01*
X234400Y258583D01*
X234025Y258417D01*
X234150Y259500D01*
X235275D01*
G01X224517Y253000D02*
Y255500D01*
X225558D01*
X225892Y255375D01*
X226100Y255208D01*
X226183Y254875D01*
X226100Y254542D01*
X225850Y254333D01*
X225558Y254208D01*
X224517D01*
G01X225558D02*
X226183Y253000D01*
G01X227533Y253500D02*
X227783Y253208D01*
X228117Y253042D01*
X228492Y253000D01*
X228825Y253042D01*
X229158Y253250D01*
X229367Y253500D01*
X229408Y253750D01*
X229325Y254042D01*
X229033Y254250D01*
X228742Y254333D01*
X228367D01*
G01X228742D02*
X228992Y254458D01*
X229200Y254667D01*
X229283Y254917D01*
X229200Y255167D01*
X228992Y255375D01*
X228617Y255500D01*
X228242Y255458D01*
X227867Y255292D01*
G01X230842Y253292D02*
X231133Y253083D01*
X231467Y253000D01*
X231800Y253083D01*
X232092Y253333D01*
X232300Y253708D01*
X232383Y254083D01*
Y254542D01*
X232300Y254917D01*
X232092Y255250D01*
X231842Y255417D01*
X231550Y255500D01*
X231217Y255417D01*
X230967Y255250D01*
X230800Y255000D01*
X230717Y254667D01*
X230800Y254375D01*
X231008Y254083D01*
X231258Y253917D01*
X231550Y253875D01*
X231883Y253958D01*
X232133Y254167D01*
X232383Y254542D01*
G01X235150Y253000D02*
Y255500D01*
X233608Y253708D01*
X235692D01*
G01X209708Y273767D02*
X209583Y273517D01*
X209500Y273225D01*
Y272892D01*
X209625Y272517D01*
X209833Y272225D01*
X210083Y272017D01*
X210500Y271850D01*
X210875Y271808D01*
X211250Y271892D01*
X211500Y272017D01*
X211750Y272267D01*
X211917Y272558D01*
X212000Y272850D01*
Y273142D01*
X211917Y273433D01*
X211792Y273683D01*
X211625Y273892D01*
G01X209917Y275158D02*
X209667Y275408D01*
X209542Y275700D01*
X209500Y276033D01*
X209583Y276450D01*
X209792Y276742D01*
X210042Y276825D01*
X210292Y276783D01*
X210500Y276617D01*
X210917Y275783D01*
X211208Y275408D01*
X211625Y275158D01*
X212000Y275075D01*
Y276825D01*
G01X211625Y278133D02*
X211833Y278383D01*
X211958Y278675D01*
X212000Y279050D01*
X211917Y279425D01*
X211750Y279717D01*
X211458Y279925D01*
X211125Y279967D01*
X210792Y279883D01*
X210583Y279675D01*
X210417Y279383D01*
X210375Y279092D01*
X210417Y278800D01*
X210583Y278425D01*
X209500Y278550D01*
Y279675D01*
G01X212000Y282650D02*
X209500D01*
X211292Y281108D01*
Y283192D01*
G01X226700Y285000D02*
Y281000D01*
X234100D01*
G01X218000Y267017D02*
X215500D01*
Y268058D01*
X215625Y268392D01*
X215792Y268600D01*
X216125Y268683D01*
X216458Y268600D01*
X216667Y268350D01*
X216792Y268058D01*
Y267017D01*
G01Y268058D02*
X218000Y268683D01*
G01X215917Y270158D02*
X215667Y270408D01*
X215542Y270700D01*
X215500Y271033D01*
X215583Y271450D01*
X215792Y271742D01*
X216042Y271825D01*
X216292Y271783D01*
X216500Y271617D01*
X216917Y270783D01*
X217208Y270408D01*
X217625Y270158D01*
X218000Y270075D01*
Y271825D01*
G01X217500Y273133D02*
X217792Y273383D01*
X217958Y273717D01*
X218000Y274092D01*
X217958Y274425D01*
X217750Y274758D01*
X217500Y274967D01*
X217250Y275008D01*
X216958Y274925D01*
X216750Y274633D01*
X216667Y274342D01*
Y273967D01*
G01Y274342D02*
X216542Y274592D01*
X216333Y274800D01*
X216083Y274883D01*
X215833Y274800D01*
X215625Y274592D01*
X215500Y274217D01*
X215542Y273842D01*
X215708Y273467D01*
G01X218000Y277067D02*
X217458Y277150D01*
X217000Y277275D01*
X216583Y277442D01*
X216125Y277650D01*
X215500Y277983D01*
Y276317D01*
G01X223000Y265900D02*
X222958Y265567D01*
X222792Y265275D01*
X222542Y265025D01*
X222250Y264858D01*
X221917Y264775D01*
X221583D01*
X221250Y264858D01*
X220958Y265025D01*
X220708Y265275D01*
X220542Y265567D01*
X220500Y265900D01*
X220542Y266233D01*
X220708Y266525D01*
X220958Y266775D01*
X221250Y266942D01*
X221583Y267025D01*
X221917D01*
X222250Y266942D01*
X222542Y266775D01*
X222792Y266525D01*
X222958Y266233D01*
X223000Y265900D01*
G01X222333Y266233D02*
X223000Y266733D01*
G01X221958Y268208D02*
X221667Y268500D01*
X221500Y268750D01*
X221417Y269083D01*
X221500Y269375D01*
X221667Y269583D01*
X221917Y269750D01*
X222208Y269792D01*
X222458Y269750D01*
X222708Y269583D01*
X222917Y269333D01*
X223000Y269042D01*
X222917Y268708D01*
X222667Y268417D01*
X222292Y268250D01*
X221875Y268208D01*
X221333Y268292D01*
X221042Y268417D01*
X220750Y268625D01*
X220542Y268917D01*
X220500Y269208D01*
X220583Y269500D01*
X220792Y269708D01*
G01X222625Y271183D02*
X222833Y271433D01*
X222958Y271725D01*
X223000Y272100D01*
X222917Y272475D01*
X222750Y272767D01*
X222458Y272975D01*
X222125Y273017D01*
X221792Y272933D01*
X221583Y272725D01*
X221417Y272433D01*
X221375Y272142D01*
X221417Y271850D01*
X221583Y271475D01*
X220500Y271600D01*
Y272725D01*
G01X225000Y266100D02*
X238000D01*
G01X225000Y280100D02*
Y266100D01*
G01X238000Y280100D02*
X225000D01*
G01X215498Y290114D02*
X241498D01*
G01X215498Y303114D02*
Y290114D01*
G01X241498Y303114D02*
X215498D01*
G01X231698Y285114D02*
Y289114D01*
X224298D01*
G01X221900Y304100D02*
Y309600D01*
G01X229900Y304100D02*
X221900D01*
G01X229900Y309600D02*
Y304100D01*
G01X215498Y323114D02*
X241498D01*
G01X215498Y336114D02*
Y323114D01*
G01X211208Y312767D02*
X211083Y312517D01*
X211000Y312225D01*
Y311892D01*
X211125Y311517D01*
X211333Y311225D01*
X211583Y311017D01*
X212000Y310850D01*
X212375Y310808D01*
X212750Y310892D01*
X213000Y311017D01*
X213250Y311267D01*
X213417Y311558D01*
X213500Y311850D01*
Y312142D01*
X213417Y312433D01*
X213292Y312683D01*
X213125Y312892D01*
G01X211417Y314158D02*
X211167Y314408D01*
X211042Y314700D01*
X211000Y315033D01*
X211083Y315450D01*
X211292Y315742D01*
X211542Y315825D01*
X211792Y315783D01*
X212000Y315617D01*
X212417Y314783D01*
X212708Y314408D01*
X213125Y314158D01*
X213500Y314075D01*
Y315825D01*
G01X213125Y317133D02*
X213333Y317383D01*
X213458Y317675D01*
X213500Y318050D01*
X213417Y318425D01*
X213250Y318717D01*
X212958Y318925D01*
X212625Y318967D01*
X212292Y318883D01*
X212083Y318675D01*
X211917Y318383D01*
X211875Y318092D01*
X211917Y317800D01*
X212083Y317425D01*
X211000Y317550D01*
Y318675D01*
G01X213500Y321150D02*
X211000D01*
X211500Y320650D01*
G01X213500D02*
Y321650D01*
G01X229900Y321700D02*
Y316200D01*
G01X221900Y321700D02*
X229900D01*
G01X221900Y316200D02*
Y321700D01*
G01X241498Y336114D02*
X215498D01*
G01X224998Y337314D02*
Y342814D01*
G01X232998Y337314D02*
X224998D01*
G01X216298D02*
Y342814D01*
G01X224298Y337314D02*
X216298D01*
G01X224298Y342814D02*
Y337314D01*
G01X212807Y356817D02*
X212682Y356567D01*
X212599Y356275D01*
Y355942D01*
X212724Y355567D01*
X212932Y355275D01*
X213182Y355067D01*
X213599Y354900D01*
X213974Y354858D01*
X214349Y354942D01*
X214599Y355067D01*
X214849Y355317D01*
X215016Y355608D01*
X215099Y355900D01*
Y356192D01*
X215016Y356483D01*
X214891Y356733D01*
X214724Y356942D01*
G01X213016Y358208D02*
X212766Y358458D01*
X212641Y358750D01*
X212599Y359083D01*
X212682Y359500D01*
X212891Y359792D01*
X213141Y359875D01*
X213391Y359833D01*
X213599Y359667D01*
X214016Y358833D01*
X214307Y358458D01*
X214724Y358208D01*
X215099Y358125D01*
Y359875D01*
G01X214724Y361183D02*
X214932Y361433D01*
X215057Y361725D01*
X215099Y362100D01*
X215016Y362475D01*
X214849Y362767D01*
X214557Y362975D01*
X214224Y363017D01*
X213891Y362933D01*
X213682Y362725D01*
X213516Y362433D01*
X213474Y362142D01*
X213516Y361850D01*
X213682Y361475D01*
X212599Y361600D01*
Y362725D01*
G01X214807Y364492D02*
X215016Y364783D01*
X215099Y365117D01*
X215016Y365450D01*
X214766Y365742D01*
X214391Y365950D01*
X214016Y366033D01*
X213557D01*
X213182Y365950D01*
X212849Y365742D01*
X212682Y365492D01*
X212599Y365200D01*
X212682Y364867D01*
X212849Y364617D01*
X213099Y364450D01*
X213432Y364367D01*
X213724Y364450D01*
X214016Y364658D01*
X214182Y364908D01*
X214224Y365200D01*
X214141Y365533D01*
X213932Y365783D01*
X213557Y366033D01*
G01X228206Y359281D02*
X228081Y359031D01*
X227998Y358739D01*
Y358406D01*
X228123Y358031D01*
X228331Y357739D01*
X228581Y357531D01*
X228998Y357364D01*
X229373Y357322D01*
X229748Y357406D01*
X229998Y357531D01*
X230248Y357781D01*
X230415Y358072D01*
X230498Y358364D01*
Y358656D01*
X230415Y358947D01*
X230290Y359197D01*
X230123Y359406D01*
G01X228415Y360672D02*
X228165Y360922D01*
X228040Y361214D01*
X227998Y361547D01*
X228081Y361964D01*
X228290Y362256D01*
X228540Y362339D01*
X228790Y362297D01*
X228998Y362131D01*
X229415Y361297D01*
X229706Y360922D01*
X230123Y360672D01*
X230498Y360589D01*
Y362339D01*
G01X230123Y363647D02*
X230331Y363897D01*
X230456Y364189D01*
X230498Y364564D01*
X230415Y364939D01*
X230248Y365231D01*
X229956Y365439D01*
X229623Y365481D01*
X229290Y365397D01*
X229081Y365189D01*
X228915Y364897D01*
X228873Y364606D01*
X228915Y364314D01*
X229081Y363939D01*
X227998Y364064D01*
Y365189D01*
G01X230498Y367581D02*
X229956Y367664D01*
X229498Y367789D01*
X229081Y367956D01*
X228623Y368164D01*
X227998Y368497D01*
Y366831D01*
G01X224998Y354914D02*
X232998D01*
G01X224998Y349414D02*
Y354914D01*
G01X219506Y359281D02*
X219381Y359031D01*
X219298Y358739D01*
Y358406D01*
X219423Y358031D01*
X219631Y357739D01*
X219881Y357531D01*
X220298Y357364D01*
X220673Y357322D01*
X221048Y357406D01*
X221298Y357531D01*
X221548Y357781D01*
X221715Y358072D01*
X221798Y358364D01*
Y358656D01*
X221715Y358947D01*
X221590Y359197D01*
X221423Y359406D01*
G01X219715Y360672D02*
X219465Y360922D01*
X219340Y361214D01*
X219298Y361547D01*
X219381Y361964D01*
X219590Y362256D01*
X219840Y362339D01*
X220090Y362297D01*
X220298Y362131D01*
X220715Y361297D01*
X221006Y360922D01*
X221423Y360672D01*
X221798Y360589D01*
Y362339D01*
G01X221423Y363647D02*
X221631Y363897D01*
X221756Y364189D01*
X221798Y364564D01*
X221715Y364939D01*
X221548Y365231D01*
X221256Y365439D01*
X220923Y365481D01*
X220590Y365397D01*
X220381Y365189D01*
X220215Y364897D01*
X220173Y364606D01*
X220215Y364314D01*
X220381Y363939D01*
X219298Y364064D01*
Y365189D01*
G01X221798Y367664D02*
X221756Y367956D01*
X221631Y368289D01*
X221423Y368497D01*
X221131Y368581D01*
X220840Y368497D01*
X220590Y368247D01*
X220465Y367872D01*
Y367456D01*
X220381Y367206D01*
X220173Y366997D01*
X219881Y366914D01*
X219590Y367039D01*
X219381Y367331D01*
X219298Y367664D01*
X219381Y367997D01*
X219590Y368289D01*
X219881Y368414D01*
X220173Y368331D01*
X220381Y368122D01*
X220465Y367872D01*
Y367456D01*
X220590Y367081D01*
X220840Y366831D01*
X221131Y366747D01*
X221423Y366831D01*
X221631Y367039D01*
X221756Y367372D01*
X221798Y367664D01*
G01X224298Y354914D02*
Y349414D01*
G01X216298Y354914D02*
X224298D01*
G01X216298Y349414D02*
Y354914D01*
G01X230916Y382550D02*
Y387550D01*
X234082D01*
G01X232916Y385133D02*
X230916D01*
G01X236516Y386717D02*
X237016Y387217D01*
X237599Y387467D01*
X238266Y387550D01*
X239099Y387383D01*
X239682Y386967D01*
X239849Y386467D01*
X239766Y385967D01*
X239432Y385550D01*
X237766Y384717D01*
X237016Y384133D01*
X236516Y383300D01*
X236349Y382550D01*
X239849D01*
G01X243699Y387550D02*
X243032Y387383D01*
X242532Y386967D01*
X242199Y386467D01*
X241949Y385800D01*
X241866Y385050D01*
X241949Y384300D01*
X242199Y383633D01*
X242532Y383133D01*
X243032Y382717D01*
X243699Y382550D01*
X244366Y382717D01*
X244866Y383133D01*
X245199Y383633D01*
X245449Y384300D01*
X245532Y385050D01*
X245449Y385800D01*
X245199Y386467D01*
X244866Y386967D01*
X244366Y387383D01*
X243699Y387550D01*
G01X249299Y382383D02*
X249132Y382467D01*
Y382633D01*
X249299Y382717D01*
X249466Y382633D01*
Y382467D01*
X249299Y382383D01*
G01Y384633D02*
X249132Y384717D01*
Y384883D01*
X249299Y384967D01*
X249466Y384883D01*
Y384717D01*
X249299Y384633D01*
G01X253066Y383550D02*
X253566Y382967D01*
X254232Y382633D01*
X254982Y382550D01*
X255649Y382633D01*
X256316Y383050D01*
X256732Y383550D01*
X256816Y384050D01*
X256649Y384633D01*
X256066Y385050D01*
X255482Y385217D01*
X254732D01*
G01X255482D02*
X255982Y385467D01*
X256399Y385883D01*
X256566Y386383D01*
X256399Y386883D01*
X255982Y387300D01*
X255232Y387550D01*
X254482Y387467D01*
X253732Y387133D01*
G01X258416Y382550D02*
X260499Y387550D01*
X262582Y382550D01*
G01X261832Y384300D02*
X259166D01*
G01X264599Y382383D02*
X267599Y387550D01*
G01X271699Y382550D02*
Y387550D01*
X270699Y386550D01*
G01Y382550D02*
X272699D01*
G01X275466Y383300D02*
X275966Y382883D01*
X276549Y382633D01*
X277299Y382550D01*
X278049Y382717D01*
X278632Y383050D01*
X279049Y383633D01*
X279132Y384300D01*
X278966Y384967D01*
X278549Y385383D01*
X277966Y385717D01*
X277382Y385800D01*
X276799Y385717D01*
X276049Y385383D01*
X276299Y387550D01*
X278549D01*
G01X280816D02*
X282899Y382550D01*
X284982Y387550D01*
G01X211900Y472500D02*
Y449500D01*
G01X217000Y457045D02*
X214500D01*
Y458629D01*
G01X215708Y458045D02*
Y457045D01*
G01X214917Y460145D02*
X214667Y460395D01*
X214542Y460687D01*
X214500Y461020D01*
X214583Y461437D01*
X214792Y461729D01*
X215042Y461812D01*
X215292Y461770D01*
X215500Y461604D01*
X215917Y460770D01*
X216208Y460395D01*
X216625Y460145D01*
X217000Y460062D01*
Y461812D01*
G01Y464037D02*
X216958Y464329D01*
X216833Y464662D01*
X216625Y464870D01*
X216333Y464954D01*
X216042Y464870D01*
X215792Y464620D01*
X215667Y464245D01*
Y463829D01*
X215583Y463579D01*
X215375Y463370D01*
X215083Y463287D01*
X214792Y463412D01*
X214583Y463704D01*
X214500Y464037D01*
X214583Y464370D01*
X214792Y464662D01*
X215083Y464787D01*
X215375Y464704D01*
X215583Y464495D01*
X215667Y464245D01*
Y463829D01*
X215792Y463454D01*
X216042Y463204D01*
X216333Y463120D01*
X216625Y463204D01*
X216833Y463412D01*
X216958Y463745D01*
X217000Y464037D01*
G01X219916Y492050D02*
Y497050D01*
X223082D01*
G01X221916Y494633D02*
X219916D01*
G01X225516Y496217D02*
X226016Y496717D01*
X226599Y496967D01*
X227266Y497050D01*
X228099Y496883D01*
X228682Y496467D01*
X228849Y495967D01*
X228766Y495467D01*
X228432Y495050D01*
X226766Y494217D01*
X226016Y493633D01*
X225516Y492800D01*
X225349Y492050D01*
X228849D01*
G01X232532D02*
X232699Y493133D01*
X232949Y494050D01*
X233282Y494883D01*
X233699Y495800D01*
X234366Y497050D01*
X231032D01*
G01X238299Y491883D02*
X238132Y491967D01*
Y492133D01*
X238299Y492217D01*
X238466Y492133D01*
Y491967D01*
X238299Y491883D01*
G01Y494133D02*
X238132Y494217D01*
Y494383D01*
X238299Y494467D01*
X238466Y494383D01*
Y494217D01*
X238299Y494133D01*
G01X242316Y496217D02*
X242816Y496717D01*
X243399Y496967D01*
X244066Y497050D01*
X244899Y496883D01*
X245482Y496467D01*
X245649Y495967D01*
X245566Y495467D01*
X245232Y495050D01*
X243566Y494217D01*
X242816Y493633D01*
X242316Y492800D01*
X242149Y492050D01*
X245649D01*
G01X247416D02*
X249499Y497050D01*
X251582Y492050D01*
G01X250832Y493800D02*
X248166D01*
G01X253599Y491883D02*
X256599Y497050D01*
G01X259116Y494133D02*
X259699Y494717D01*
X260199Y495050D01*
X260866Y495217D01*
X261449Y495050D01*
X261866Y494717D01*
X262199Y494217D01*
X262282Y493633D01*
X262199Y493133D01*
X261866Y492633D01*
X261366Y492217D01*
X260782Y492050D01*
X260116Y492217D01*
X259532Y492717D01*
X259199Y493467D01*
X259116Y494300D01*
X259282Y495383D01*
X259532Y495967D01*
X259949Y496550D01*
X260532Y496967D01*
X261116Y497050D01*
X261699Y496883D01*
X262116Y496467D01*
G01X264216Y497050D02*
X266299Y492050D01*
X268382Y497050D01*
G01X219416Y482550D02*
Y487550D01*
X222582D01*
G01X221416Y485133D02*
X219416D01*
G01X225016Y486717D02*
X225516Y487217D01*
X226099Y487467D01*
X226766Y487550D01*
X227599Y487383D01*
X228182Y486967D01*
X228349Y486467D01*
X228266Y485967D01*
X227932Y485550D01*
X226266Y484717D01*
X225516Y484133D01*
X225016Y483300D01*
X224849Y482550D01*
X228349D01*
G01X232199D02*
X232782Y482633D01*
X233449Y482883D01*
X233866Y483300D01*
X234032Y483883D01*
X233866Y484467D01*
X233366Y484967D01*
X232616Y485217D01*
X231782D01*
X231282Y485383D01*
X230866Y485800D01*
X230699Y486383D01*
X230949Y486967D01*
X231532Y487383D01*
X232199Y487550D01*
X232866Y487383D01*
X233449Y486967D01*
X233699Y486383D01*
X233532Y485800D01*
X233116Y485383D01*
X232616Y485217D01*
X231782D01*
X231032Y484967D01*
X230532Y484467D01*
X230366Y483883D01*
X230532Y483300D01*
X230949Y482883D01*
X231616Y482633D01*
X232199Y482550D01*
G01X237799Y482383D02*
X237632Y482467D01*
Y482633D01*
X237799Y482717D01*
X237966Y482633D01*
Y482467D01*
X237799Y482383D01*
G01Y484633D02*
X237632Y484717D01*
Y484883D01*
X237799Y484967D01*
X237966Y484883D01*
Y484717D01*
X237799Y484633D01*
G01X241566Y483550D02*
X242066Y482967D01*
X242732Y482633D01*
X243482Y482550D01*
X244149Y482633D01*
X244816Y483050D01*
X245232Y483550D01*
X245316Y484050D01*
X245149Y484633D01*
X244566Y485050D01*
X243982Y485217D01*
X243232D01*
G01X243982D02*
X244482Y485467D01*
X244899Y485883D01*
X245066Y486383D01*
X244899Y486883D01*
X244482Y487300D01*
X243732Y487550D01*
X242982Y487467D01*
X242232Y487133D01*
G01X246916Y482550D02*
X248999Y487550D01*
X251082Y482550D01*
G01X250332Y484300D02*
X247666D01*
G01X253099Y482383D02*
X256099Y487550D01*
G01X260199Y482550D02*
Y487550D01*
X259199Y486550D01*
G01Y482550D02*
X261199D01*
G01X263966Y483300D02*
X264466Y482883D01*
X265049Y482633D01*
X265799Y482550D01*
X266549Y482717D01*
X267132Y483050D01*
X267549Y483633D01*
X267632Y484300D01*
X267466Y484967D01*
X267049Y485383D01*
X266466Y485717D01*
X265882Y485800D01*
X265299Y485717D01*
X264549Y485383D01*
X264799Y487550D01*
X267049D01*
G01X269316D02*
X271399Y482550D01*
X273482Y487550D01*
G01X222000Y509017D02*
X219500D01*
Y510058D01*
X219625Y510392D01*
X219792Y510600D01*
X220125Y510683D01*
X220458Y510600D01*
X220667Y510350D01*
X220792Y510058D01*
Y509017D01*
G01Y510058D02*
X222000Y510683D01*
G01X221500Y512033D02*
X221792Y512283D01*
X221958Y512617D01*
X222000Y512992D01*
X221958Y513325D01*
X221750Y513658D01*
X221500Y513867D01*
X221250Y513908D01*
X220958Y513825D01*
X220750Y513533D01*
X220667Y513242D01*
Y512867D01*
G01Y513242D02*
X220542Y513492D01*
X220333Y513700D01*
X220083Y513783D01*
X219833Y513700D01*
X219625Y513492D01*
X219500Y513117D01*
X219542Y512742D01*
X219708Y512367D01*
G01X222000Y516050D02*
X219500D01*
X220000Y515550D01*
G01X222000D02*
Y516550D01*
G01X221625Y518233D02*
X221833Y518483D01*
X221958Y518775D01*
X222000Y519150D01*
X221917Y519525D01*
X221750Y519817D01*
X221458Y520025D01*
X221125Y520067D01*
X220792Y519983D01*
X220583Y519775D01*
X220417Y519483D01*
X220375Y519192D01*
X220417Y518900D01*
X220583Y518525D01*
X219500Y518650D01*
Y519775D01*
G01X226000Y509017D02*
X223500D01*
Y510058D01*
X223625Y510392D01*
X223792Y510600D01*
X224125Y510683D01*
X224458Y510600D01*
X224667Y510350D01*
X224792Y510058D01*
Y509017D01*
G01Y510058D02*
X226000Y510683D01*
G01X225500Y512033D02*
X225792Y512283D01*
X225958Y512617D01*
X226000Y512992D01*
X225958Y513325D01*
X225750Y513658D01*
X225500Y513867D01*
X225250Y513908D01*
X224958Y513825D01*
X224750Y513533D01*
X224667Y513242D01*
Y512867D01*
G01Y513242D02*
X224542Y513492D01*
X224333Y513700D01*
X224083Y513783D01*
X223833Y513700D01*
X223625Y513492D01*
X223500Y513117D01*
X223542Y512742D01*
X223708Y512367D01*
G01X226000Y516050D02*
X223500D01*
X224000Y515550D01*
G01X226000D02*
Y516550D01*
G01X224958Y518358D02*
X224667Y518650D01*
X224500Y518900D01*
X224417Y519233D01*
X224500Y519525D01*
X224667Y519733D01*
X224917Y519900D01*
X225208Y519942D01*
X225458Y519900D01*
X225708Y519733D01*
X225917Y519483D01*
X226000Y519192D01*
X225917Y518858D01*
X225667Y518567D01*
X225292Y518400D01*
X224875Y518358D01*
X224333Y518442D01*
X224042Y518567D01*
X223750Y518775D01*
X223542Y519067D01*
X223500Y519358D01*
X223583Y519650D01*
X223792Y519858D01*
G01X230000Y509017D02*
X227500D01*
Y510058D01*
X227625Y510392D01*
X227792Y510600D01*
X228125Y510683D01*
X228458Y510600D01*
X228667Y510350D01*
X228792Y510058D01*
Y509017D01*
G01Y510058D02*
X230000Y510683D01*
G01X229500Y512033D02*
X229792Y512283D01*
X229958Y512617D01*
X230000Y512992D01*
X229958Y513325D01*
X229750Y513658D01*
X229500Y513867D01*
X229250Y513908D01*
X228958Y513825D01*
X228750Y513533D01*
X228667Y513242D01*
Y512867D01*
G01Y513242D02*
X228542Y513492D01*
X228333Y513700D01*
X228083Y513783D01*
X227833Y513700D01*
X227625Y513492D01*
X227500Y513117D01*
X227542Y512742D01*
X227708Y512367D01*
G01X230000Y516050D02*
X227500D01*
X228000Y515550D01*
G01X230000D02*
Y516550D01*
G01Y519067D02*
X229458Y519150D01*
X229000Y519275D01*
X228583Y519442D01*
X228125Y519650D01*
X227500Y519983D01*
Y518317D01*
G01X226208Y524767D02*
X226083Y524517D01*
X226000Y524225D01*
Y523892D01*
X226125Y523517D01*
X226333Y523225D01*
X226583Y523017D01*
X227000Y522850D01*
X227375Y522808D01*
X227750Y522892D01*
X228000Y523017D01*
X228250Y523267D01*
X228417Y523558D01*
X228500Y523850D01*
Y524142D01*
X228417Y524433D01*
X228292Y524683D01*
X228125Y524892D01*
G01X228000Y526033D02*
X228292Y526283D01*
X228458Y526617D01*
X228500Y526992D01*
X228458Y527325D01*
X228250Y527658D01*
X228000Y527867D01*
X227750Y527908D01*
X227458Y527825D01*
X227250Y527533D01*
X227167Y527242D01*
Y526867D01*
G01Y527242D02*
X227042Y527492D01*
X226833Y527700D01*
X226583Y527783D01*
X226333Y527700D01*
X226125Y527492D01*
X226000Y527117D01*
X226042Y526742D01*
X226208Y526367D01*
G01X228500Y530550D02*
X226000D01*
X227792Y529008D01*
Y531092D01*
G01X228500Y533150D02*
X226000D01*
X226500Y532650D01*
G01X228500D02*
Y533650D01*
G01X216500Y523017D02*
X214000D01*
Y524058D01*
X214125Y524392D01*
X214292Y524600D01*
X214625Y524683D01*
X214958Y524600D01*
X215167Y524350D01*
X215292Y524058D01*
Y523017D01*
G01Y524058D02*
X216500Y524683D01*
G01X216000Y526033D02*
X216292Y526283D01*
X216458Y526617D01*
X216500Y526992D01*
X216458Y527325D01*
X216250Y527658D01*
X216000Y527867D01*
X215750Y527908D01*
X215458Y527825D01*
X215250Y527533D01*
X215167Y527242D01*
Y526867D01*
G01Y527242D02*
X215042Y527492D01*
X214833Y527700D01*
X214583Y527783D01*
X214333Y527700D01*
X214125Y527492D01*
X214000Y527117D01*
X214042Y526742D01*
X214208Y526367D01*
G01X214417Y529258D02*
X214167Y529508D01*
X214042Y529800D01*
X214000Y530133D01*
X214083Y530550D01*
X214292Y530842D01*
X214542Y530925D01*
X214792Y530883D01*
X215000Y530717D01*
X215417Y529883D01*
X215708Y529508D01*
X216125Y529258D01*
X216500Y529175D01*
Y530925D01*
G01X216000Y532233D02*
X216292Y532483D01*
X216458Y532817D01*
X216500Y533192D01*
X216458Y533525D01*
X216250Y533858D01*
X216000Y534067D01*
X215750Y534108D01*
X215458Y534025D01*
X215250Y533733D01*
X215167Y533442D01*
Y533067D01*
G01Y533442D02*
X215042Y533692D01*
X214833Y533900D01*
X214583Y533983D01*
X214333Y533900D01*
X214125Y533692D01*
X214000Y533317D01*
X214042Y532942D01*
X214208Y532567D01*
G01X220500Y523017D02*
X218000D01*
Y524058D01*
X218125Y524392D01*
X218292Y524600D01*
X218625Y524683D01*
X218958Y524600D01*
X219167Y524350D01*
X219292Y524058D01*
Y523017D01*
G01Y524058D02*
X220500Y524683D01*
G01X220000Y526033D02*
X220292Y526283D01*
X220458Y526617D01*
X220500Y526992D01*
X220458Y527325D01*
X220250Y527658D01*
X220000Y527867D01*
X219750Y527908D01*
X219458Y527825D01*
X219250Y527533D01*
X219167Y527242D01*
Y526867D01*
G01Y527242D02*
X219042Y527492D01*
X218833Y527700D01*
X218583Y527783D01*
X218333Y527700D01*
X218125Y527492D01*
X218000Y527117D01*
X218042Y526742D01*
X218208Y526367D01*
G01X218417Y529258D02*
X218167Y529508D01*
X218042Y529800D01*
X218000Y530133D01*
X218083Y530550D01*
X218292Y530842D01*
X218542Y530925D01*
X218792Y530883D01*
X219000Y530717D01*
X219417Y529883D01*
X219708Y529508D01*
X220125Y529258D01*
X220500Y529175D01*
Y530925D01*
G01Y533650D02*
X218000D01*
X219792Y532108D01*
Y534192D01*
G01X224500Y523017D02*
X222000D01*
Y524058D01*
X222125Y524392D01*
X222292Y524600D01*
X222625Y524683D01*
X222958Y524600D01*
X223167Y524350D01*
X223292Y524058D01*
Y523017D01*
G01Y524058D02*
X224500Y524683D01*
G01X224000Y526033D02*
X224292Y526283D01*
X224458Y526617D01*
X224500Y526992D01*
X224458Y527325D01*
X224250Y527658D01*
X224000Y527867D01*
X223750Y527908D01*
X223458Y527825D01*
X223250Y527533D01*
X223167Y527242D01*
Y526867D01*
G01Y527242D02*
X223042Y527492D01*
X222833Y527700D01*
X222583Y527783D01*
X222333Y527700D01*
X222125Y527492D01*
X222000Y527117D01*
X222042Y526742D01*
X222208Y526367D01*
G01X222417Y529258D02*
X222167Y529508D01*
X222042Y529800D01*
X222000Y530133D01*
X222083Y530550D01*
X222292Y530842D01*
X222542Y530925D01*
X222792Y530883D01*
X223000Y530717D01*
X223417Y529883D01*
X223708Y529508D01*
X224125Y529258D01*
X224500Y529175D01*
Y530925D01*
G01X224125Y532233D02*
X224333Y532483D01*
X224458Y532775D01*
X224500Y533150D01*
X224417Y533525D01*
X224250Y533817D01*
X223958Y534025D01*
X223625Y534067D01*
X223292Y533983D01*
X223083Y533775D01*
X222917Y533483D01*
X222875Y533192D01*
X222917Y532900D01*
X223083Y532525D01*
X222000Y532650D01*
Y533775D01*
G01X217465Y641850D02*
X227465D01*
G01Y634850D02*
X217465D01*
G01X222465D02*
Y641850D01*
G01X217465Y631417D02*
X227465D01*
Y628083D01*
X226965Y626750D01*
X226298Y625750D01*
X225298Y624917D01*
X224131Y624250D01*
X222465Y624083D01*
X220798Y624250D01*
X219632Y624917D01*
X218631Y625750D01*
X217965Y626750D01*
X217465Y628083D01*
Y631417D01*
G01Y620817D02*
X227465D01*
Y617483D01*
X226965Y616150D01*
X226298Y615150D01*
X225298Y614317D01*
X224131Y613650D01*
X222465Y613483D01*
X220798Y613650D01*
X219632Y614317D01*
X218631Y615150D01*
X217965Y616150D01*
X217465Y617483D01*
Y620817D01*
G01Y606550D02*
X217632Y605383D01*
X218132Y604050D01*
X218965Y603217D01*
X220132Y602883D01*
X221298Y603217D01*
X222298Y604217D01*
X222798Y605717D01*
Y607383D01*
X223132Y608383D01*
X223965Y609217D01*
X225132Y609550D01*
X226298Y609050D01*
X227132Y607884D01*
X227465Y606550D01*
X227132Y605217D01*
X226298Y604050D01*
X225132Y603550D01*
X223965Y603883D01*
X223132Y604717D01*
X222798Y605717D01*
Y607383D01*
X222298Y608883D01*
X221298Y609883D01*
X220132Y610217D01*
X218965Y609883D01*
X218132Y609050D01*
X217632Y607717D01*
X217465Y606550D01*
G01X215707Y676317D02*
X215582Y676067D01*
X215499Y675775D01*
Y675442D01*
X215624Y675067D01*
X215832Y674775D01*
X216082Y674567D01*
X216499Y674400D01*
X216874Y674358D01*
X217249Y674442D01*
X217499Y674567D01*
X217749Y674817D01*
X217916Y675108D01*
X217999Y675400D01*
Y675692D01*
X217916Y675983D01*
X217791Y676233D01*
X217624Y676442D01*
G01X215916Y677708D02*
X215666Y677958D01*
X215541Y678250D01*
X215499Y678583D01*
X215582Y679000D01*
X215791Y679292D01*
X216041Y679375D01*
X216291Y679333D01*
X216499Y679167D01*
X216916Y678333D01*
X217207Y677958D01*
X217624Y677708D01*
X217999Y677625D01*
Y679375D01*
G01X217499Y680683D02*
X217791Y680933D01*
X217957Y681267D01*
X217999Y681642D01*
X217957Y681975D01*
X217749Y682308D01*
X217499Y682517D01*
X217249Y682558D01*
X216957Y682475D01*
X216749Y682183D01*
X216666Y681892D01*
Y681517D01*
G01Y681892D02*
X216541Y682142D01*
X216332Y682350D01*
X216082Y682433D01*
X215832Y682350D01*
X215624Y682142D01*
X215499Y681767D01*
X215541Y681392D01*
X215707Y681017D01*
G01X217999Y684700D02*
X217957Y684992D01*
X217832Y685325D01*
X217624Y685533D01*
X217332Y685617D01*
X217041Y685533D01*
X216791Y685283D01*
X216666Y684908D01*
Y684492D01*
X216582Y684242D01*
X216374Y684033D01*
X216082Y683950D01*
X215791Y684075D01*
X215582Y684367D01*
X215499Y684700D01*
X215582Y685033D01*
X215791Y685325D01*
X216082Y685450D01*
X216374Y685367D01*
X216582Y685158D01*
X216666Y684908D01*
Y684492D01*
X216791Y684117D01*
X217041Y683867D01*
X217332Y683783D01*
X217624Y683867D01*
X217832Y684075D01*
X217957Y684408D01*
X217999Y684700D01*
G01X222499Y673067D02*
X219999D01*
Y674108D01*
X220124Y674442D01*
X220291Y674650D01*
X220624Y674733D01*
X220957Y674650D01*
X221166Y674400D01*
X221291Y674108D01*
Y673067D01*
G01Y674108D02*
X222499Y674733D01*
G01X220416Y676208D02*
X220166Y676458D01*
X220041Y676750D01*
X219999Y677083D01*
X220082Y677500D01*
X220291Y677792D01*
X220541Y677875D01*
X220791Y677833D01*
X220999Y677667D01*
X221416Y676833D01*
X221707Y676458D01*
X222124Y676208D01*
X222499Y676125D01*
Y677875D01*
G01Y680100D02*
X219999D01*
X220499Y679600D01*
G01X222499D02*
Y680600D01*
G01X222207Y682492D02*
X222416Y682783D01*
X222499Y683117D01*
X222416Y683450D01*
X222166Y683742D01*
X221791Y683950D01*
X221416Y684033D01*
X220957D01*
X220582Y683950D01*
X220249Y683742D01*
X220082Y683492D01*
X219999Y683200D01*
X220082Y682867D01*
X220249Y682617D01*
X220499Y682450D01*
X220832Y682367D01*
X221124Y682450D01*
X221416Y682658D01*
X221582Y682908D01*
X221624Y683200D01*
X221541Y683533D01*
X221332Y683783D01*
X220957Y684033D01*
G01X227400Y668500D02*
X227067Y668542D01*
X226775Y668708D01*
X226525Y668958D01*
X226358Y669250D01*
X226275Y669583D01*
Y669917D01*
X226358Y670250D01*
X226525Y670542D01*
X226775Y670792D01*
X227067Y670958D01*
X227400Y671000D01*
X227733Y670958D01*
X228025Y670792D01*
X228275Y670542D01*
X228442Y670250D01*
X228525Y669917D01*
Y669583D01*
X228442Y669250D01*
X228275Y668958D01*
X228025Y668708D01*
X227733Y668542D01*
X227400Y668500D01*
G01X227733Y669167D02*
X228233Y668500D01*
G01X229708Y669542D02*
X230000Y669833D01*
X230250Y670000D01*
X230583Y670083D01*
X230875Y670000D01*
X231083Y669833D01*
X231250Y669583D01*
X231292Y669292D01*
X231250Y669042D01*
X231083Y668792D01*
X230833Y668583D01*
X230542Y668500D01*
X230208Y668583D01*
X229917Y668833D01*
X229750Y669208D01*
X229708Y669625D01*
X229792Y670167D01*
X229917Y670458D01*
X230125Y670750D01*
X230417Y670958D01*
X230708Y671000D01*
X231000Y670917D01*
X231208Y670708D01*
G01X232683Y669000D02*
X232933Y668708D01*
X233267Y668542D01*
X233642Y668500D01*
X233975Y668542D01*
X234308Y668750D01*
X234517Y669000D01*
X234558Y669250D01*
X234475Y669542D01*
X234183Y669750D01*
X233892Y669833D01*
X233517D01*
G01X233892D02*
X234142Y669958D01*
X234350Y670167D01*
X234433Y670417D01*
X234350Y670667D01*
X234142Y670875D01*
X233767Y671000D01*
X233392Y670958D01*
X233017Y670792D01*
G01X224400Y673000D02*
X237400D01*
G01X224400Y687000D02*
Y673000D01*
G01X215999Y696550D02*
X241999D01*
G01X215999Y709550D02*
Y696550D01*
G01X231699Y691550D02*
Y695550D01*
X224299D01*
G01X224300Y691500D02*
Y687500D01*
X231700D01*
G01X237400Y687000D02*
X224400D01*
G01X241999Y709550D02*
X215999D01*
G01X212708Y718767D02*
X212583Y718517D01*
X212500Y718225D01*
Y717892D01*
X212625Y717517D01*
X212833Y717225D01*
X213083Y717017D01*
X213500Y716850D01*
X213875Y716808D01*
X214250Y716892D01*
X214500Y717017D01*
X214750Y717267D01*
X214917Y717558D01*
X215000Y717850D01*
Y718142D01*
X214917Y718433D01*
X214792Y718683D01*
X214625Y718892D01*
G01X212917Y720158D02*
X212667Y720408D01*
X212542Y720700D01*
X212500Y721033D01*
X212583Y721450D01*
X212792Y721742D01*
X213042Y721825D01*
X213292Y721783D01*
X213500Y721617D01*
X213917Y720783D01*
X214208Y720408D01*
X214625Y720158D01*
X215000Y720075D01*
Y721825D01*
G01X214500Y723133D02*
X214792Y723383D01*
X214958Y723717D01*
X215000Y724092D01*
X214958Y724425D01*
X214750Y724758D01*
X214500Y724967D01*
X214250Y725008D01*
X213958Y724925D01*
X213750Y724633D01*
X213667Y724342D01*
Y723967D01*
G01Y724342D02*
X213542Y724592D01*
X213333Y724800D01*
X213083Y724883D01*
X212833Y724800D01*
X212625Y724592D01*
X212500Y724217D01*
X212542Y723842D01*
X212708Y723467D01*
G01X215000Y727067D02*
X214458Y727150D01*
X214000Y727275D01*
X213583Y727442D01*
X213125Y727650D01*
X212500Y727983D01*
Y726317D01*
G01X221499Y711750D02*
Y717250D01*
G01X229499Y711750D02*
X221499D01*
G01X229499Y717250D02*
Y711750D01*
G01Y729350D02*
Y723850D01*
G01X221499D02*
Y729350D01*
G01X215499Y730550D02*
X241499D01*
G01X215499Y743550D02*
Y730550D01*
G01X241499Y743550D02*
X215499D01*
G01X225999Y746250D02*
Y751750D01*
G01X233999Y746250D02*
X225999D01*
G01X217299D02*
Y751750D01*
G01X225299Y746250D02*
X217299D01*
G01X225299Y751750D02*
Y746250D01*
G01X221499Y729350D02*
X229499D01*
G01X213208Y763767D02*
X213083Y763517D01*
X213000Y763225D01*
Y762892D01*
X213125Y762517D01*
X213333Y762225D01*
X213583Y762017D01*
X214000Y761850D01*
X214375Y761808D01*
X214750Y761892D01*
X215000Y762017D01*
X215250Y762267D01*
X215417Y762558D01*
X215500Y762850D01*
Y763142D01*
X215417Y763433D01*
X215292Y763683D01*
X215125Y763892D01*
G01X213417Y765158D02*
X213167Y765408D01*
X213042Y765700D01*
X213000Y766033D01*
X213083Y766450D01*
X213292Y766742D01*
X213542Y766825D01*
X213792Y766783D01*
X214000Y766617D01*
X214417Y765783D01*
X214708Y765408D01*
X215125Y765158D01*
X215500Y765075D01*
Y766825D01*
G01Y769550D02*
X213000D01*
X214792Y768008D01*
Y770092D01*
G01X215000Y771233D02*
X215292Y771483D01*
X215458Y771817D01*
X215500Y772192D01*
X215458Y772525D01*
X215250Y772858D01*
X215000Y773067D01*
X214750Y773108D01*
X214458Y773025D01*
X214250Y772733D01*
X214167Y772442D01*
Y772067D01*
G01Y772442D02*
X214042Y772692D01*
X213833Y772900D01*
X213583Y772983D01*
X213333Y772900D01*
X213125Y772692D01*
X213000Y772317D01*
X213042Y771942D01*
X213208Y771567D01*
G01X228707Y768217D02*
X228582Y767967D01*
X228499Y767675D01*
Y767342D01*
X228624Y766967D01*
X228832Y766675D01*
X229082Y766467D01*
X229499Y766300D01*
X229874Y766258D01*
X230249Y766342D01*
X230499Y766467D01*
X230749Y766717D01*
X230916Y767008D01*
X230999Y767300D01*
Y767592D01*
X230916Y767883D01*
X230791Y768133D01*
X230624Y768342D01*
G01X228916Y769608D02*
X228666Y769858D01*
X228541Y770150D01*
X228499Y770483D01*
X228582Y770900D01*
X228791Y771192D01*
X229041Y771275D01*
X229291Y771233D01*
X229499Y771067D01*
X229916Y770233D01*
X230207Y769858D01*
X230624Y769608D01*
X230999Y769525D01*
Y771275D01*
G01Y774000D02*
X228499D01*
X230291Y772458D01*
Y774542D01*
G01X230999Y776600D02*
X228499D01*
X228999Y776100D01*
G01X230999D02*
Y777100D01*
G01X225999Y763850D02*
X233999D01*
G01X225999Y758350D02*
Y763850D01*
G01X220007Y768217D02*
X219882Y767967D01*
X219799Y767675D01*
Y767342D01*
X219924Y766967D01*
X220132Y766675D01*
X220382Y766467D01*
X220799Y766300D01*
X221174Y766258D01*
X221549Y766342D01*
X221799Y766467D01*
X222049Y766717D01*
X222216Y767008D01*
X222299Y767300D01*
Y767592D01*
X222216Y767883D01*
X222091Y768133D01*
X221924Y768342D01*
G01X220216Y769608D02*
X219966Y769858D01*
X219841Y770150D01*
X219799Y770483D01*
X219882Y770900D01*
X220091Y771192D01*
X220341Y771275D01*
X220591Y771233D01*
X220799Y771067D01*
X221216Y770233D01*
X221507Y769858D01*
X221924Y769608D01*
X222299Y769525D01*
Y771275D01*
G01Y774000D02*
X219799D01*
X221591Y772458D01*
Y774542D01*
G01X220216Y775808D02*
X219966Y776058D01*
X219841Y776350D01*
X219799Y776683D01*
X219882Y777100D01*
X220091Y777392D01*
X220341Y777475D01*
X220591Y777433D01*
X220799Y777267D01*
X221216Y776433D01*
X221507Y776058D01*
X221924Y775808D01*
X222299Y775725D01*
Y777475D01*
G01X225299Y763850D02*
Y758350D01*
G01X217299Y763850D02*
X225299D01*
G01X217299Y758350D02*
Y763850D01*
G01X211425Y822789D02*
Y820997D01*
X211592Y820622D01*
X211925Y820372D01*
X212342Y820289D01*
X212759Y820372D01*
X213092Y820622D01*
X213259Y820997D01*
Y822789D01*
G01X214525Y820789D02*
X214775Y820497D01*
X215109Y820331D01*
X215484Y820289D01*
X215817Y820331D01*
X216150Y820539D01*
X216359Y820789D01*
X216400Y821039D01*
X216317Y821331D01*
X216025Y821539D01*
X215734Y821622D01*
X215359D01*
G01X215734D02*
X215984Y821747D01*
X216192Y821956D01*
X216275Y822206D01*
X216192Y822456D01*
X215984Y822664D01*
X215609Y822789D01*
X215234Y822747D01*
X214859Y822581D01*
G01X218542Y820289D02*
X218834Y820331D01*
X219167Y820456D01*
X219375Y820664D01*
X219459Y820956D01*
X219375Y821247D01*
X219125Y821497D01*
X218750Y821622D01*
X218334D01*
X218084Y821706D01*
X217875Y821914D01*
X217792Y822206D01*
X217917Y822497D01*
X218209Y822706D01*
X218542Y822789D01*
X218875Y822706D01*
X219167Y822497D01*
X219292Y822206D01*
X219209Y821914D01*
X219000Y821706D01*
X218750Y821622D01*
X218334D01*
X217959Y821497D01*
X217709Y821247D01*
X217625Y820956D01*
X217709Y820664D01*
X217917Y820456D01*
X218250Y820331D01*
X218542Y820289D01*
G01X222517Y875000D02*
Y877500D01*
X223558D01*
X223892Y877375D01*
X224100Y877208D01*
X224183Y876875D01*
X224100Y876542D01*
X223850Y876333D01*
X223558Y876208D01*
X222517D01*
G01X223558D02*
X224183Y875000D01*
G01X225533Y875375D02*
X225783Y875167D01*
X226075Y875042D01*
X226450Y875000D01*
X226825Y875083D01*
X227117Y875250D01*
X227325Y875542D01*
X227367Y875875D01*
X227283Y876208D01*
X227075Y876417D01*
X226783Y876583D01*
X226492Y876625D01*
X226200Y876583D01*
X225825Y876417D01*
X225950Y877500D01*
X227075D01*
G01X228633Y875500D02*
X228883Y875208D01*
X229217Y875042D01*
X229592Y875000D01*
X229925Y875042D01*
X230258Y875250D01*
X230467Y875500D01*
X230508Y875750D01*
X230425Y876042D01*
X230133Y876250D01*
X229842Y876333D01*
X229467D01*
G01X229842D02*
X230092Y876458D01*
X230300Y876667D01*
X230383Y876917D01*
X230300Y877167D01*
X230092Y877375D01*
X229717Y877500D01*
X229342Y877458D01*
X228967Y877292D01*
G01X232567Y875000D02*
X232650Y875542D01*
X232775Y876000D01*
X232942Y876417D01*
X233150Y876875D01*
X233483Y877500D01*
X231817D01*
G01X220100Y872200D02*
Y880200D01*
G01X229000Y885017D02*
X226500D01*
Y886058D01*
X226625Y886392D01*
X226792Y886600D01*
X227125Y886683D01*
X227458Y886600D01*
X227667Y886350D01*
X227792Y886058D01*
Y885017D01*
G01Y886058D02*
X229000Y886683D01*
G01Y889450D02*
X226500D01*
X228292Y887908D01*
Y889992D01*
G01X227958Y891258D02*
X227667Y891550D01*
X227500Y891800D01*
X227417Y892133D01*
X227500Y892425D01*
X227667Y892633D01*
X227917Y892800D01*
X228208Y892842D01*
X228458Y892800D01*
X228708Y892633D01*
X228917Y892383D01*
X229000Y892092D01*
X228917Y891758D01*
X228667Y891467D01*
X228292Y891300D01*
X227875Y891258D01*
X227333Y891342D01*
X227042Y891467D01*
X226750Y891675D01*
X226542Y891967D01*
X226500Y892258D01*
X226583Y892550D01*
X226792Y892758D01*
G01X229000Y895150D02*
X228958Y895442D01*
X228833Y895775D01*
X228625Y895983D01*
X228333Y896067D01*
X228042Y895983D01*
X227792Y895733D01*
X227667Y895358D01*
Y894942D01*
X227583Y894692D01*
X227375Y894483D01*
X227083Y894400D01*
X226792Y894525D01*
X226583Y894817D01*
X226500Y895150D01*
X226583Y895483D01*
X226792Y895775D01*
X227083Y895900D01*
X227375Y895817D01*
X227583Y895608D01*
X227667Y895358D01*
Y894942D01*
X227792Y894567D01*
X228042Y894317D01*
X228333Y894233D01*
X228625Y894317D01*
X228833Y894525D01*
X228958Y894858D01*
X229000Y895150D01*
G01X213999Y881533D02*
X215791D01*
X216166Y881700D01*
X216416Y882033D01*
X216499Y882450D01*
X216416Y882867D01*
X216166Y883200D01*
X215791Y883367D01*
X213999D01*
G01X215999Y884633D02*
X216291Y884883D01*
X216457Y885217D01*
X216499Y885592D01*
X216457Y885925D01*
X216249Y886258D01*
X215999Y886467D01*
X215749Y886508D01*
X215457Y886425D01*
X215249Y886133D01*
X215166Y885842D01*
Y885467D01*
G01Y885842D02*
X215041Y886092D01*
X214832Y886300D01*
X214582Y886383D01*
X214332Y886300D01*
X214124Y886092D01*
X213999Y885717D01*
X214041Y885342D01*
X214207Y884967D01*
G01X216499Y888567D02*
X215957Y888650D01*
X215499Y888775D01*
X215082Y888942D01*
X214624Y889150D01*
X213999Y889483D01*
Y887817D01*
G01X210999Y895250D02*
Y881850D01*
G01X211699Y917013D02*
X230899D01*
Y928213D01*
X211699D01*
Y917013D01*
X212099D01*
G01X211799Y924613D02*
X213899Y922813D01*
X211799Y920613D01*
G01X219500Y1022000D02*
X229500D01*
G01Y1015000D02*
X219500D01*
G01X224500D02*
Y1022000D01*
G01X219500Y1011567D02*
X229500D01*
Y1008233D01*
X229000Y1006900D01*
X228333Y1005900D01*
X227333Y1005067D01*
X226166Y1004400D01*
X224500Y1004233D01*
X222833Y1004400D01*
X221667Y1005067D01*
X220666Y1005900D01*
X220000Y1006900D01*
X219500Y1008233D01*
Y1011567D01*
G01Y1000967D02*
X229500D01*
Y997633D01*
X229000Y996300D01*
X228333Y995300D01*
X227333Y994467D01*
X226166Y993800D01*
X224500Y993633D01*
X222833Y993800D01*
X221667Y994467D01*
X220666Y995300D01*
X220000Y996300D01*
X219500Y997633D01*
Y1000967D01*
G01Y987033D02*
X221667Y986700D01*
X223500Y986200D01*
X225167Y985533D01*
X227000Y984700D01*
X229500Y983367D01*
Y990033D01*
G01X219000Y1067517D02*
X216500D01*
Y1068558D01*
X216625Y1068892D01*
X216792Y1069100D01*
X217125Y1069183D01*
X217458Y1069100D01*
X217667Y1068850D01*
X217792Y1068558D01*
Y1067517D01*
G01Y1068558D02*
X219000Y1069183D01*
G01X216917Y1070658D02*
X216667Y1070908D01*
X216542Y1071200D01*
X216500Y1071533D01*
X216583Y1071950D01*
X216792Y1072242D01*
X217042Y1072325D01*
X217292Y1072283D01*
X217500Y1072117D01*
X217917Y1071283D01*
X218208Y1070908D01*
X218625Y1070658D01*
X219000Y1070575D01*
Y1072325D01*
G01X216500Y1074550D02*
X216583Y1074217D01*
X216792Y1073967D01*
X217042Y1073800D01*
X217375Y1073675D01*
X217750Y1073633D01*
X218125Y1073675D01*
X218458Y1073800D01*
X218708Y1073967D01*
X218917Y1074217D01*
X219000Y1074550D01*
X218917Y1074883D01*
X218708Y1075133D01*
X218458Y1075300D01*
X218125Y1075425D01*
X217750Y1075467D01*
X217375Y1075425D01*
X217042Y1075300D01*
X216792Y1075133D01*
X216583Y1074883D01*
X216500Y1074550D01*
G01X218500Y1076733D02*
X218792Y1076983D01*
X218958Y1077317D01*
X219000Y1077692D01*
X218958Y1078025D01*
X218750Y1078358D01*
X218500Y1078567D01*
X218250Y1078608D01*
X217958Y1078525D01*
X217750Y1078233D01*
X217667Y1077942D01*
Y1077567D01*
G01Y1077942D02*
X217542Y1078192D01*
X217333Y1078400D01*
X217083Y1078483D01*
X216833Y1078400D01*
X216625Y1078192D01*
X216500Y1077817D01*
X216542Y1077442D01*
X216708Y1077067D01*
G01X215000Y1067517D02*
X212500D01*
Y1068558D01*
X212625Y1068892D01*
X212792Y1069100D01*
X213125Y1069183D01*
X213458Y1069100D01*
X213667Y1068850D01*
X213792Y1068558D01*
Y1067517D01*
G01Y1068558D02*
X215000Y1069183D01*
G01X214500Y1070533D02*
X214792Y1070783D01*
X214958Y1071117D01*
X215000Y1071492D01*
X214958Y1071825D01*
X214750Y1072158D01*
X214500Y1072367D01*
X214250Y1072408D01*
X213958Y1072325D01*
X213750Y1072033D01*
X213667Y1071742D01*
Y1071367D01*
G01Y1071742D02*
X213542Y1071992D01*
X213333Y1072200D01*
X213083Y1072283D01*
X212833Y1072200D01*
X212625Y1071992D01*
X212500Y1071617D01*
X212542Y1071242D01*
X212708Y1070867D01*
G01X215000Y1074550D02*
X214958Y1074842D01*
X214833Y1075175D01*
X214625Y1075383D01*
X214333Y1075467D01*
X214042Y1075383D01*
X213792Y1075133D01*
X213667Y1074758D01*
Y1074342D01*
X213583Y1074092D01*
X213375Y1073883D01*
X213083Y1073800D01*
X212792Y1073925D01*
X212583Y1074217D01*
X212500Y1074550D01*
X212583Y1074883D01*
X212792Y1075175D01*
X213083Y1075300D01*
X213375Y1075217D01*
X213583Y1075008D01*
X213667Y1074758D01*
Y1074342D01*
X213792Y1073967D01*
X214042Y1073717D01*
X214333Y1073633D01*
X214625Y1073717D01*
X214833Y1073925D01*
X214958Y1074258D01*
X215000Y1074550D01*
G01Y1078150D02*
X212500D01*
X214292Y1076608D01*
Y1078692D01*
G01X228800Y1092000D02*
X224800D01*
Y1084600D01*
G01X222550Y1084500D02*
Y1080500D01*
X229950D01*
G01X215500Y1096600D02*
X241500D01*
G01X215500Y1109600D02*
Y1096600D01*
G01X241500Y1109600D02*
X215500D01*
G01X220300Y1115900D02*
Y1121400D01*
G01X228300Y1115900D02*
X220300D01*
G01X228300Y1121400D02*
Y1115900D01*
G01Y1133500D02*
Y1128000D01*
G01X220300D02*
Y1133500D01*
G01X229000Y1131900D02*
X236000D01*
Y1118500D01*
X229000D01*
Y1131900D01*
G01X229099Y1148650D02*
X231199Y1146850D01*
X229099Y1144650D01*
G01X228999Y1141050D02*
X248199D01*
Y1152250D01*
X228999D01*
Y1141050D01*
X229399D01*
G01X220300Y1133500D02*
X228300D01*
G01X227999Y1369050D02*
Y1379050D01*
G01X234999D02*
Y1369050D01*
G01Y1374050D02*
X227999D01*
G01X238432Y1369050D02*
Y1379050D01*
X241766D01*
X243099Y1378550D01*
X244099Y1377883D01*
X244932Y1376883D01*
X245599Y1375716D01*
X245766Y1374050D01*
X245599Y1372383D01*
X244932Y1371217D01*
X244099Y1370216D01*
X243099Y1369550D01*
X241766Y1369050D01*
X238432D01*
G01X249032D02*
Y1379050D01*
X252366D01*
X253699Y1378550D01*
X254699Y1377883D01*
X255532Y1376883D01*
X256199Y1375716D01*
X256366Y1374050D01*
X256199Y1372383D01*
X255532Y1371217D01*
X254699Y1370216D01*
X253699Y1369550D01*
X252366Y1369050D01*
X249032D01*
G01X260132Y1373216D02*
X261299Y1374383D01*
X262299Y1375050D01*
X263632Y1375383D01*
X264799Y1375050D01*
X265632Y1374383D01*
X266299Y1373383D01*
X266466Y1372217D01*
X266299Y1371217D01*
X265632Y1370216D01*
X264632Y1369383D01*
X263466Y1369050D01*
X262132Y1369383D01*
X260966Y1370383D01*
X260299Y1371883D01*
X260132Y1373550D01*
X260466Y1375716D01*
X260966Y1376883D01*
X261799Y1378050D01*
X262966Y1378883D01*
X264132Y1379050D01*
X265299Y1378717D01*
X266132Y1377883D01*
G01X268899Y1365717D02*
X278899D01*
G01X281166Y1379050D02*
Y1369050D01*
X287832D01*
G01X298432D02*
X291766D01*
Y1379050D01*
X298432D01*
G01X295766Y1374217D02*
X291766D01*
G01X302032Y1369050D02*
Y1379050D01*
X305366D01*
X306699Y1378550D01*
X307699Y1377883D01*
X308532Y1376883D01*
X309199Y1375716D01*
X309366Y1374050D01*
X309199Y1372383D01*
X308532Y1371217D01*
X307699Y1370216D01*
X306699Y1369550D01*
X305366Y1369050D01*
X302032D01*
G01X215696Y1368632D02*
X215363Y1368674D01*
X215071Y1368840D01*
X214821Y1369090D01*
X214654Y1369382D01*
X214571Y1369715D01*
Y1370049D01*
X214654Y1370382D01*
X214821Y1370674D01*
X215071Y1370924D01*
X215363Y1371090D01*
X215696Y1371132D01*
X216029Y1371090D01*
X216321Y1370924D01*
X216571Y1370674D01*
X216738Y1370382D01*
X216821Y1370049D01*
Y1369715D01*
X216738Y1369382D01*
X216571Y1369090D01*
X216321Y1368840D01*
X216029Y1368674D01*
X215696Y1368632D01*
G01X216029Y1369299D02*
X216529Y1368632D01*
G01X219296D02*
Y1371132D01*
X217754Y1369340D01*
X219838D01*
G01X221896Y1371132D02*
X221563Y1371049D01*
X221313Y1370840D01*
X221146Y1370590D01*
X221021Y1370257D01*
X220979Y1369882D01*
X221021Y1369507D01*
X221146Y1369174D01*
X221313Y1368924D01*
X221563Y1368715D01*
X221896Y1368632D01*
X222229Y1368715D01*
X222479Y1368924D01*
X222646Y1369174D01*
X222771Y1369507D01*
X222813Y1369882D01*
X222771Y1370257D01*
X222646Y1370590D01*
X222479Y1370840D01*
X222229Y1371049D01*
X221896Y1371132D01*
G01X211299Y1370300D02*
Y1383300D01*
G01X212707Y1486317D02*
X212582Y1486067D01*
X212499Y1485775D01*
Y1485442D01*
X212624Y1485067D01*
X212832Y1484775D01*
X213082Y1484567D01*
X213499Y1484400D01*
X213874Y1484358D01*
X214249Y1484442D01*
X214499Y1484567D01*
X214749Y1484817D01*
X214916Y1485108D01*
X214999Y1485400D01*
Y1485692D01*
X214916Y1485983D01*
X214791Y1486233D01*
X214624Y1486442D01*
G01X212916Y1487708D02*
X212666Y1487958D01*
X212541Y1488250D01*
X212499Y1488583D01*
X212582Y1489000D01*
X212791Y1489292D01*
X213041Y1489375D01*
X213291Y1489333D01*
X213499Y1489167D01*
X213916Y1488333D01*
X214207Y1487958D01*
X214624Y1487708D01*
X214999Y1487625D01*
Y1489375D01*
G01X212499Y1491600D02*
X212582Y1491267D01*
X212791Y1491017D01*
X213041Y1490850D01*
X213374Y1490725D01*
X213749Y1490683D01*
X214124Y1490725D01*
X214457Y1490850D01*
X214707Y1491017D01*
X214916Y1491267D01*
X214999Y1491600D01*
X214916Y1491933D01*
X214707Y1492183D01*
X214457Y1492350D01*
X214124Y1492475D01*
X213749Y1492517D01*
X213374Y1492475D01*
X213041Y1492350D01*
X212791Y1492183D01*
X212582Y1491933D01*
X212499Y1491600D01*
G01X214999Y1495200D02*
X212499D01*
X214291Y1493658D01*
Y1495742D01*
G01X215517Y1473500D02*
Y1476000D01*
X216558D01*
X216892Y1475875D01*
X217100Y1475708D01*
X217183Y1475375D01*
X217100Y1475042D01*
X216850Y1474833D01*
X216558Y1474708D01*
X215517D01*
G01X216558D02*
X217183Y1473500D01*
G01X218533Y1474000D02*
X218783Y1473708D01*
X219117Y1473542D01*
X219492Y1473500D01*
X219825Y1473542D01*
X220158Y1473750D01*
X220367Y1474000D01*
X220408Y1474250D01*
X220325Y1474542D01*
X220033Y1474750D01*
X219742Y1474833D01*
X219367D01*
G01X219742D02*
X219992Y1474958D01*
X220200Y1475167D01*
X220283Y1475417D01*
X220200Y1475667D01*
X219992Y1475875D01*
X219617Y1476000D01*
X219242Y1475958D01*
X218867Y1475792D01*
G01X222467Y1473500D02*
X222550Y1474042D01*
X222675Y1474500D01*
X222842Y1474917D01*
X223050Y1475375D01*
X223383Y1476000D01*
X221717D01*
G01X225567Y1473500D02*
X225650Y1474042D01*
X225775Y1474500D01*
X225942Y1474917D01*
X226150Y1475375D01*
X226483Y1476000D01*
X224817D01*
G01X222800Y1482100D02*
Y1478100D01*
X230200D01*
G01X218999Y1483067D02*
X216499D01*
Y1484108D01*
X216624Y1484442D01*
X216791Y1484650D01*
X217124Y1484733D01*
X217457Y1484650D01*
X217666Y1484400D01*
X217791Y1484108D01*
Y1483067D01*
G01Y1484108D02*
X218999Y1484733D01*
G01Y1487000D02*
X216499D01*
X216999Y1486500D01*
G01X218999D02*
Y1487500D01*
G01X218707Y1489392D02*
X218916Y1489683D01*
X218999Y1490017D01*
X218916Y1490350D01*
X218666Y1490642D01*
X218291Y1490850D01*
X217916Y1490933D01*
X217457D01*
X217082Y1490850D01*
X216749Y1490642D01*
X216582Y1490392D01*
X216499Y1490100D01*
X216582Y1489767D01*
X216749Y1489517D01*
X216999Y1489350D01*
X217332Y1489267D01*
X217624Y1489350D01*
X217916Y1489558D01*
X218082Y1489808D01*
X218124Y1490100D01*
X218041Y1490433D01*
X217832Y1490683D01*
X217457Y1490933D01*
G01X218999Y1493200D02*
X216499D01*
X216999Y1492700D01*
G01X218999D02*
Y1493700D01*
G01X226200Y1482700D02*
X239200D01*
G01X226200Y1496700D02*
Y1482700D01*
G01X214300Y1506900D02*
X240300D01*
G01X214300Y1519900D02*
Y1506900D01*
G01X228517Y1502500D02*
Y1505000D01*
X229558D01*
X229892Y1504875D01*
X230100Y1504708D01*
X230183Y1504375D01*
X230100Y1504042D01*
X229850Y1503833D01*
X229558Y1503708D01*
X228517D01*
G01X229558D02*
X230183Y1502500D01*
G01X232450D02*
Y1505000D01*
X231950Y1504500D01*
G01Y1502500D02*
X232950D01*
G01X235550D02*
X235842Y1502542D01*
X236175Y1502667D01*
X236383Y1502875D01*
X236467Y1503167D01*
X236383Y1503458D01*
X236133Y1503708D01*
X235758Y1503833D01*
X235342D01*
X235092Y1503917D01*
X234883Y1504125D01*
X234800Y1504417D01*
X234925Y1504708D01*
X235217Y1504917D01*
X235550Y1505000D01*
X235883Y1504917D01*
X236175Y1504708D01*
X236300Y1504417D01*
X236217Y1504125D01*
X236008Y1503917D01*
X235758Y1503833D01*
X235342D01*
X234967Y1503708D01*
X234717Y1503458D01*
X234633Y1503167D01*
X234717Y1502875D01*
X234925Y1502667D01*
X235258Y1502542D01*
X235550Y1502500D01*
G01X237942Y1502792D02*
X238233Y1502583D01*
X238567Y1502500D01*
X238900Y1502583D01*
X239192Y1502833D01*
X239400Y1503208D01*
X239483Y1503583D01*
Y1504042D01*
X239400Y1504417D01*
X239192Y1504750D01*
X238942Y1504917D01*
X238650Y1505000D01*
X238317Y1504917D01*
X238067Y1504750D01*
X237900Y1504500D01*
X237817Y1504167D01*
X237900Y1503875D01*
X238108Y1503583D01*
X238358Y1503417D01*
X238650Y1503375D01*
X238983Y1503458D01*
X239233Y1503667D01*
X239483Y1504042D01*
G01X227499Y1504750D02*
X223499D01*
Y1497350D01*
G01X227700Y1501300D02*
Y1497300D01*
X235100D01*
G01X239200Y1496700D02*
X226200D01*
G01X240300Y1519900D02*
X214300D01*
G01X210708Y1526767D02*
X210583Y1526517D01*
X210500Y1526225D01*
Y1525892D01*
X210625Y1525517D01*
X210833Y1525225D01*
X211083Y1525017D01*
X211500Y1524850D01*
X211875Y1524808D01*
X212250Y1524892D01*
X212500Y1525017D01*
X212750Y1525267D01*
X212917Y1525558D01*
X213000Y1525850D01*
Y1526142D01*
X212917Y1526433D01*
X212792Y1526683D01*
X212625Y1526892D01*
G01X210917Y1528158D02*
X210667Y1528408D01*
X210542Y1528700D01*
X210500Y1529033D01*
X210583Y1529450D01*
X210792Y1529742D01*
X211042Y1529825D01*
X211292Y1529783D01*
X211500Y1529617D01*
X211917Y1528783D01*
X212208Y1528408D01*
X212625Y1528158D01*
X213000Y1528075D01*
Y1529825D01*
G01X210500Y1532050D02*
X210583Y1531717D01*
X210792Y1531467D01*
X211042Y1531300D01*
X211375Y1531175D01*
X211750Y1531133D01*
X212125Y1531175D01*
X212458Y1531300D01*
X212708Y1531467D01*
X212917Y1531717D01*
X213000Y1532050D01*
X212917Y1532383D01*
X212708Y1532633D01*
X212458Y1532800D01*
X212125Y1532925D01*
X211750Y1532967D01*
X211375Y1532925D01*
X211042Y1532800D01*
X210792Y1532633D01*
X210583Y1532383D01*
X210500Y1532050D01*
G01X211958Y1534358D02*
X211667Y1534650D01*
X211500Y1534900D01*
X211417Y1535233D01*
X211500Y1535525D01*
X211667Y1535733D01*
X211917Y1535900D01*
X212208Y1535942D01*
X212458Y1535900D01*
X212708Y1535733D01*
X212917Y1535483D01*
X213000Y1535192D01*
X212917Y1534858D01*
X212667Y1534567D01*
X212292Y1534400D01*
X211875Y1534358D01*
X211333Y1534442D01*
X211042Y1534567D01*
X210750Y1534775D01*
X210542Y1535067D01*
X210500Y1535358D01*
X210583Y1535650D01*
X210792Y1535858D01*
G01X220999Y1521250D02*
Y1526750D01*
G01X228999Y1521250D02*
X220999D01*
G01X228999Y1526750D02*
Y1521250D01*
G01X215499Y1539550D02*
X241499D01*
G01X215499Y1552550D02*
Y1539550D01*
G01X241499Y1552550D02*
X215499D01*
G01X225000Y1553800D02*
Y1559300D01*
G01X233000Y1553800D02*
X225000D01*
G01X216300D02*
Y1559300D01*
G01X224300Y1553800D02*
X216300D01*
G01X224300Y1559300D02*
Y1553800D01*
G01X228999Y1538850D02*
Y1533350D01*
G01X220999Y1538850D02*
X228999D01*
G01X220999Y1533350D02*
Y1538850D01*
G01X227708Y1575267D02*
X227583Y1575017D01*
X227500Y1574725D01*
Y1574392D01*
X227625Y1574017D01*
X227833Y1573725D01*
X228083Y1573517D01*
X228500Y1573350D01*
X228875Y1573308D01*
X229250Y1573392D01*
X229500Y1573517D01*
X229750Y1573767D01*
X229917Y1574058D01*
X230000Y1574350D01*
Y1574642D01*
X229917Y1574933D01*
X229792Y1575183D01*
X229625Y1575392D01*
G01X227917Y1576658D02*
X227667Y1576908D01*
X227542Y1577200D01*
X227500Y1577533D01*
X227583Y1577950D01*
X227792Y1578242D01*
X228042Y1578325D01*
X228292Y1578283D01*
X228500Y1578117D01*
X228917Y1577283D01*
X229208Y1576908D01*
X229625Y1576658D01*
X230000Y1576575D01*
Y1578325D01*
G01X227500Y1580550D02*
X227583Y1580217D01*
X227792Y1579967D01*
X228042Y1579800D01*
X228375Y1579675D01*
X228750Y1579633D01*
X229125Y1579675D01*
X229458Y1579800D01*
X229708Y1579967D01*
X229917Y1580217D01*
X230000Y1580550D01*
X229917Y1580883D01*
X229708Y1581133D01*
X229458Y1581300D01*
X229125Y1581425D01*
X228750Y1581467D01*
X228375Y1581425D01*
X228042Y1581300D01*
X227792Y1581133D01*
X227583Y1580883D01*
X227500Y1580550D01*
G01X229708Y1582942D02*
X229917Y1583233D01*
X230000Y1583567D01*
X229917Y1583900D01*
X229667Y1584192D01*
X229292Y1584400D01*
X228917Y1584483D01*
X228458D01*
X228083Y1584400D01*
X227750Y1584192D01*
X227583Y1583942D01*
X227500Y1583650D01*
X227583Y1583317D01*
X227750Y1583067D01*
X228000Y1582900D01*
X228333Y1582817D01*
X228625Y1582900D01*
X228917Y1583108D01*
X229083Y1583358D01*
X229125Y1583650D01*
X229042Y1583983D01*
X228833Y1584233D01*
X228458Y1584483D01*
G01X225000Y1571400D02*
X233000D01*
G01X225000Y1565900D02*
Y1571400D01*
G01X219008Y1575267D02*
X218883Y1575017D01*
X218800Y1574725D01*
Y1574392D01*
X218925Y1574017D01*
X219133Y1573725D01*
X219383Y1573517D01*
X219800Y1573350D01*
X220175Y1573308D01*
X220550Y1573392D01*
X220800Y1573517D01*
X221050Y1573767D01*
X221217Y1574058D01*
X221300Y1574350D01*
Y1574642D01*
X221217Y1574933D01*
X221092Y1575183D01*
X220925Y1575392D01*
G01X219217Y1576658D02*
X218967Y1576908D01*
X218842Y1577200D01*
X218800Y1577533D01*
X218883Y1577950D01*
X219092Y1578242D01*
X219342Y1578325D01*
X219592Y1578283D01*
X219800Y1578117D01*
X220217Y1577283D01*
X220508Y1576908D01*
X220925Y1576658D01*
X221300Y1576575D01*
Y1578325D01*
G01Y1580550D02*
X218800D01*
X219300Y1580050D01*
G01X221300D02*
Y1581050D01*
G01X218800Y1583650D02*
X218883Y1583317D01*
X219092Y1583067D01*
X219342Y1582900D01*
X219675Y1582775D01*
X220050Y1582733D01*
X220425Y1582775D01*
X220758Y1582900D01*
X221008Y1583067D01*
X221217Y1583317D01*
X221300Y1583650D01*
X221217Y1583983D01*
X221008Y1584233D01*
X220758Y1584400D01*
X220425Y1584525D01*
X220050Y1584567D01*
X219675Y1584525D01*
X219342Y1584400D01*
X219092Y1584233D01*
X218883Y1583983D01*
X218800Y1583650D01*
G01X224300Y1571400D02*
Y1565900D01*
G01X216300Y1571400D02*
X224300D01*
G01X216300Y1565900D02*
Y1571400D01*
G01X226416Y1602050D02*
Y1607050D01*
X229582D01*
G01X228416Y1604633D02*
X226416D01*
G01X233599Y1602050D02*
Y1607050D01*
X232599Y1606050D01*
G01Y1602050D02*
X234599D01*
G01X240199D02*
Y1607050D01*
X237116Y1603467D01*
X241282D01*
G01X244799Y1601883D02*
X244632Y1601967D01*
Y1602133D01*
X244799Y1602217D01*
X244966Y1602133D01*
Y1601967D01*
X244799Y1601883D01*
G01Y1604133D02*
X244632Y1604217D01*
Y1604383D01*
X244799Y1604467D01*
X244966Y1604383D01*
Y1604217D01*
X244799Y1604133D01*
G01X248566Y1603050D02*
X249066Y1602467D01*
X249732Y1602133D01*
X250482Y1602050D01*
X251149Y1602133D01*
X251816Y1602550D01*
X252232Y1603050D01*
X252316Y1603550D01*
X252149Y1604133D01*
X251566Y1604550D01*
X250982Y1604717D01*
X250232D01*
G01X250982D02*
X251482Y1604967D01*
X251899Y1605383D01*
X252066Y1605883D01*
X251899Y1606383D01*
X251482Y1606800D01*
X250732Y1607050D01*
X249982Y1606967D01*
X249232Y1606633D01*
G01X253916Y1602050D02*
X255999Y1607050D01*
X258082Y1602050D01*
G01X257332Y1603800D02*
X254666D01*
G01X260099Y1601883D02*
X263099Y1607050D01*
G01X267199Y1602050D02*
Y1607050D01*
X266199Y1606050D01*
G01Y1602050D02*
X268199D01*
G01X270966Y1602800D02*
X271466Y1602383D01*
X272049Y1602133D01*
X272799Y1602050D01*
X273549Y1602217D01*
X274132Y1602550D01*
X274549Y1603133D01*
X274632Y1603800D01*
X274466Y1604467D01*
X274049Y1604883D01*
X273466Y1605217D01*
X272882Y1605300D01*
X272299Y1605217D01*
X271549Y1604883D01*
X271799Y1607050D01*
X274049D01*
G01X276316D02*
X278399Y1602050D01*
X280482Y1607050D01*
G01X211999Y1777550D02*
Y1787550D01*
G01X218999D02*
Y1777550D01*
G01Y1782550D02*
X211999D01*
G01X222432Y1777550D02*
Y1787550D01*
X225766D01*
X227099Y1787050D01*
X228099Y1786383D01*
X228932Y1785383D01*
X229599Y1784216D01*
X229766Y1782550D01*
X229599Y1780883D01*
X228932Y1779717D01*
X228099Y1778716D01*
X227099Y1778050D01*
X225766Y1777550D01*
X222432D01*
G01X233032D02*
Y1787550D01*
X236366D01*
X237699Y1787050D01*
X238699Y1786383D01*
X239532Y1785383D01*
X240199Y1784216D01*
X240366Y1782550D01*
X240199Y1780883D01*
X239532Y1779717D01*
X238699Y1778716D01*
X237699Y1778050D01*
X236366Y1777550D01*
X233032D01*
G01X243632Y1779050D02*
X244632Y1778217D01*
X245799Y1777717D01*
X247299Y1777550D01*
X248799Y1777883D01*
X249966Y1778550D01*
X250799Y1779717D01*
X250966Y1781050D01*
X250632Y1782383D01*
X249799Y1783217D01*
X248632Y1783883D01*
X247466Y1784050D01*
X246299Y1783883D01*
X244799Y1783217D01*
X245299Y1787550D01*
X249799D01*
G01X252899Y1774217D02*
X262899D01*
G01X265166Y1787550D02*
Y1777550D01*
X271832D01*
G01X282432D02*
X275766D01*
Y1787550D01*
X282432D01*
G01X279766Y1782717D02*
X275766D01*
G01X286032Y1777550D02*
Y1787550D01*
X289366D01*
X290699Y1787050D01*
X291699Y1786383D01*
X292532Y1785383D01*
X293199Y1784216D01*
X293366Y1782550D01*
X293199Y1780883D01*
X292532Y1779717D01*
X291699Y1778716D01*
X290699Y1778050D01*
X289366Y1777550D01*
X286032D01*
G01X230000Y1864900D02*
X229958Y1864567D01*
X229792Y1864275D01*
X229542Y1864025D01*
X229250Y1863858D01*
X228917Y1863775D01*
X228583D01*
X228250Y1863858D01*
X227958Y1864025D01*
X227708Y1864275D01*
X227542Y1864567D01*
X227500Y1864900D01*
X227542Y1865233D01*
X227708Y1865525D01*
X227958Y1865775D01*
X228250Y1865942D01*
X228583Y1866025D01*
X228917D01*
X229250Y1865942D01*
X229542Y1865775D01*
X229792Y1865525D01*
X229958Y1865233D01*
X230000Y1864900D01*
G01X229333Y1865233D02*
X230000Y1865733D01*
G01X229625Y1867083D02*
X229833Y1867333D01*
X229958Y1867625D01*
X230000Y1868000D01*
X229917Y1868375D01*
X229750Y1868667D01*
X229458Y1868875D01*
X229125Y1868917D01*
X228792Y1868833D01*
X228583Y1868625D01*
X228417Y1868333D01*
X228375Y1868042D01*
X228417Y1867750D01*
X228583Y1867375D01*
X227500Y1867500D01*
Y1868625D01*
G01X228958Y1870308D02*
X228667Y1870600D01*
X228500Y1870850D01*
X228417Y1871183D01*
X228500Y1871475D01*
X228667Y1871683D01*
X228917Y1871850D01*
X229208Y1871892D01*
X229458Y1871850D01*
X229708Y1871683D01*
X229917Y1871433D01*
X230000Y1871142D01*
X229917Y1870808D01*
X229667Y1870517D01*
X229292Y1870350D01*
X228875Y1870308D01*
X228333Y1870392D01*
X228042Y1870517D01*
X227750Y1870725D01*
X227542Y1871017D01*
X227500Y1871308D01*
X227583Y1871600D01*
X227792Y1871808D01*
G01X215100Y1886100D02*
Y1874700D01*
G01X228500Y1886100D02*
X215100D01*
G01X228500Y1874700D02*
Y1886100D01*
G01X215100Y1874700D02*
X228500D01*
G01X221436Y1891665D02*
X225436D01*
Y1899065D01*
G01X233000Y1885900D02*
X229000D01*
Y1878500D01*
G01X215500Y1888017D02*
X213000D01*
Y1889058D01*
X213125Y1889392D01*
X213292Y1889600D01*
X213625Y1889683D01*
X213958Y1889600D01*
X214167Y1889350D01*
X214292Y1889058D01*
Y1888017D01*
G01Y1889058D02*
X215500Y1889683D01*
G01X215000Y1891033D02*
X215292Y1891283D01*
X215458Y1891617D01*
X215500Y1891992D01*
X215458Y1892325D01*
X215250Y1892658D01*
X215000Y1892867D01*
X214750Y1892908D01*
X214458Y1892825D01*
X214250Y1892533D01*
X214167Y1892242D01*
Y1891867D01*
G01Y1892242D02*
X214042Y1892492D01*
X213833Y1892700D01*
X213583Y1892783D01*
X213333Y1892700D01*
X213125Y1892492D01*
X213000Y1892117D01*
X213042Y1891742D01*
X213208Y1891367D01*
G01X215500Y1894967D02*
X214958Y1895050D01*
X214500Y1895175D01*
X214083Y1895342D01*
X213625Y1895550D01*
X213000Y1895883D01*
Y1894217D01*
G01X214458Y1897358D02*
X214167Y1897650D01*
X214000Y1897900D01*
X213917Y1898233D01*
X214000Y1898525D01*
X214167Y1898733D01*
X214417Y1898900D01*
X214708Y1898942D01*
X214958Y1898900D01*
X215208Y1898733D01*
X215417Y1898483D01*
X215500Y1898192D01*
X215417Y1897858D01*
X215167Y1897567D01*
X214792Y1897400D01*
X214375Y1897358D01*
X213833Y1897442D01*
X213542Y1897567D01*
X213250Y1897775D01*
X213042Y1898067D01*
X213000Y1898358D01*
X213083Y1898650D01*
X213292Y1898858D01*
G01X212999Y1901567D02*
X210499D01*
Y1902608D01*
X210624Y1902942D01*
X210791Y1903150D01*
X211124Y1903233D01*
X211457Y1903150D01*
X211666Y1902900D01*
X211791Y1902608D01*
Y1901567D01*
G01Y1902608D02*
X212999Y1903233D01*
G01Y1905500D02*
X210499D01*
X210999Y1905000D01*
G01X212999D02*
Y1906000D01*
G01Y1908517D02*
X212457Y1908600D01*
X211999Y1908725D01*
X211582Y1908892D01*
X211124Y1909100D01*
X210499Y1909433D01*
Y1907767D01*
G01X212624Y1910783D02*
X212832Y1911033D01*
X212957Y1911325D01*
X212999Y1911700D01*
X212916Y1912075D01*
X212749Y1912367D01*
X212457Y1912575D01*
X212124Y1912617D01*
X211791Y1912533D01*
X211582Y1912325D01*
X211416Y1912033D01*
X211374Y1911742D01*
X211416Y1911450D01*
X211582Y1911075D01*
X210499Y1911200D01*
Y1912325D01*
G01X215934Y1900187D02*
X241934D01*
G01X215934Y1913187D02*
Y1900187D01*
G01X241934Y1913187D02*
X215934D01*
G01X211500Y1920350D02*
X214000D01*
G01X211500Y1919392D02*
Y1921308D01*
G01X214000Y1922617D02*
X211500D01*
Y1923617D01*
X211625Y1923950D01*
X211917Y1924200D01*
X212250Y1924283D01*
X212583Y1924200D01*
X212833Y1923992D01*
X212958Y1923617D01*
Y1922617D01*
G01X213500Y1925633D02*
X213792Y1925883D01*
X213958Y1926217D01*
X214000Y1926592D01*
X213958Y1926925D01*
X213750Y1927258D01*
X213500Y1927467D01*
X213250Y1927508D01*
X212958Y1927425D01*
X212750Y1927133D01*
X212667Y1926842D01*
Y1926467D01*
G01Y1926842D02*
X212542Y1927092D01*
X212333Y1927300D01*
X212083Y1927383D01*
X211833Y1927300D01*
X211625Y1927092D01*
X211500Y1926717D01*
X211542Y1926342D01*
X211708Y1925967D01*
G01X211500Y1929650D02*
X211583Y1929317D01*
X211792Y1929067D01*
X212042Y1928900D01*
X212375Y1928775D01*
X212750Y1928733D01*
X213125Y1928775D01*
X213458Y1928900D01*
X213708Y1929067D01*
X213917Y1929317D01*
X214000Y1929650D01*
X213917Y1929983D01*
X213708Y1930233D01*
X213458Y1930400D01*
X213125Y1930525D01*
X212750Y1930567D01*
X212375Y1930525D01*
X212042Y1930400D01*
X211792Y1930233D01*
X211583Y1929983D01*
X211500Y1929650D01*
G01X221814Y1916813D02*
Y1922313D01*
G01X229814Y1916813D02*
X221814D01*
G01X229814Y1922313D02*
Y1916813D01*
G01Y1934413D02*
Y1928913D01*
G01X221814Y1934413D02*
X229814D01*
G01X221814Y1928913D02*
Y1934413D01*
G01X214434Y1936487D02*
X240434D01*
G01X214434Y1949487D02*
Y1936487D01*
G01X240434Y1949487D02*
X214434D01*
G01X210708Y1939767D02*
X210583Y1939517D01*
X210500Y1939225D01*
Y1938892D01*
X210625Y1938517D01*
X210833Y1938225D01*
X211083Y1938017D01*
X211500Y1937850D01*
X211875Y1937808D01*
X212250Y1937892D01*
X212500Y1938017D01*
X212750Y1938267D01*
X212917Y1938558D01*
X213000Y1938850D01*
Y1939142D01*
X212917Y1939433D01*
X212792Y1939683D01*
X212625Y1939892D01*
G01X213000Y1941950D02*
X210500D01*
X211000Y1941450D01*
G01X213000D02*
Y1942450D01*
G01X212708Y1944342D02*
X212917Y1944633D01*
X213000Y1944967D01*
X212917Y1945300D01*
X212667Y1945592D01*
X212292Y1945800D01*
X211917Y1945883D01*
X211458D01*
X211083Y1945800D01*
X210750Y1945592D01*
X210583Y1945342D01*
X210500Y1945050D01*
X210583Y1944717D01*
X210750Y1944467D01*
X211000Y1944300D01*
X211333Y1944217D01*
X211625Y1944300D01*
X211917Y1944508D01*
X212083Y1944758D01*
X212125Y1945050D01*
X212042Y1945383D01*
X211833Y1945633D01*
X211458Y1945883D01*
G01X213000Y1948150D02*
X210500D01*
X211000Y1947650D01*
G01X213000D02*
Y1948650D01*
G01X216300Y1950300D02*
Y1955800D01*
G01X224300Y1950300D02*
X216300D01*
G01X224300Y1955800D02*
Y1950300D01*
G01X225000D02*
Y1955800D01*
G01X233000Y1950300D02*
X225000D01*
G01X212493Y1968304D02*
X212368Y1968054D01*
X212285Y1967762D01*
Y1967429D01*
X212410Y1967054D01*
X212618Y1966762D01*
X212868Y1966554D01*
X213285Y1966387D01*
X213660Y1966345D01*
X214035Y1966429D01*
X214285Y1966554D01*
X214535Y1966804D01*
X214702Y1967095D01*
X214785Y1967387D01*
Y1967679D01*
X214702Y1967970D01*
X214577Y1968220D01*
X214410Y1968429D01*
G01X214785Y1970487D02*
X212285D01*
X212785Y1969987D01*
G01X214785D02*
Y1970987D01*
G01X214493Y1972879D02*
X214702Y1973170D01*
X214785Y1973504D01*
X214702Y1973837D01*
X214452Y1974129D01*
X214077Y1974337D01*
X213702Y1974420D01*
X213243D01*
X212868Y1974337D01*
X212535Y1974129D01*
X212368Y1973879D01*
X212285Y1973587D01*
X212368Y1973254D01*
X212535Y1973004D01*
X212785Y1972837D01*
X213118Y1972754D01*
X213410Y1972837D01*
X213702Y1973045D01*
X213868Y1973295D01*
X213910Y1973587D01*
X213827Y1973920D01*
X213618Y1974170D01*
X213243Y1974420D01*
G01X214410Y1975770D02*
X214618Y1976020D01*
X214743Y1976312D01*
X214785Y1976687D01*
X214702Y1977062D01*
X214535Y1977354D01*
X214243Y1977562D01*
X213910Y1977604D01*
X213577Y1977520D01*
X213368Y1977312D01*
X213202Y1977020D01*
X213160Y1976729D01*
X213202Y1976437D01*
X213368Y1976062D01*
X212285Y1976187D01*
Y1977312D01*
G01X219508Y1971767D02*
X219383Y1971517D01*
X219300Y1971225D01*
Y1970892D01*
X219425Y1970517D01*
X219633Y1970225D01*
X219883Y1970017D01*
X220300Y1969850D01*
X220675Y1969808D01*
X221050Y1969892D01*
X221300Y1970017D01*
X221550Y1970267D01*
X221717Y1970558D01*
X221800Y1970850D01*
Y1971142D01*
X221717Y1971433D01*
X221592Y1971683D01*
X221425Y1971892D01*
G01X221800Y1973950D02*
X219300D01*
X219800Y1973450D01*
G01X221800D02*
Y1974450D01*
G01X221508Y1976342D02*
X221717Y1976633D01*
X221800Y1976967D01*
X221717Y1977300D01*
X221467Y1977592D01*
X221092Y1977800D01*
X220717Y1977883D01*
X220258D01*
X219883Y1977800D01*
X219550Y1977592D01*
X219383Y1977342D01*
X219300Y1977050D01*
X219383Y1976717D01*
X219550Y1976467D01*
X219800Y1976300D01*
X220133Y1976217D01*
X220425Y1976300D01*
X220717Y1976508D01*
X220883Y1976758D01*
X220925Y1977050D01*
X220842Y1977383D01*
X220633Y1977633D01*
X220258Y1977883D01*
G01X219717Y1979358D02*
X219467Y1979608D01*
X219342Y1979900D01*
X219300Y1980233D01*
X219383Y1980650D01*
X219592Y1980942D01*
X219842Y1981025D01*
X220092Y1980983D01*
X220300Y1980817D01*
X220717Y1979983D01*
X221008Y1979608D01*
X221425Y1979358D01*
X221800Y1979275D01*
Y1981025D01*
G01X224300Y1967900D02*
Y1962400D01*
G01X216300Y1967900D02*
X224300D01*
G01X216300Y1962400D02*
Y1967900D01*
G01X228208Y1971767D02*
X228083Y1971517D01*
X228000Y1971225D01*
Y1970892D01*
X228125Y1970517D01*
X228333Y1970225D01*
X228583Y1970017D01*
X229000Y1969850D01*
X229375Y1969808D01*
X229750Y1969892D01*
X230000Y1970017D01*
X230250Y1970267D01*
X230417Y1970558D01*
X230500Y1970850D01*
Y1971142D01*
X230417Y1971433D01*
X230292Y1971683D01*
X230125Y1971892D01*
G01X230500Y1973950D02*
X228000D01*
X228500Y1973450D01*
G01X230500D02*
Y1974450D01*
G01X230208Y1976342D02*
X230417Y1976633D01*
X230500Y1976967D01*
X230417Y1977300D01*
X230167Y1977592D01*
X229792Y1977800D01*
X229417Y1977883D01*
X228958D01*
X228583Y1977800D01*
X228250Y1977592D01*
X228083Y1977342D01*
X228000Y1977050D01*
X228083Y1976717D01*
X228250Y1976467D01*
X228500Y1976300D01*
X228833Y1976217D01*
X229125Y1976300D01*
X229417Y1976508D01*
X229583Y1976758D01*
X229625Y1977050D01*
X229542Y1977383D01*
X229333Y1977633D01*
X228958Y1977883D01*
G01X230000Y1979233D02*
X230292Y1979483D01*
X230458Y1979817D01*
X230500Y1980192D01*
X230458Y1980525D01*
X230250Y1980858D01*
X230000Y1981067D01*
X229750Y1981108D01*
X229458Y1981025D01*
X229250Y1980733D01*
X229167Y1980442D01*
Y1980067D01*
G01Y1980442D02*
X229042Y1980692D01*
X228833Y1980900D01*
X228583Y1980983D01*
X228333Y1980900D01*
X228125Y1980692D01*
X228000Y1980317D01*
X228042Y1979942D01*
X228208Y1979567D01*
G01X225000Y1967900D02*
X233000D01*
G01X225000Y1962400D02*
Y1967900D01*
G01X246517Y52500D02*
Y55000D01*
X247517D01*
X247850Y54875D01*
X248100Y54583D01*
X248183Y54250D01*
X248100Y53917D01*
X247892Y53667D01*
X247517Y53542D01*
X246517D01*
G01X251367Y54792D02*
X251117Y54917D01*
X250825Y55000D01*
X250492D01*
X250117Y54875D01*
X249825Y54667D01*
X249617Y54417D01*
X249450Y54000D01*
X249408Y53625D01*
X249492Y53250D01*
X249617Y53000D01*
X249867Y52750D01*
X250158Y52583D01*
X250450Y52500D01*
X250742D01*
X251033Y52583D01*
X251283Y52708D01*
X251492Y52875D01*
G01X253550Y52500D02*
Y55000D01*
X253050Y54500D01*
G01Y52500D02*
X254050D01*
G01X255858Y53542D02*
X256150Y53833D01*
X256400Y54000D01*
X256733Y54083D01*
X257025Y54000D01*
X257233Y53833D01*
X257400Y53583D01*
X257442Y53292D01*
X257400Y53042D01*
X257233Y52792D01*
X256983Y52583D01*
X256692Y52500D01*
X256358Y52583D01*
X256067Y52833D01*
X255900Y53208D01*
X255858Y53625D01*
X255942Y54167D01*
X256067Y54458D01*
X256275Y54750D01*
X256567Y54958D01*
X256858Y55000D01*
X257150Y54917D01*
X257358Y54708D01*
G01X246517Y40500D02*
Y43000D01*
X247517D01*
X247850Y42875D01*
X248100Y42583D01*
X248183Y42250D01*
X248100Y41917D01*
X247892Y41667D01*
X247517Y41542D01*
X246517D01*
G01X251367Y42792D02*
X251117Y42917D01*
X250825Y43000D01*
X250492D01*
X250117Y42875D01*
X249825Y42667D01*
X249617Y42417D01*
X249450Y42000D01*
X249408Y41625D01*
X249492Y41250D01*
X249617Y41000D01*
X249867Y40750D01*
X250158Y40583D01*
X250450Y40500D01*
X250742D01*
X251033Y40583D01*
X251283Y40708D01*
X251492Y40875D01*
G01X253550Y40500D02*
Y43000D01*
X253050Y42500D01*
G01Y40500D02*
X254050D01*
G01X256650D02*
X256942Y40542D01*
X257275Y40667D01*
X257483Y40875D01*
X257567Y41167D01*
X257483Y41458D01*
X257233Y41708D01*
X256858Y41833D01*
X256442D01*
X256192Y41917D01*
X255983Y42125D01*
X255900Y42417D01*
X256025Y42708D01*
X256317Y42917D01*
X256650Y43000D01*
X256983Y42917D01*
X257275Y42708D01*
X257400Y42417D01*
X257317Y42125D01*
X257108Y41917D01*
X256858Y41833D01*
X256442D01*
X256067Y41708D01*
X255817Y41458D01*
X255733Y41167D01*
X255817Y40875D01*
X256025Y40667D01*
X256358Y40542D01*
X256650Y40500D01*
G01X246517Y44500D02*
Y47000D01*
X247517D01*
X247850Y46875D01*
X248100Y46583D01*
X248183Y46250D01*
X248100Y45917D01*
X247892Y45667D01*
X247517Y45542D01*
X246517D01*
G01X251367Y46792D02*
X251117Y46917D01*
X250825Y47000D01*
X250492D01*
X250117Y46875D01*
X249825Y46667D01*
X249617Y46417D01*
X249450Y46000D01*
X249408Y45625D01*
X249492Y45250D01*
X249617Y45000D01*
X249867Y44750D01*
X250158Y44583D01*
X250450Y44500D01*
X250742D01*
X251033Y44583D01*
X251283Y44708D01*
X251492Y44875D01*
G01X252758Y46583D02*
X253008Y46833D01*
X253300Y46958D01*
X253633Y47000D01*
X254050Y46917D01*
X254342Y46708D01*
X254425Y46458D01*
X254383Y46208D01*
X254217Y46000D01*
X253383Y45583D01*
X253008Y45292D01*
X252758Y44875D01*
X252675Y44500D01*
X254425D01*
G01X255858Y46583D02*
X256108Y46833D01*
X256400Y46958D01*
X256733Y47000D01*
X257150Y46917D01*
X257442Y46708D01*
X257525Y46458D01*
X257483Y46208D01*
X257317Y46000D01*
X256483Y45583D01*
X256108Y45292D01*
X255858Y44875D01*
X255775Y44500D01*
X257525D01*
G01X246517Y48500D02*
Y51000D01*
X247517D01*
X247850Y50875D01*
X248100Y50583D01*
X248183Y50250D01*
X248100Y49917D01*
X247892Y49667D01*
X247517Y49542D01*
X246517D01*
G01X251367Y50792D02*
X251117Y50917D01*
X250825Y51000D01*
X250492D01*
X250117Y50875D01*
X249825Y50667D01*
X249617Y50417D01*
X249450Y50000D01*
X249408Y49625D01*
X249492Y49250D01*
X249617Y49000D01*
X249867Y48750D01*
X250158Y48583D01*
X250450Y48500D01*
X250742D01*
X251033Y48583D01*
X251283Y48708D01*
X251492Y48875D01*
G01X252758Y50583D02*
X253008Y50833D01*
X253300Y50958D01*
X253633Y51000D01*
X254050Y50917D01*
X254342Y50708D01*
X254425Y50458D01*
X254383Y50208D01*
X254217Y50000D01*
X253383Y49583D01*
X253008Y49292D01*
X252758Y48875D01*
X252675Y48500D01*
X254425D01*
G01X257150D02*
Y51000D01*
X255608Y49208D01*
X257692D01*
G01X246517Y56500D02*
Y59000D01*
X247517D01*
X247850Y58875D01*
X248100Y58583D01*
X248183Y58250D01*
X248100Y57917D01*
X247892Y57667D01*
X247517Y57542D01*
X246517D01*
G01X251367Y58792D02*
X251117Y58917D01*
X250825Y59000D01*
X250492D01*
X250117Y58875D01*
X249825Y58667D01*
X249617Y58417D01*
X249450Y58000D01*
X249408Y57625D01*
X249492Y57250D01*
X249617Y57000D01*
X249867Y56750D01*
X250158Y56583D01*
X250450Y56500D01*
X250742D01*
X251033Y56583D01*
X251283Y56708D01*
X251492Y56875D01*
G01X253550Y56500D02*
Y59000D01*
X253050Y58500D01*
G01Y56500D02*
X254050D01*
G01X257150D02*
Y59000D01*
X255608Y57208D01*
X257692D01*
G01X248432Y81695D02*
Y84195D01*
X249432D01*
X249765Y84070D01*
X250015Y83778D01*
X250098Y83445D01*
X250015Y83112D01*
X249807Y82862D01*
X249432Y82737D01*
X248432D01*
G01X253282Y83987D02*
X253032Y84112D01*
X252740Y84195D01*
X252407D01*
X252032Y84070D01*
X251740Y83862D01*
X251532Y83612D01*
X251365Y83195D01*
X251323Y82820D01*
X251407Y82445D01*
X251532Y82195D01*
X251782Y81945D01*
X252073Y81778D01*
X252365Y81695D01*
X252657D01*
X252948Y81778D01*
X253198Y81903D01*
X253407Y82070D01*
G01X255465Y81695D02*
Y84195D01*
X254965Y83695D01*
G01Y81695D02*
X255965D01*
G01X258482D02*
X258565Y82237D01*
X258690Y82695D01*
X258857Y83112D01*
X259065Y83570D01*
X259398Y84195D01*
X257732D01*
G01X245016Y94550D02*
Y97050D01*
X246016D01*
X246349Y96925D01*
X246599Y96633D01*
X246682Y96300D01*
X246599Y95967D01*
X246391Y95717D01*
X246016Y95592D01*
X245016D01*
G01X248116Y94550D02*
Y97050D01*
X249157D01*
X249491Y96925D01*
X249699Y96758D01*
X249782Y96425D01*
X249699Y96092D01*
X249449Y95883D01*
X249157Y95758D01*
X248116D01*
G01X249157D02*
X249782Y94550D01*
G01X251257Y96633D02*
X251507Y96883D01*
X251799Y97008D01*
X252132Y97050D01*
X252549Y96967D01*
X252841Y96758D01*
X252924Y96508D01*
X252882Y96258D01*
X252716Y96050D01*
X251882Y95633D01*
X251507Y95342D01*
X251257Y94925D01*
X251174Y94550D01*
X252924D01*
G01X254357Y95592D02*
X254649Y95883D01*
X254899Y96050D01*
X255232Y96133D01*
X255524Y96050D01*
X255732Y95883D01*
X255899Y95633D01*
X255941Y95342D01*
X255899Y95092D01*
X255732Y94842D01*
X255482Y94633D01*
X255191Y94550D01*
X254857Y94633D01*
X254566Y94883D01*
X254399Y95258D01*
X254357Y95675D01*
X254441Y96217D01*
X254566Y96508D01*
X254774Y96800D01*
X255066Y97008D01*
X255357Y97050D01*
X255649Y96967D01*
X255857Y96758D01*
G01X243699Y93550D02*
Y97550D01*
X236299D01*
G01X248016Y75050D02*
Y77550D01*
X249016D01*
X249349Y77425D01*
X249599Y77133D01*
X249682Y76800D01*
X249599Y76467D01*
X249391Y76217D01*
X249016Y76092D01*
X248016D01*
G01X251116Y75050D02*
Y77550D01*
X252157D01*
X252491Y77425D01*
X252699Y77258D01*
X252782Y76925D01*
X252699Y76592D01*
X252449Y76383D01*
X252157Y76258D01*
X251116D01*
G01X252157D02*
X252782Y75050D01*
G01X255049D02*
Y77550D01*
X254549Y77050D01*
G01Y75050D02*
X255549D01*
G01X257441Y75342D02*
X257732Y75133D01*
X258066Y75050D01*
X258399Y75133D01*
X258691Y75383D01*
X258899Y75758D01*
X258982Y76133D01*
Y76592D01*
X258899Y76967D01*
X258691Y77300D01*
X258441Y77467D01*
X258149Y77550D01*
X257816Y77467D01*
X257566Y77300D01*
X257399Y77050D01*
X257316Y76717D01*
X257399Y76425D01*
X257607Y76133D01*
X257857Y75967D01*
X258149Y75925D01*
X258482Y76008D01*
X258732Y76217D01*
X258982Y76592D01*
G01X248920Y86153D02*
Y88653D01*
X249920D01*
X250253Y88528D01*
X250503Y88236D01*
X250586Y87903D01*
X250503Y87570D01*
X250295Y87320D01*
X249920Y87195D01*
X248920D01*
G01X253770Y88445D02*
X253520Y88570D01*
X253228Y88653D01*
X252895D01*
X252520Y88528D01*
X252228Y88320D01*
X252020Y88070D01*
X251853Y87653D01*
X251811Y87278D01*
X251895Y86903D01*
X252020Y86653D01*
X252270Y86403D01*
X252561Y86236D01*
X252853Y86153D01*
X253145D01*
X253436Y86236D01*
X253686Y86361D01*
X253895Y86528D01*
G01X255161Y88236D02*
X255411Y88486D01*
X255703Y88611D01*
X256036Y88653D01*
X256453Y88570D01*
X256745Y88361D01*
X256828Y88111D01*
X256786Y87861D01*
X256620Y87653D01*
X255786Y87236D01*
X255411Y86945D01*
X255161Y86528D01*
X255078Y86153D01*
X256828D01*
G01X258136Y86653D02*
X258386Y86361D01*
X258720Y86195D01*
X259095Y86153D01*
X259428Y86195D01*
X259761Y86403D01*
X259970Y86653D01*
X260011Y86903D01*
X259928Y87195D01*
X259636Y87403D01*
X259345Y87486D01*
X258970D01*
G01X259345D02*
X259595Y87611D01*
X259803Y87820D01*
X259886Y88070D01*
X259803Y88320D01*
X259595Y88528D01*
X259220Y88653D01*
X258845Y88611D01*
X258470Y88445D01*
G01X245066Y101050D02*
Y103550D01*
X246066D01*
X246399Y103425D01*
X246649Y103133D01*
X246732Y102800D01*
X246649Y102467D01*
X246441Y102217D01*
X246066Y102092D01*
X245066D01*
G01X249249Y102300D02*
X250082D01*
Y101550D01*
X249832Y101300D01*
X249541Y101133D01*
X249124Y101050D01*
X248707Y101133D01*
X248416Y101300D01*
X248166Y101550D01*
X247999Y101842D01*
X247916Y102175D01*
Y102467D01*
X247999Y102717D01*
X248166Y103008D01*
X248416Y103258D01*
X248666Y103425D01*
X248999Y103550D01*
X249291D01*
X249624Y103467D01*
X249874Y103300D01*
G01X251307Y103133D02*
X251557Y103383D01*
X251849Y103508D01*
X252182Y103550D01*
X252599Y103467D01*
X252891Y103258D01*
X252974Y103008D01*
X252932Y102758D01*
X252766Y102550D01*
X251932Y102133D01*
X251557Y101842D01*
X251307Y101425D01*
X251224Y101050D01*
X252974D01*
G01X238417Y233500D02*
Y238500D01*
X241583D01*
G01X240417Y236083D02*
X238417D01*
G01X245600Y233500D02*
Y238500D01*
X244600Y237500D01*
G01Y233500D02*
X246600D01*
G01X249783Y234083D02*
X250367Y233667D01*
X251033Y233500D01*
X251700Y233667D01*
X252283Y234167D01*
X252700Y234917D01*
X252867Y235667D01*
Y236583D01*
X252700Y237333D01*
X252283Y238000D01*
X251783Y238333D01*
X251200Y238500D01*
X250533Y238333D01*
X250033Y238000D01*
X249700Y237500D01*
X249533Y236833D01*
X249700Y236250D01*
X250117Y235667D01*
X250617Y235333D01*
X251200Y235250D01*
X251867Y235417D01*
X252367Y235833D01*
X252867Y236583D01*
G01X256800Y233333D02*
X256633Y233417D01*
Y233583D01*
X256800Y233667D01*
X256967Y233583D01*
Y233417D01*
X256800Y233333D01*
G01Y235583D02*
X256633Y235667D01*
Y235833D01*
X256800Y235917D01*
X256967Y235833D01*
Y235667D01*
X256800Y235583D01*
G01X260817Y237667D02*
X261317Y238167D01*
X261900Y238417D01*
X262567Y238500D01*
X263400Y238333D01*
X263983Y237917D01*
X264150Y237417D01*
X264067Y236917D01*
X263733Y236500D01*
X262067Y235667D01*
X261317Y235083D01*
X260817Y234250D01*
X260650Y233500D01*
X264150D01*
G01X265917D02*
X268000Y238500D01*
X270083Y233500D01*
G01X269333Y235250D02*
X266667D01*
G01X272100Y233333D02*
X275100Y238500D01*
G01X277617Y235583D02*
X278200Y236167D01*
X278700Y236500D01*
X279367Y236667D01*
X279950Y236500D01*
X280367Y236167D01*
X280700Y235667D01*
X280783Y235083D01*
X280700Y234583D01*
X280367Y234083D01*
X279867Y233667D01*
X279283Y233500D01*
X278617Y233667D01*
X278033Y234167D01*
X277700Y234917D01*
X277617Y235750D01*
X277783Y236833D01*
X278033Y237417D01*
X278450Y238000D01*
X279033Y238417D01*
X279617Y238500D01*
X280200Y238333D01*
X280617Y237917D01*
G01X282717Y238500D02*
X284800Y233500D01*
X286883Y238500D01*
G01X241400Y260500D02*
X241067Y260542D01*
X240775Y260708D01*
X240525Y260958D01*
X240358Y261250D01*
X240275Y261583D01*
Y261917D01*
X240358Y262250D01*
X240525Y262542D01*
X240775Y262792D01*
X241067Y262958D01*
X241400Y263000D01*
X241733Y262958D01*
X242025Y262792D01*
X242275Y262542D01*
X242442Y262250D01*
X242525Y261917D01*
Y261583D01*
X242442Y261250D01*
X242275Y260958D01*
X242025Y260708D01*
X241733Y260542D01*
X241400Y260500D01*
G01X241733Y261167D02*
X242233Y260500D01*
G01X243708Y261542D02*
X244000Y261833D01*
X244250Y262000D01*
X244583Y262083D01*
X244875Y262000D01*
X245083Y261833D01*
X245250Y261583D01*
X245292Y261292D01*
X245250Y261042D01*
X245083Y260792D01*
X244833Y260583D01*
X244542Y260500D01*
X244208Y260583D01*
X243917Y260833D01*
X243750Y261208D01*
X243708Y261625D01*
X243792Y262167D01*
X243917Y262458D01*
X244125Y262750D01*
X244417Y262958D01*
X244708Y263000D01*
X245000Y262917D01*
X245208Y262708D01*
G01X248100Y260500D02*
Y263000D01*
X246558Y261208D01*
X248642D01*
G01X240517Y255500D02*
Y258000D01*
X241558D01*
X241892Y257875D01*
X242100Y257708D01*
X242183Y257375D01*
X242100Y257042D01*
X241850Y256833D01*
X241558Y256708D01*
X240517D01*
G01X241558D02*
X242183Y255500D01*
G01X243533Y256000D02*
X243783Y255708D01*
X244117Y255542D01*
X244492Y255500D01*
X244825Y255542D01*
X245158Y255750D01*
X245367Y256000D01*
X245408Y256250D01*
X245325Y256542D01*
X245033Y256750D01*
X244742Y256833D01*
X244367D01*
G01X244742D02*
X244992Y256958D01*
X245200Y257167D01*
X245283Y257417D01*
X245200Y257667D01*
X244992Y257875D01*
X244617Y258000D01*
X244242Y257958D01*
X243867Y257792D01*
G01X246842Y255792D02*
X247133Y255583D01*
X247467Y255500D01*
X247800Y255583D01*
X248092Y255833D01*
X248300Y256208D01*
X248383Y256583D01*
Y257042D01*
X248300Y257417D01*
X248092Y257750D01*
X247842Y257917D01*
X247550Y258000D01*
X247217Y257917D01*
X246967Y257750D01*
X246800Y257500D01*
X246717Y257167D01*
X246800Y256875D01*
X247008Y256583D01*
X247258Y256417D01*
X247550Y256375D01*
X247883Y256458D01*
X248133Y256667D01*
X248383Y257042D01*
G01X249733Y255875D02*
X249983Y255667D01*
X250275Y255542D01*
X250650Y255500D01*
X251025Y255583D01*
X251317Y255750D01*
X251525Y256042D01*
X251567Y256375D01*
X251483Y256708D01*
X251275Y256917D01*
X250983Y257083D01*
X250692Y257125D01*
X250400Y257083D01*
X250025Y256917D01*
X250150Y258000D01*
X251275D01*
G01X238900Y272100D02*
X250300D01*
G01X238900Y285500D02*
Y272100D01*
G01X250300D02*
Y285500D01*
G01X246000Y267700D02*
Y271700D01*
X238600D01*
G01X238000Y266100D02*
Y280100D01*
G01X250300Y285500D02*
X238900D01*
G01X241498Y290114D02*
Y303114D01*
G01X230648Y314364D02*
Y304864D01*
X248348D01*
Y314364D01*
X230648D01*
G01X242300Y303500D02*
X249300D01*
Y290100D01*
X242300D01*
Y303500D01*
G01X241498Y323114D02*
Y336114D01*
G01X251498Y327214D02*
Y366014D01*
G01X274498Y327214D02*
X251498D01*
G01X242498Y315814D02*
Y321314D01*
G01X250498Y315814D02*
X242498D01*
G01X250498Y321314D02*
Y315814D01*
G01X231607Y316550D02*
Y319050D01*
X233191D01*
G01X232607Y317842D02*
X231607D01*
G01X235499Y316550D02*
Y319050D01*
X234999Y318550D01*
G01Y316550D02*
X235999D01*
G01X237891Y316842D02*
X238182Y316633D01*
X238516Y316550D01*
X238849Y316633D01*
X239141Y316883D01*
X239349Y317258D01*
X239432Y317633D01*
Y318092D01*
X239349Y318467D01*
X239141Y318800D01*
X238891Y318967D01*
X238599Y319050D01*
X238266Y318967D01*
X238016Y318800D01*
X237849Y318550D01*
X237766Y318217D01*
X237849Y317925D01*
X238057Y317633D01*
X238307Y317467D01*
X238599Y317425D01*
X238932Y317508D01*
X239182Y317717D01*
X239432Y318092D01*
G01X250498Y333414D02*
Y327914D01*
G01X242498Y333414D02*
X250498D01*
G01X242498Y327914D02*
Y333414D01*
G01X233698Y337314D02*
Y342814D01*
G01X241698Y337314D02*
X233698D01*
G01X241698Y342814D02*
Y337314D01*
G01X232998Y342814D02*
Y337314D01*
G01X250400Y337300D02*
Y354900D01*
G01X242400Y337300D02*
X250400D01*
G01X242400Y354900D02*
Y337300D01*
G01X251498Y366014D02*
X274498D01*
G01X236906Y359281D02*
X236781Y359031D01*
X236698Y358739D01*
Y358406D01*
X236823Y358031D01*
X237031Y357739D01*
X237281Y357531D01*
X237698Y357364D01*
X238073Y357322D01*
X238448Y357406D01*
X238698Y357531D01*
X238948Y357781D01*
X239115Y358072D01*
X239198Y358364D01*
Y358656D01*
X239115Y358947D01*
X238990Y359197D01*
X238823Y359406D01*
G01X237115Y360672D02*
X236865Y360922D01*
X236740Y361214D01*
X236698Y361547D01*
X236781Y361964D01*
X236990Y362256D01*
X237240Y362339D01*
X237490Y362297D01*
X237698Y362131D01*
X238115Y361297D01*
X238406Y360922D01*
X238823Y360672D01*
X239198Y360589D01*
Y362339D01*
G01X238823Y363647D02*
X239031Y363897D01*
X239156Y364189D01*
X239198Y364564D01*
X239115Y364939D01*
X238948Y365231D01*
X238656Y365439D01*
X238323Y365481D01*
X237990Y365397D01*
X237781Y365189D01*
X237615Y364897D01*
X237573Y364606D01*
X237615Y364314D01*
X237781Y363939D01*
X236698Y364064D01*
Y365189D01*
G01X238156Y366872D02*
X237865Y367164D01*
X237698Y367414D01*
X237615Y367747D01*
X237698Y368039D01*
X237865Y368247D01*
X238115Y368414D01*
X238406Y368456D01*
X238656Y368414D01*
X238906Y368247D01*
X239115Y367997D01*
X239198Y367706D01*
X239115Y367372D01*
X238865Y367081D01*
X238490Y366914D01*
X238073Y366872D01*
X237531Y366956D01*
X237240Y367081D01*
X236948Y367289D01*
X236740Y367581D01*
X236698Y367872D01*
X236781Y368164D01*
X236990Y368372D01*
G01X241698Y354914D02*
Y349414D01*
G01X233698Y354914D02*
X241698D01*
G01X233698Y349414D02*
Y354914D01*
G01X232998D02*
Y349414D01*
G01X247000Y357017D02*
X244500D01*
Y358058D01*
X244625Y358392D01*
X244792Y358600D01*
X245125Y358683D01*
X245458Y358600D01*
X245667Y358350D01*
X245792Y358058D01*
Y357017D01*
G01Y358058D02*
X247000Y358683D01*
G01X246625Y360033D02*
X246833Y360283D01*
X246958Y360575D01*
X247000Y360950D01*
X246917Y361325D01*
X246750Y361617D01*
X246458Y361825D01*
X246125Y361867D01*
X245792Y361783D01*
X245583Y361575D01*
X245417Y361283D01*
X245375Y360992D01*
X245417Y360700D01*
X245583Y360325D01*
X244500Y360450D01*
Y361575D01*
G01X246500Y363133D02*
X246792Y363383D01*
X246958Y363717D01*
X247000Y364092D01*
X246958Y364425D01*
X246750Y364758D01*
X246500Y364967D01*
X246250Y365008D01*
X245958Y364925D01*
X245750Y364633D01*
X245667Y364342D01*
Y363967D01*
G01Y364342D02*
X245542Y364592D01*
X245333Y364800D01*
X245083Y364883D01*
X244833Y364800D01*
X244625Y364592D01*
X244500Y364217D01*
X244542Y363842D01*
X244708Y363467D01*
G01X247000Y367150D02*
X244500D01*
X245000Y366650D01*
G01X247000D02*
Y367650D01*
G01X250400Y354900D02*
X242400D01*
G01X235000Y516900D02*
X234958Y516567D01*
X234792Y516275D01*
X234542Y516025D01*
X234250Y515858D01*
X233917Y515775D01*
X233583D01*
X233250Y515858D01*
X232958Y516025D01*
X232708Y516275D01*
X232542Y516567D01*
X232500Y516900D01*
X232542Y517233D01*
X232708Y517525D01*
X232958Y517775D01*
X233250Y517942D01*
X233583Y518025D01*
X233917D01*
X234250Y517942D01*
X234542Y517775D01*
X234792Y517525D01*
X234958Y517233D01*
X235000Y516900D01*
G01X234333Y517233D02*
X235000Y517733D01*
G01X232917Y519208D02*
X232667Y519458D01*
X232542Y519750D01*
X232500Y520083D01*
X232583Y520500D01*
X232792Y520792D01*
X233042Y520875D01*
X233292Y520833D01*
X233500Y520667D01*
X233917Y519833D01*
X234208Y519458D01*
X234625Y519208D01*
X235000Y519125D01*
Y520875D01*
G01Y523017D02*
X234458Y523100D01*
X234000Y523225D01*
X233583Y523392D01*
X233125Y523600D01*
X232500Y523933D01*
Y522267D01*
G01X238017Y663500D02*
Y666000D01*
X239058D01*
X239392Y665875D01*
X239600Y665708D01*
X239683Y665375D01*
X239600Y665042D01*
X239350Y664833D01*
X239058Y664708D01*
X238017D01*
G01X239058D02*
X239683Y663500D01*
G01X241033Y664000D02*
X241283Y663708D01*
X241617Y663542D01*
X241992Y663500D01*
X242325Y663542D01*
X242658Y663750D01*
X242867Y664000D01*
X242908Y664250D01*
X242825Y664542D01*
X242533Y664750D01*
X242242Y664833D01*
X241867D01*
G01X242242D02*
X242492Y664958D01*
X242700Y665167D01*
X242783Y665417D01*
X242700Y665667D01*
X242492Y665875D01*
X242117Y666000D01*
X241742Y665958D01*
X241367Y665792D01*
G01X245050Y663500D02*
X245342Y663542D01*
X245675Y663667D01*
X245883Y663875D01*
X245967Y664167D01*
X245883Y664458D01*
X245633Y664708D01*
X245258Y664833D01*
X244842D01*
X244592Y664917D01*
X244383Y665125D01*
X244300Y665417D01*
X244425Y665708D01*
X244717Y665917D01*
X245050Y666000D01*
X245383Y665917D01*
X245675Y665708D01*
X245800Y665417D01*
X245717Y665125D01*
X245508Y664917D01*
X245258Y664833D01*
X244842D01*
X244467Y664708D01*
X244217Y664458D01*
X244133Y664167D01*
X244217Y663875D01*
X244425Y663667D01*
X244758Y663542D01*
X245050Y663500D01*
G01X247233Y663875D02*
X247483Y663667D01*
X247775Y663542D01*
X248150Y663500D01*
X248525Y663583D01*
X248817Y663750D01*
X249025Y664042D01*
X249067Y664375D01*
X248983Y664708D01*
X248775Y664917D01*
X248483Y665083D01*
X248192Y665125D01*
X247900Y665083D01*
X247525Y664917D01*
X247650Y666000D01*
X248775D01*
G01X238300Y679500D02*
X249700D01*
G01X238300Y692900D02*
Y679500D01*
G01X249700D02*
Y692900D01*
G01X245400Y675100D02*
Y679100D01*
X238000D01*
G01X237400Y673000D02*
Y687000D01*
G01X249700Y692900D02*
X238300D01*
G01X241999Y696550D02*
Y709550D01*
G01X242800Y710400D02*
X249800D01*
Y697000D01*
X242800D01*
Y710400D01*
G01X242499Y722750D02*
Y728250D01*
G01X250499Y722750D02*
X242499D01*
G01X250499Y728250D02*
Y722750D01*
G01X232607Y723050D02*
Y725550D01*
X234191D01*
G01X233607Y724342D02*
X232607D01*
G01X236499Y723050D02*
Y725550D01*
X235999Y725050D01*
G01Y723050D02*
X236999D01*
G01X239516D02*
X239599Y723592D01*
X239724Y724050D01*
X239891Y724467D01*
X240099Y724925D01*
X240432Y725550D01*
X238766D01*
G01X231149Y721300D02*
Y711800D01*
X248849D01*
Y721300D01*
X231149D01*
G01X241499Y730550D02*
Y743550D01*
G01X250499Y740350D02*
Y734850D01*
G01X242499Y740350D02*
X250499D01*
G01X242499Y734850D02*
Y740350D01*
G01X234699Y746250D02*
Y751750D01*
G01X242699Y746250D02*
X234699D01*
G01X242699Y751750D02*
Y746250D01*
G01X233999Y751750D02*
Y746250D01*
G01X251400Y746300D02*
Y763900D01*
G01X243400Y746300D02*
X251400D01*
G01X243400Y763900D02*
Y746300D01*
G01X237407Y768217D02*
X237282Y767967D01*
X237199Y767675D01*
Y767342D01*
X237324Y766967D01*
X237532Y766675D01*
X237782Y766467D01*
X238199Y766300D01*
X238574Y766258D01*
X238949Y766342D01*
X239199Y766467D01*
X239449Y766717D01*
X239616Y767008D01*
X239699Y767300D01*
Y767592D01*
X239616Y767883D01*
X239491Y768133D01*
X239324Y768342D01*
G01X237616Y769608D02*
X237366Y769858D01*
X237241Y770150D01*
X237199Y770483D01*
X237282Y770900D01*
X237491Y771192D01*
X237741Y771275D01*
X237991Y771233D01*
X238199Y771067D01*
X238616Y770233D01*
X238907Y769858D01*
X239324Y769608D01*
X239699Y769525D01*
Y771275D01*
G01Y774000D02*
X237199D01*
X238991Y772458D01*
Y774542D01*
G01X237199Y776600D02*
X237282Y776267D01*
X237491Y776017D01*
X237741Y775850D01*
X238074Y775725D01*
X238449Y775683D01*
X238824Y775725D01*
X239157Y775850D01*
X239407Y776017D01*
X239616Y776267D01*
X239699Y776600D01*
X239616Y776933D01*
X239407Y777183D01*
X239157Y777350D01*
X238824Y777475D01*
X238449Y777517D01*
X238074Y777475D01*
X237741Y777350D01*
X237491Y777183D01*
X237282Y776933D01*
X237199Y776600D01*
G01X242699Y763850D02*
Y758350D01*
G01X234699Y763850D02*
X242699D01*
G01X234699Y758350D02*
Y763850D01*
G01X233999D02*
Y758350D01*
G01X244000Y766517D02*
X241500D01*
Y767558D01*
X241625Y767892D01*
X241792Y768100D01*
X242125Y768183D01*
X242458Y768100D01*
X242667Y767850D01*
X242792Y767558D01*
Y766517D01*
G01Y767558D02*
X244000Y768183D01*
G01X243625Y769533D02*
X243833Y769783D01*
X243958Y770075D01*
X244000Y770450D01*
X243917Y770825D01*
X243750Y771117D01*
X243458Y771325D01*
X243125Y771367D01*
X242792Y771283D01*
X242583Y771075D01*
X242417Y770783D01*
X242375Y770492D01*
X242417Y770200D01*
X242583Y769825D01*
X241500Y769950D01*
Y771075D01*
G01X241917Y772758D02*
X241667Y773008D01*
X241542Y773300D01*
X241500Y773633D01*
X241583Y774050D01*
X241792Y774342D01*
X242042Y774425D01*
X242292Y774383D01*
X242500Y774217D01*
X242917Y773383D01*
X243208Y773008D01*
X243625Y772758D01*
X244000Y772675D01*
Y774425D01*
G01X243708Y775942D02*
X243917Y776233D01*
X244000Y776567D01*
X243917Y776900D01*
X243667Y777192D01*
X243292Y777400D01*
X242917Y777483D01*
X242458D01*
X242083Y777400D01*
X241750Y777192D01*
X241583Y776942D01*
X241500Y776650D01*
X241583Y776317D01*
X241750Y776067D01*
X242000Y775900D01*
X242333Y775817D01*
X242625Y775900D01*
X242917Y776108D01*
X243083Y776358D01*
X243125Y776650D01*
X243042Y776983D01*
X242833Y777233D01*
X242458Y777483D01*
G01X251400Y763900D02*
X243400D01*
G01X241916Y794550D02*
Y799550D01*
X245082D01*
G01X243916Y797133D02*
X241916D01*
G01X249099Y794550D02*
Y799550D01*
X248099Y798550D01*
G01Y794550D02*
X250099D01*
G01X254699D02*
X255282Y794633D01*
X255949Y794883D01*
X256366Y795300D01*
X256532Y795883D01*
X256366Y796467D01*
X255866Y796967D01*
X255116Y797217D01*
X254282D01*
X253782Y797383D01*
X253366Y797800D01*
X253199Y798383D01*
X253449Y798967D01*
X254032Y799383D01*
X254699Y799550D01*
X255366Y799383D01*
X255949Y798967D01*
X256199Y798383D01*
X256032Y797800D01*
X255616Y797383D01*
X255116Y797217D01*
X254282D01*
X253532Y796967D01*
X253032Y796467D01*
X252866Y795883D01*
X253032Y795300D01*
X253449Y794883D01*
X254116Y794633D01*
X254699Y794550D01*
G01X260299Y794383D02*
X260132Y794467D01*
Y794633D01*
X260299Y794717D01*
X260466Y794633D01*
Y794467D01*
X260299Y794383D01*
G01Y796633D02*
X260132Y796717D01*
Y796883D01*
X260299Y796967D01*
X260466Y796883D01*
Y796717D01*
X260299Y796633D01*
G01X264066Y795550D02*
X264566Y794967D01*
X265232Y794633D01*
X265982Y794550D01*
X266649Y794633D01*
X267316Y795050D01*
X267732Y795550D01*
X267816Y796050D01*
X267649Y796633D01*
X267066Y797050D01*
X266482Y797217D01*
X265732D01*
G01X266482D02*
X266982Y797467D01*
X267399Y797883D01*
X267566Y798383D01*
X267399Y798883D01*
X266982Y799300D01*
X266232Y799550D01*
X265482Y799467D01*
X264732Y799133D01*
G01X269416Y794550D02*
X271499Y799550D01*
X273582Y794550D01*
G01X272832Y796300D02*
X270166D01*
G01X275599Y794383D02*
X278599Y799550D01*
G01X282699Y794550D02*
Y799550D01*
X281699Y798550D01*
G01Y794550D02*
X283699D01*
G01X286466Y795300D02*
X286966Y794883D01*
X287549Y794633D01*
X288299Y794550D01*
X289049Y794717D01*
X289632Y795050D01*
X290049Y795633D01*
X290132Y796300D01*
X289966Y796967D01*
X289549Y797383D01*
X288966Y797717D01*
X288382Y797800D01*
X287799Y797717D01*
X287049Y797383D01*
X287299Y799550D01*
X289549D01*
G01X291816D02*
X293899Y794550D01*
X295982Y799550D01*
G01X242499Y855158D02*
X239999D01*
Y856742D01*
G01X241207Y856158D02*
Y855158D01*
G01X240416Y858258D02*
X240166Y858508D01*
X240041Y858800D01*
X239999Y859133D01*
X240082Y859550D01*
X240291Y859842D01*
X240541Y859925D01*
X240791Y859883D01*
X240999Y859717D01*
X241416Y858883D01*
X241707Y858508D01*
X242124Y858258D01*
X242499Y858175D01*
Y859925D01*
G01X241457Y861358D02*
X241166Y861650D01*
X240999Y861900D01*
X240916Y862233D01*
X240999Y862525D01*
X241166Y862733D01*
X241416Y862900D01*
X241707Y862942D01*
X241957Y862900D01*
X242207Y862733D01*
X242416Y862483D01*
X242499Y862192D01*
X242416Y861858D01*
X242166Y861567D01*
X241791Y861400D01*
X241374Y861358D01*
X240832Y861442D01*
X240541Y861567D01*
X240249Y861775D01*
X240041Y862067D01*
X239999Y862358D01*
X240082Y862650D01*
X240291Y862858D01*
G01X235899Y871113D02*
Y848113D01*
G01X234708Y886767D02*
X234583Y886517D01*
X234500Y886225D01*
Y885892D01*
X234625Y885517D01*
X234833Y885225D01*
X235083Y885017D01*
X235500Y884850D01*
X235875Y884808D01*
X236250Y884892D01*
X236500Y885017D01*
X236750Y885267D01*
X236917Y885558D01*
X237000Y885850D01*
Y886142D01*
X236917Y886433D01*
X236792Y886683D01*
X236625Y886892D01*
G01X234917Y888158D02*
X234667Y888408D01*
X234542Y888700D01*
X234500Y889033D01*
X234583Y889450D01*
X234792Y889742D01*
X235042Y889825D01*
X235292Y889783D01*
X235500Y889617D01*
X235917Y888783D01*
X236208Y888408D01*
X236625Y888158D01*
X237000Y888075D01*
Y889825D01*
G01X236708Y891342D02*
X236917Y891633D01*
X237000Y891967D01*
X236917Y892300D01*
X236667Y892592D01*
X236292Y892800D01*
X235917Y892883D01*
X235458D01*
X235083Y892800D01*
X234750Y892592D01*
X234583Y892342D01*
X234500Y892050D01*
X234583Y891717D01*
X234750Y891467D01*
X235000Y891300D01*
X235333Y891217D01*
X235625Y891300D01*
X235917Y891508D01*
X236083Y891758D01*
X236125Y892050D01*
X236042Y892383D01*
X235833Y892633D01*
X235458Y892883D01*
G01X236500Y894233D02*
X236792Y894483D01*
X236958Y894817D01*
X237000Y895192D01*
X236958Y895525D01*
X236750Y895858D01*
X236500Y896067D01*
X236250Y896108D01*
X235958Y896025D01*
X235750Y895733D01*
X235667Y895442D01*
Y895067D01*
G01Y895442D02*
X235542Y895692D01*
X235333Y895900D01*
X235083Y895983D01*
X234833Y895900D01*
X234625Y895692D01*
X234500Y895317D01*
X234542Y894942D01*
X234708Y894567D01*
G01X233000Y885017D02*
X230500D01*
Y886058D01*
X230625Y886392D01*
X230792Y886600D01*
X231125Y886683D01*
X231458Y886600D01*
X231667Y886350D01*
X231792Y886058D01*
Y885017D01*
G01Y886058D02*
X233000Y886683D01*
G01Y889450D02*
X230500D01*
X232292Y887908D01*
Y889992D01*
G01X231958Y891258D02*
X231667Y891550D01*
X231500Y891800D01*
X231417Y892133D01*
X231500Y892425D01*
X231667Y892633D01*
X231917Y892800D01*
X232208Y892842D01*
X232458Y892800D01*
X232708Y892633D01*
X232917Y892383D01*
X233000Y892092D01*
X232917Y891758D01*
X232667Y891467D01*
X232292Y891300D01*
X231875Y891258D01*
X231333Y891342D01*
X231042Y891467D01*
X230750Y891675D01*
X230542Y891967D01*
X230500Y892258D01*
X230583Y892550D01*
X230792Y892758D01*
G01X232708Y894442D02*
X232917Y894733D01*
X233000Y895067D01*
X232917Y895400D01*
X232667Y895692D01*
X232292Y895900D01*
X231917Y895983D01*
X231458D01*
X231083Y895900D01*
X230750Y895692D01*
X230583Y895442D01*
X230500Y895150D01*
X230583Y894817D01*
X230750Y894567D01*
X231000Y894400D01*
X231333Y894317D01*
X231625Y894400D01*
X231917Y894608D01*
X232083Y894858D01*
X232125Y895150D01*
X232042Y895483D01*
X231833Y895733D01*
X231458Y895983D01*
G01X238999Y920450D02*
X238957Y920117D01*
X238791Y919825D01*
X238541Y919575D01*
X238249Y919408D01*
X237916Y919325D01*
X237582D01*
X237249Y919408D01*
X236957Y919575D01*
X236707Y919825D01*
X236541Y920117D01*
X236499Y920450D01*
X236541Y920783D01*
X236707Y921075D01*
X236957Y921325D01*
X237249Y921492D01*
X237582Y921575D01*
X237916D01*
X238249Y921492D01*
X238541Y921325D01*
X238791Y921075D01*
X238957Y920783D01*
X238999Y920450D01*
G01X238332Y920783D02*
X238999Y921283D01*
G01X236916Y922758D02*
X236666Y923008D01*
X236541Y923300D01*
X236499Y923633D01*
X236582Y924050D01*
X236791Y924342D01*
X237041Y924425D01*
X237291Y924383D01*
X237499Y924217D01*
X237916Y923383D01*
X238207Y923008D01*
X238624Y922758D01*
X238999Y922675D01*
Y924425D01*
G01X238624Y925733D02*
X238832Y925983D01*
X238957Y926275D01*
X238999Y926650D01*
X238916Y927025D01*
X238749Y927317D01*
X238457Y927525D01*
X238124Y927567D01*
X237791Y927483D01*
X237582Y927275D01*
X237416Y926983D01*
X237374Y926692D01*
X237416Y926400D01*
X237582Y926025D01*
X236499Y926150D01*
Y927275D01*
G01X232400Y1061000D02*
X232067Y1061042D01*
X231775Y1061208D01*
X231525Y1061458D01*
X231358Y1061750D01*
X231275Y1062083D01*
Y1062417D01*
X231358Y1062750D01*
X231525Y1063042D01*
X231775Y1063292D01*
X232067Y1063458D01*
X232400Y1063500D01*
X232733Y1063458D01*
X233025Y1063292D01*
X233275Y1063042D01*
X233442Y1062750D01*
X233525Y1062417D01*
Y1062083D01*
X233442Y1061750D01*
X233275Y1061458D01*
X233025Y1061208D01*
X232733Y1061042D01*
X232400Y1061000D01*
G01X232733Y1061667D02*
X233233Y1061000D01*
G01X234708Y1062042D02*
X235000Y1062333D01*
X235250Y1062500D01*
X235583Y1062583D01*
X235875Y1062500D01*
X236083Y1062333D01*
X236250Y1062083D01*
X236292Y1061792D01*
X236250Y1061542D01*
X236083Y1061292D01*
X235833Y1061083D01*
X235542Y1061000D01*
X235208Y1061083D01*
X234917Y1061333D01*
X234750Y1061708D01*
X234708Y1062125D01*
X234792Y1062667D01*
X234917Y1062958D01*
X235125Y1063250D01*
X235417Y1063458D01*
X235708Y1063500D01*
X236000Y1063417D01*
X236208Y1063208D01*
G01X238600Y1063500D02*
X238267Y1063417D01*
X238017Y1063208D01*
X237850Y1062958D01*
X237725Y1062625D01*
X237683Y1062250D01*
X237725Y1061875D01*
X237850Y1061542D01*
X238017Y1061292D01*
X238267Y1061083D01*
X238600Y1061000D01*
X238933Y1061083D01*
X239183Y1061292D01*
X239350Y1061542D01*
X239475Y1061875D01*
X239517Y1062250D01*
X239475Y1062625D01*
X239350Y1062958D01*
X239183Y1063208D01*
X238933Y1063417D01*
X238600Y1063500D01*
G01X245000Y1065860D02*
Y1077260D01*
G01X231600Y1065860D02*
X245000D01*
G01X231600Y1077260D02*
Y1065860D01*
G01X250000Y1062017D02*
X247500D01*
Y1063058D01*
X247625Y1063392D01*
X247792Y1063600D01*
X248125Y1063683D01*
X248458Y1063600D01*
X248667Y1063350D01*
X248792Y1063058D01*
Y1062017D01*
G01Y1063058D02*
X250000Y1063683D01*
G01X249500Y1065033D02*
X249792Y1065283D01*
X249958Y1065617D01*
X250000Y1065992D01*
X249958Y1066325D01*
X249750Y1066658D01*
X249500Y1066867D01*
X249250Y1066908D01*
X248958Y1066825D01*
X248750Y1066533D01*
X248667Y1066242D01*
Y1065867D01*
G01Y1066242D02*
X248542Y1066492D01*
X248333Y1066700D01*
X248083Y1066783D01*
X247833Y1066700D01*
X247625Y1066492D01*
X247500Y1066117D01*
X247542Y1065742D01*
X247708Y1065367D01*
G01X250000Y1069050D02*
X249958Y1069342D01*
X249833Y1069675D01*
X249625Y1069883D01*
X249333Y1069967D01*
X249042Y1069883D01*
X248792Y1069633D01*
X248667Y1069258D01*
Y1068842D01*
X248583Y1068592D01*
X248375Y1068383D01*
X248083Y1068300D01*
X247792Y1068425D01*
X247583Y1068717D01*
X247500Y1069050D01*
X247583Y1069383D01*
X247792Y1069675D01*
X248083Y1069800D01*
X248375Y1069717D01*
X248583Y1069508D01*
X248667Y1069258D01*
Y1068842D01*
X248792Y1068467D01*
X249042Y1068217D01*
X249333Y1068133D01*
X249625Y1068217D01*
X249833Y1068425D01*
X249958Y1068758D01*
X250000Y1069050D01*
G01X249500Y1071233D02*
X249792Y1071483D01*
X249958Y1071817D01*
X250000Y1072192D01*
X249958Y1072525D01*
X249750Y1072858D01*
X249500Y1073067D01*
X249250Y1073108D01*
X248958Y1073025D01*
X248750Y1072733D01*
X248667Y1072442D01*
Y1072067D01*
G01Y1072442D02*
X248542Y1072692D01*
X248333Y1072900D01*
X248083Y1072983D01*
X247833Y1072900D01*
X247625Y1072692D01*
X247500Y1072317D01*
X247542Y1071942D01*
X247708Y1071567D01*
G01X245000Y1077260D02*
X231600D01*
G01X249500Y1083950D02*
X245500D01*
Y1076550D01*
G01X249000Y1087400D02*
X248958Y1087067D01*
X248792Y1086775D01*
X248542Y1086525D01*
X248250Y1086358D01*
X247917Y1086275D01*
X247583D01*
X247250Y1086358D01*
X246958Y1086525D01*
X246708Y1086775D01*
X246542Y1087067D01*
X246500Y1087400D01*
X246542Y1087733D01*
X246708Y1088025D01*
X246958Y1088275D01*
X247250Y1088442D01*
X247583Y1088525D01*
X247917D01*
X248250Y1088442D01*
X248542Y1088275D01*
X248792Y1088025D01*
X248958Y1087733D01*
X249000Y1087400D01*
G01X248333Y1087733D02*
X249000Y1088233D01*
G01X247958Y1089708D02*
X247667Y1090000D01*
X247500Y1090250D01*
X247417Y1090583D01*
X247500Y1090875D01*
X247667Y1091083D01*
X247917Y1091250D01*
X248208Y1091292D01*
X248458Y1091250D01*
X248708Y1091083D01*
X248917Y1090833D01*
X249000Y1090542D01*
X248917Y1090208D01*
X248667Y1089917D01*
X248292Y1089750D01*
X247875Y1089708D01*
X247333Y1089792D01*
X247042Y1089917D01*
X246750Y1090125D01*
X246542Y1090417D01*
X246500Y1090708D01*
X246583Y1091000D01*
X246792Y1091208D01*
G01X249000Y1093600D02*
X246500D01*
X247000Y1093100D01*
G01X249000D02*
Y1094100D01*
G01X244750Y1079125D02*
Y1092125D01*
G01X230750Y1079125D02*
X244750D01*
G01X230750Y1092125D02*
Y1079125D01*
G01X243017Y1103000D02*
Y1105500D01*
X244058D01*
X244392Y1105375D01*
X244600Y1105208D01*
X244683Y1104875D01*
X244600Y1104542D01*
X244350Y1104333D01*
X244058Y1104208D01*
X243017D01*
G01X244058D02*
X244683Y1103000D01*
G01X246158Y1105083D02*
X246408Y1105333D01*
X246700Y1105458D01*
X247033Y1105500D01*
X247450Y1105417D01*
X247742Y1105208D01*
X247825Y1104958D01*
X247783Y1104708D01*
X247617Y1104500D01*
X246783Y1104083D01*
X246408Y1103792D01*
X246158Y1103375D01*
X246075Y1103000D01*
X247825D01*
G01X250050Y1105500D02*
X249717Y1105417D01*
X249467Y1105208D01*
X249300Y1104958D01*
X249175Y1104625D01*
X249133Y1104250D01*
X249175Y1103875D01*
X249300Y1103542D01*
X249467Y1103292D01*
X249717Y1103083D01*
X250050Y1103000D01*
X250383Y1103083D01*
X250633Y1103292D01*
X250800Y1103542D01*
X250925Y1103875D01*
X250967Y1104250D01*
X250925Y1104625D01*
X250800Y1104958D01*
X250633Y1105208D01*
X250383Y1105417D01*
X250050Y1105500D01*
G01X252233Y1103375D02*
X252483Y1103167D01*
X252775Y1103042D01*
X253150Y1103000D01*
X253525Y1103083D01*
X253817Y1103250D01*
X254025Y1103542D01*
X254067Y1103875D01*
X253983Y1104208D01*
X253775Y1104417D01*
X253483Y1104583D01*
X253192Y1104625D01*
X252900Y1104583D01*
X252525Y1104417D01*
X252650Y1105500D01*
X253775D01*
G01X241500Y1096600D02*
Y1109600D01*
G01X244750Y1092125D02*
X230750D01*
G01X237549Y1113840D02*
X247049D01*
Y1131540D01*
X237549D01*
Y1113840D01*
G01X233900Y1465500D02*
X233567Y1465542D01*
X233275Y1465708D01*
X233025Y1465958D01*
X232858Y1466250D01*
X232775Y1466583D01*
Y1466917D01*
X232858Y1467250D01*
X233025Y1467542D01*
X233275Y1467792D01*
X233567Y1467958D01*
X233900Y1468000D01*
X234233Y1467958D01*
X234525Y1467792D01*
X234775Y1467542D01*
X234942Y1467250D01*
X235025Y1466917D01*
Y1466583D01*
X234942Y1466250D01*
X234775Y1465958D01*
X234525Y1465708D01*
X234233Y1465542D01*
X233900Y1465500D01*
G01X234233Y1466167D02*
X234733Y1465500D01*
G01X236083Y1465875D02*
X236333Y1465667D01*
X236625Y1465542D01*
X237000Y1465500D01*
X237375Y1465583D01*
X237667Y1465750D01*
X237875Y1466042D01*
X237917Y1466375D01*
X237833Y1466708D01*
X237625Y1466917D01*
X237333Y1467083D01*
X237042Y1467125D01*
X236750Y1467083D01*
X236375Y1466917D01*
X236500Y1468000D01*
X237625D01*
G01X240100Y1465500D02*
X240392Y1465542D01*
X240725Y1465667D01*
X240933Y1465875D01*
X241017Y1466167D01*
X240933Y1466458D01*
X240683Y1466708D01*
X240308Y1466833D01*
X239892D01*
X239642Y1466917D01*
X239433Y1467125D01*
X239350Y1467417D01*
X239475Y1467708D01*
X239767Y1467917D01*
X240100Y1468000D01*
X240433Y1467917D01*
X240725Y1467708D01*
X240850Y1467417D01*
X240767Y1467125D01*
X240558Y1466917D01*
X240308Y1466833D01*
X239892D01*
X239517Y1466708D01*
X239267Y1466458D01*
X239183Y1466167D01*
X239267Y1465875D01*
X239475Y1465667D01*
X239808Y1465542D01*
X240100Y1465500D01*
G01X230600Y1481500D02*
Y1470100D01*
G01X244000Y1481500D02*
X230600D01*
G01X244000Y1470100D02*
Y1481500D01*
G01X230600Y1470100D02*
X244000D01*
G01Y1486400D02*
X243958Y1486067D01*
X243792Y1485775D01*
X243542Y1485525D01*
X243250Y1485358D01*
X242917Y1485275D01*
X242583D01*
X242250Y1485358D01*
X241958Y1485525D01*
X241708Y1485775D01*
X241542Y1486067D01*
X241500Y1486400D01*
X241542Y1486733D01*
X241708Y1487025D01*
X241958Y1487275D01*
X242250Y1487442D01*
X242583Y1487525D01*
X242917D01*
X243250Y1487442D01*
X243542Y1487275D01*
X243792Y1487025D01*
X243958Y1486733D01*
X244000Y1486400D01*
G01X243333Y1486733D02*
X244000Y1487233D01*
G01X243625Y1488583D02*
X243833Y1488833D01*
X243958Y1489125D01*
X244000Y1489500D01*
X243917Y1489875D01*
X243750Y1490167D01*
X243458Y1490375D01*
X243125Y1490417D01*
X242792Y1490333D01*
X242583Y1490125D01*
X242417Y1489833D01*
X242375Y1489542D01*
X242417Y1489250D01*
X242583Y1488875D01*
X241500Y1489000D01*
Y1490125D01*
G01X243708Y1491892D02*
X243917Y1492183D01*
X244000Y1492517D01*
X243917Y1492850D01*
X243667Y1493142D01*
X243292Y1493350D01*
X242917Y1493433D01*
X242458D01*
X242083Y1493350D01*
X241750Y1493142D01*
X241583Y1492892D01*
X241500Y1492600D01*
X241583Y1492267D01*
X241750Y1492017D01*
X242000Y1491850D01*
X242333Y1491767D01*
X242625Y1491850D01*
X242917Y1492058D01*
X243083Y1492308D01*
X243125Y1492600D01*
X243042Y1492933D01*
X242833Y1493183D01*
X242458Y1493433D01*
G01X239200Y1482700D02*
Y1496700D01*
G01X240300Y1506900D02*
Y1519900D01*
G01X246517Y1500500D02*
Y1503000D01*
X247558D01*
X247892Y1502875D01*
X248100Y1502708D01*
X248183Y1502375D01*
X248100Y1502042D01*
X247850Y1501833D01*
X247558Y1501708D01*
X246517D01*
G01X247558D02*
X248183Y1500500D01*
G01X249533Y1501000D02*
X249783Y1500708D01*
X250117Y1500542D01*
X250492Y1500500D01*
X250825Y1500542D01*
X251158Y1500750D01*
X251367Y1501000D01*
X251408Y1501250D01*
X251325Y1501542D01*
X251033Y1501750D01*
X250742Y1501833D01*
X250367D01*
G01X250742D02*
X250992Y1501958D01*
X251200Y1502167D01*
X251283Y1502417D01*
X251200Y1502667D01*
X250992Y1502875D01*
X250617Y1503000D01*
X250242Y1502958D01*
X249867Y1502792D01*
G01X253467Y1500500D02*
X253550Y1501042D01*
X253675Y1501500D01*
X253842Y1501917D01*
X254050Y1502375D01*
X254383Y1503000D01*
X252717D01*
G01X256650Y1500500D02*
X256942Y1500542D01*
X257275Y1500667D01*
X257483Y1500875D01*
X257567Y1501167D01*
X257483Y1501458D01*
X257233Y1501708D01*
X256858Y1501833D01*
X256442D01*
X256192Y1501917D01*
X255983Y1502125D01*
X255900Y1502417D01*
X256025Y1502708D01*
X256317Y1502917D01*
X256650Y1503000D01*
X256983Y1502917D01*
X257275Y1502708D01*
X257400Y1502417D01*
X257317Y1502125D01*
X257108Y1501917D01*
X256858Y1501833D01*
X256442D01*
X256067Y1501708D01*
X255817Y1501458D01*
X255733Y1501167D01*
X255817Y1500875D01*
X256025Y1500667D01*
X256358Y1500542D01*
X256650Y1500500D01*
G01X250017Y1506500D02*
Y1509000D01*
X251058D01*
X251392Y1508875D01*
X251600Y1508708D01*
X251683Y1508375D01*
X251600Y1508042D01*
X251350Y1507833D01*
X251058Y1507708D01*
X250017D01*
G01X251058D02*
X251683Y1506500D01*
G01X253033Y1506875D02*
X253283Y1506667D01*
X253575Y1506542D01*
X253950Y1506500D01*
X254325Y1506583D01*
X254617Y1506750D01*
X254825Y1507042D01*
X254867Y1507375D01*
X254783Y1507708D01*
X254575Y1507917D01*
X254283Y1508083D01*
X253992Y1508125D01*
X253700Y1508083D01*
X253325Y1507917D01*
X253450Y1509000D01*
X254575D01*
G01X256258Y1508583D02*
X256508Y1508833D01*
X256800Y1508958D01*
X257133Y1509000D01*
X257550Y1508917D01*
X257842Y1508708D01*
X257925Y1508458D01*
X257883Y1508208D01*
X257717Y1508000D01*
X256883Y1507583D01*
X256508Y1507292D01*
X256258Y1506875D01*
X256175Y1506500D01*
X257925D01*
G01X260650D02*
Y1509000D01*
X259108Y1507208D01*
X261192D01*
G01X241300Y1519900D02*
X248300D01*
Y1506500D01*
X241300D01*
Y1519900D01*
G01X242499Y1532250D02*
Y1537750D01*
G01X250499Y1532250D02*
X242499D01*
G01X250499Y1537750D02*
Y1532250D01*
G01X232107Y1533550D02*
Y1536050D01*
X233691D01*
G01X233107Y1534842D02*
X232107D01*
G01X235999Y1533550D02*
Y1536050D01*
X235499Y1535550D01*
G01Y1533550D02*
X236499D01*
G01X238182Y1534050D02*
X238432Y1533758D01*
X238766Y1533592D01*
X239141Y1533550D01*
X239474Y1533592D01*
X239807Y1533800D01*
X240016Y1534050D01*
X240057Y1534300D01*
X239974Y1534592D01*
X239682Y1534800D01*
X239391Y1534883D01*
X239016D01*
G01X239391D02*
X239641Y1535008D01*
X239849Y1535217D01*
X239932Y1535467D01*
X239849Y1535717D01*
X239641Y1535925D01*
X239266Y1536050D01*
X238891Y1536008D01*
X238516Y1535842D01*
G01X230649Y1530800D02*
Y1521300D01*
X248349D01*
Y1530800D01*
X230649D01*
G01X241499Y1539550D02*
Y1552550D01*
G01X251499Y1543650D02*
Y1582450D01*
G01X274499Y1543650D02*
X251499D01*
G01X250499Y1549850D02*
Y1544350D01*
G01X242499Y1549850D02*
X250499D01*
G01X242499Y1544350D02*
Y1549850D01*
G01X233700Y1553800D02*
Y1559300D01*
G01X241700Y1553800D02*
X233700D01*
G01X241700Y1559300D02*
Y1553800D01*
G01X233000Y1559300D02*
Y1553800D01*
G01X250400D02*
Y1571400D01*
G01X242400Y1553800D02*
X250400D01*
G01X242400Y1571400D02*
Y1553800D01*
G01X236408Y1575267D02*
X236283Y1575017D01*
X236200Y1574725D01*
Y1574392D01*
X236325Y1574017D01*
X236533Y1573725D01*
X236783Y1573517D01*
X237200Y1573350D01*
X237575Y1573308D01*
X237950Y1573392D01*
X238200Y1573517D01*
X238450Y1573767D01*
X238617Y1574058D01*
X238700Y1574350D01*
Y1574642D01*
X238617Y1574933D01*
X238492Y1575183D01*
X238325Y1575392D01*
G01X236617Y1576658D02*
X236367Y1576908D01*
X236242Y1577200D01*
X236200Y1577533D01*
X236283Y1577950D01*
X236492Y1578242D01*
X236742Y1578325D01*
X236992Y1578283D01*
X237200Y1578117D01*
X237617Y1577283D01*
X237908Y1576908D01*
X238325Y1576658D01*
X238700Y1576575D01*
Y1578325D01*
G01X236200Y1580550D02*
X236283Y1580217D01*
X236492Y1579967D01*
X236742Y1579800D01*
X237075Y1579675D01*
X237450Y1579633D01*
X237825Y1579675D01*
X238158Y1579800D01*
X238408Y1579967D01*
X238617Y1580217D01*
X238700Y1580550D01*
X238617Y1580883D01*
X238408Y1581133D01*
X238158Y1581300D01*
X237825Y1581425D01*
X237450Y1581467D01*
X237075Y1581425D01*
X236742Y1581300D01*
X236492Y1581133D01*
X236283Y1580883D01*
X236200Y1580550D01*
G01X238700Y1583650D02*
X238658Y1583942D01*
X238533Y1584275D01*
X238325Y1584483D01*
X238033Y1584567D01*
X237742Y1584483D01*
X237492Y1584233D01*
X237367Y1583858D01*
Y1583442D01*
X237283Y1583192D01*
X237075Y1582983D01*
X236783Y1582900D01*
X236492Y1583025D01*
X236283Y1583317D01*
X236200Y1583650D01*
X236283Y1583983D01*
X236492Y1584275D01*
X236783Y1584400D01*
X237075Y1584317D01*
X237283Y1584108D01*
X237367Y1583858D01*
Y1583442D01*
X237492Y1583067D01*
X237742Y1582817D01*
X238033Y1582733D01*
X238325Y1582817D01*
X238533Y1583025D01*
X238658Y1583358D01*
X238700Y1583650D01*
G01X241700Y1571400D02*
Y1565900D01*
G01X233700Y1571400D02*
X241700D01*
G01X233700Y1565900D02*
Y1571400D01*
G01X233000D02*
Y1565900D01*
G01X247500Y1573017D02*
X245000D01*
Y1574058D01*
X245125Y1574392D01*
X245292Y1574600D01*
X245625Y1574683D01*
X245958Y1574600D01*
X246167Y1574350D01*
X246292Y1574058D01*
Y1573017D01*
G01Y1574058D02*
X247500Y1574683D01*
G01X247125Y1576033D02*
X247333Y1576283D01*
X247458Y1576575D01*
X247500Y1576950D01*
X247417Y1577325D01*
X247250Y1577617D01*
X246958Y1577825D01*
X246625Y1577867D01*
X246292Y1577783D01*
X246083Y1577575D01*
X245917Y1577283D01*
X245875Y1576992D01*
X245917Y1576700D01*
X246083Y1576325D01*
X245000Y1576450D01*
Y1577575D01*
G01X245417Y1579258D02*
X245167Y1579508D01*
X245042Y1579800D01*
X245000Y1580133D01*
X245083Y1580550D01*
X245292Y1580842D01*
X245542Y1580925D01*
X245792Y1580883D01*
X246000Y1580717D01*
X246417Y1579883D01*
X246708Y1579508D01*
X247125Y1579258D01*
X247500Y1579175D01*
Y1580925D01*
G01X247125Y1582233D02*
X247333Y1582483D01*
X247458Y1582775D01*
X247500Y1583150D01*
X247417Y1583525D01*
X247250Y1583817D01*
X246958Y1584025D01*
X246625Y1584067D01*
X246292Y1583983D01*
X246083Y1583775D01*
X245917Y1583483D01*
X245875Y1583192D01*
X245917Y1582900D01*
X246083Y1582525D01*
X245000Y1582650D01*
Y1583775D01*
G01X250400Y1571400D02*
X242400D01*
G01X251499Y1582450D02*
X274499D01*
G01X234000Y1864067D02*
X231500D01*
Y1865108D01*
X231625Y1865442D01*
X231792Y1865650D01*
X232125Y1865733D01*
X232458Y1865650D01*
X232667Y1865400D01*
X232792Y1865108D01*
Y1864067D01*
G01Y1865108D02*
X234000Y1865733D01*
G01X233500Y1867083D02*
X233792Y1867333D01*
X233958Y1867667D01*
X234000Y1868042D01*
X233958Y1868375D01*
X233750Y1868708D01*
X233500Y1868917D01*
X233250Y1868958D01*
X232958Y1868875D01*
X232750Y1868583D01*
X232667Y1868292D01*
Y1867917D01*
G01Y1868292D02*
X232542Y1868542D01*
X232333Y1868750D01*
X232083Y1868833D01*
X231833Y1868750D01*
X231625Y1868542D01*
X231500Y1868167D01*
X231542Y1867792D01*
X231708Y1867417D01*
G01X234000Y1871017D02*
X233458Y1871100D01*
X233000Y1871225D01*
X232583Y1871392D01*
X232125Y1871600D01*
X231500Y1871933D01*
Y1870267D01*
G01X233625Y1873283D02*
X233833Y1873533D01*
X233958Y1873825D01*
X234000Y1874200D01*
X233917Y1874575D01*
X233750Y1874867D01*
X233458Y1875075D01*
X233125Y1875117D01*
X232792Y1875033D01*
X232583Y1874825D01*
X232417Y1874533D01*
X232375Y1874242D01*
X232417Y1873950D01*
X232583Y1873575D01*
X231500Y1873700D01*
Y1874825D01*
G01X238900Y1869500D02*
X238567Y1869542D01*
X238275Y1869708D01*
X238025Y1869958D01*
X237858Y1870250D01*
X237775Y1870583D01*
Y1870917D01*
X237858Y1871250D01*
X238025Y1871542D01*
X238275Y1871792D01*
X238567Y1871958D01*
X238900Y1872000D01*
X239233Y1871958D01*
X239525Y1871792D01*
X239775Y1871542D01*
X239942Y1871250D01*
X240025Y1870917D01*
Y1870583D01*
X239942Y1870250D01*
X239775Y1869958D01*
X239525Y1869708D01*
X239233Y1869542D01*
X238900Y1869500D01*
G01X239233Y1870167D02*
X239733Y1869500D01*
G01X241083Y1869875D02*
X241333Y1869667D01*
X241625Y1869542D01*
X242000Y1869500D01*
X242375Y1869583D01*
X242667Y1869750D01*
X242875Y1870042D01*
X242917Y1870375D01*
X242833Y1870708D01*
X242625Y1870917D01*
X242333Y1871083D01*
X242042Y1871125D01*
X241750Y1871083D01*
X241375Y1870917D01*
X241500Y1872000D01*
X242625D01*
G01X245017Y1869500D02*
X245100Y1870042D01*
X245225Y1870500D01*
X245392Y1870917D01*
X245600Y1871375D01*
X245933Y1872000D01*
X244267D01*
G01X238100Y1899300D02*
X234100D01*
Y1891900D01*
G01X246600Y1877200D02*
Y1891200D01*
G01X233600Y1877200D02*
X246600D01*
G01X233600Y1891200D02*
Y1877200D01*
G01X246600Y1891200D02*
X233600D01*
G01X251000Y1886017D02*
X248500D01*
Y1887058D01*
X248625Y1887392D01*
X248792Y1887600D01*
X249125Y1887683D01*
X249458Y1887600D01*
X249667Y1887350D01*
X249792Y1887058D01*
Y1886017D01*
G01Y1887058D02*
X251000Y1887683D01*
G01X250625Y1889033D02*
X250833Y1889283D01*
X250958Y1889575D01*
X251000Y1889950D01*
X250917Y1890325D01*
X250750Y1890617D01*
X250458Y1890825D01*
X250125Y1890867D01*
X249792Y1890783D01*
X249583Y1890575D01*
X249417Y1890283D01*
X249375Y1889992D01*
X249417Y1889700D01*
X249583Y1889325D01*
X248500Y1889450D01*
Y1890575D01*
G01X248917Y1892258D02*
X248667Y1892508D01*
X248542Y1892800D01*
X248500Y1893133D01*
X248583Y1893550D01*
X248792Y1893842D01*
X249042Y1893925D01*
X249292Y1893883D01*
X249500Y1893717D01*
X249917Y1892883D01*
X250208Y1892508D01*
X250625Y1892258D01*
X251000Y1892175D01*
Y1893925D01*
G01X248917Y1895358D02*
X248667Y1895608D01*
X248542Y1895900D01*
X248500Y1896233D01*
X248583Y1896650D01*
X248792Y1896942D01*
X249042Y1897025D01*
X249292Y1896983D01*
X249500Y1896817D01*
X249917Y1895983D01*
X250208Y1895608D01*
X250625Y1895358D01*
X251000Y1895275D01*
Y1897025D01*
G01X241934Y1900187D02*
Y1913187D01*
G01X243800Y1914900D02*
X250800D01*
Y1901500D01*
X243800D01*
Y1914900D01*
G01X242314Y1930813D02*
Y1936313D01*
G01X250314Y1930813D02*
X242314D01*
G01X250314Y1936313D02*
Y1930813D01*
G01X240000Y1927608D02*
X237500D01*
Y1929192D01*
G01X238708Y1928608D02*
Y1927608D01*
G01X240000Y1931500D02*
X237500D01*
X238000Y1931000D01*
G01X240000D02*
Y1932000D01*
G01Y1934600D02*
X237500D01*
X238000Y1934100D01*
G01X240000D02*
Y1935100D01*
G01X232574Y1925737D02*
Y1916237D01*
X250274D01*
Y1925737D01*
X232574D01*
G01X240434Y1936487D02*
Y1949487D01*
G01X251499Y1940150D02*
Y1978950D01*
G01X274499Y1940150D02*
X251499D01*
G01X250314Y1948413D02*
Y1942913D01*
G01X242314Y1948413D02*
X250314D01*
G01X242314Y1942913D02*
Y1948413D01*
G01X233000Y1955800D02*
Y1950300D01*
G01X233700D02*
Y1955800D01*
G01X241700Y1950300D02*
X233700D01*
G01X241700Y1955800D02*
Y1950300D01*
G01X250400D02*
Y1967900D01*
G01X242400Y1950300D02*
X250400D01*
G01X242400Y1967900D02*
Y1950300D01*
G01X233000Y1967900D02*
Y1962400D01*
G01X236908Y1971767D02*
X236783Y1971517D01*
X236700Y1971225D01*
Y1970892D01*
X236825Y1970517D01*
X237033Y1970225D01*
X237283Y1970017D01*
X237700Y1969850D01*
X238075Y1969808D01*
X238450Y1969892D01*
X238700Y1970017D01*
X238950Y1970267D01*
X239117Y1970558D01*
X239200Y1970850D01*
Y1971142D01*
X239117Y1971433D01*
X238992Y1971683D01*
X238825Y1971892D01*
G01X239200Y1973950D02*
X236700D01*
X237200Y1973450D01*
G01X239200D02*
Y1974450D01*
G01X238908Y1976342D02*
X239117Y1976633D01*
X239200Y1976967D01*
X239117Y1977300D01*
X238867Y1977592D01*
X238492Y1977800D01*
X238117Y1977883D01*
X237658D01*
X237283Y1977800D01*
X236950Y1977592D01*
X236783Y1977342D01*
X236700Y1977050D01*
X236783Y1976717D01*
X236950Y1976467D01*
X237200Y1976300D01*
X237533Y1976217D01*
X237825Y1976300D01*
X238117Y1976508D01*
X238283Y1976758D01*
X238325Y1977050D01*
X238242Y1977383D01*
X238033Y1977633D01*
X237658Y1977883D01*
G01X239200Y1980650D02*
X236700D01*
X238492Y1979108D01*
Y1981192D01*
G01X241700Y1967900D02*
Y1962400D01*
G01X233700Y1967900D02*
X241700D01*
G01X233700Y1962400D02*
Y1967900D01*
G01X247000Y1970517D02*
X244500D01*
Y1971558D01*
X244625Y1971892D01*
X244792Y1972100D01*
X245125Y1972183D01*
X245458Y1972100D01*
X245667Y1971850D01*
X245792Y1971558D01*
Y1970517D01*
G01Y1971558D02*
X247000Y1972183D01*
G01X246625Y1973533D02*
X246833Y1973783D01*
X246958Y1974075D01*
X247000Y1974450D01*
X246917Y1974825D01*
X246750Y1975117D01*
X246458Y1975325D01*
X246125Y1975367D01*
X245792Y1975283D01*
X245583Y1975075D01*
X245417Y1974783D01*
X245375Y1974492D01*
X245417Y1974200D01*
X245583Y1973825D01*
X244500Y1973950D01*
Y1975075D01*
G01X244917Y1976758D02*
X244667Y1977008D01*
X244542Y1977300D01*
X244500Y1977633D01*
X244583Y1978050D01*
X244792Y1978342D01*
X245042Y1978425D01*
X245292Y1978383D01*
X245500Y1978217D01*
X245917Y1977383D01*
X246208Y1977008D01*
X246625Y1976758D01*
X247000Y1976675D01*
Y1978425D01*
G01X246500Y1979733D02*
X246792Y1979983D01*
X246958Y1980317D01*
X247000Y1980692D01*
X246958Y1981025D01*
X246750Y1981358D01*
X246500Y1981567D01*
X246250Y1981608D01*
X245958Y1981525D01*
X245750Y1981233D01*
X245667Y1980942D01*
Y1980567D01*
G01Y1980942D02*
X245542Y1981192D01*
X245333Y1981400D01*
X245083Y1981483D01*
X244833Y1981400D01*
X244625Y1981192D01*
X244500Y1980817D01*
X244542Y1980442D01*
X244708Y1980067D01*
G01X250400Y1967900D02*
X242400D01*
G01X251499Y1978950D02*
X274499D01*
G01X272208Y94267D02*
X272083Y94017D01*
X272000Y93725D01*
Y93392D01*
X272125Y93017D01*
X272333Y92725D01*
X272583Y92517D01*
X273000Y92350D01*
X273375Y92308D01*
X273750Y92392D01*
X274000Y92517D01*
X274250Y92767D01*
X274417Y93058D01*
X274500Y93350D01*
Y93642D01*
X274417Y93933D01*
X274292Y94183D01*
X274125Y94392D01*
G01X274000Y95533D02*
X274292Y95783D01*
X274458Y96117D01*
X274500Y96492D01*
X274458Y96825D01*
X274250Y97158D01*
X274000Y97367D01*
X273750Y97408D01*
X273458Y97325D01*
X273250Y97033D01*
X273167Y96742D01*
Y96367D01*
G01Y96742D02*
X273042Y96992D01*
X272833Y97200D01*
X272583Y97283D01*
X272333Y97200D01*
X272125Y96992D01*
X272000Y96617D01*
X272042Y96242D01*
X272208Y95867D01*
G01X274000Y98633D02*
X274292Y98883D01*
X274458Y99217D01*
X274500Y99592D01*
X274458Y99925D01*
X274250Y100258D01*
X274000Y100467D01*
X273750Y100508D01*
X273458Y100425D01*
X273250Y100133D01*
X273167Y99842D01*
Y99467D01*
G01Y99842D02*
X273042Y100092D01*
X272833Y100300D01*
X272583Y100383D01*
X272333Y100300D01*
X272125Y100092D01*
X272000Y99717D01*
X272042Y99342D01*
X272208Y98967D01*
G01X272417Y101858D02*
X272167Y102108D01*
X272042Y102400D01*
X272000Y102733D01*
X272083Y103150D01*
X272292Y103442D01*
X272542Y103525D01*
X272792Y103483D01*
X273000Y103317D01*
X273417Y102483D01*
X273708Y102108D01*
X274125Y101858D01*
X274500Y101775D01*
Y103525D01*
G01X255500Y279017D02*
X253000D01*
Y280058D01*
X253125Y280392D01*
X253292Y280600D01*
X253625Y280683D01*
X253958Y280600D01*
X254167Y280350D01*
X254292Y280058D01*
Y279017D01*
G01Y280058D02*
X255500Y280683D01*
G01X255125Y282033D02*
X255333Y282283D01*
X255458Y282575D01*
X255500Y282950D01*
X255417Y283325D01*
X255250Y283617D01*
X254958Y283825D01*
X254625Y283867D01*
X254292Y283783D01*
X254083Y283575D01*
X253917Y283283D01*
X253875Y282992D01*
X253917Y282700D01*
X254083Y282325D01*
X253000Y282450D01*
Y283575D01*
G01X255000Y285133D02*
X255292Y285383D01*
X255458Y285717D01*
X255500Y286092D01*
X255458Y286425D01*
X255250Y286758D01*
X255000Y286967D01*
X254750Y287008D01*
X254458Y286925D01*
X254250Y286633D01*
X254167Y286342D01*
Y285967D01*
G01Y286342D02*
X254042Y286592D01*
X253833Y286800D01*
X253583Y286883D01*
X253333Y286800D01*
X253125Y286592D01*
X253000Y286217D01*
X253042Y285842D01*
X253208Y285467D01*
G01X253000Y289150D02*
X253083Y288817D01*
X253292Y288567D01*
X253542Y288400D01*
X253875Y288275D01*
X254250Y288233D01*
X254625Y288275D01*
X254958Y288400D01*
X255208Y288567D01*
X255417Y288817D01*
X255500Y289150D01*
X255417Y289483D01*
X255208Y289733D01*
X254958Y289900D01*
X254625Y290025D01*
X254250Y290067D01*
X253875Y290025D01*
X253542Y289900D01*
X253292Y289733D01*
X253083Y289483D01*
X253000Y289150D01*
G01X258398Y313414D02*
Y294214D01*
X269598D01*
Y313414D01*
X258398D01*
Y313014D01*
G01X269400Y315500D02*
X269067Y315542D01*
X268775Y315708D01*
X268525Y315958D01*
X268358Y316250D01*
X268275Y316583D01*
Y316917D01*
X268358Y317250D01*
X268525Y317542D01*
X268775Y317792D01*
X269067Y317958D01*
X269400Y318000D01*
X269733Y317958D01*
X270025Y317792D01*
X270275Y317542D01*
X270442Y317250D01*
X270525Y316917D01*
Y316583D01*
X270442Y316250D01*
X270275Y315958D01*
X270025Y315708D01*
X269733Y315542D01*
X269400Y315500D01*
G01X269733Y316167D02*
X270233Y315500D01*
G01X272500D02*
Y318000D01*
X272000Y317500D01*
G01Y315500D02*
X273000D01*
G01X274892Y315792D02*
X275183Y315583D01*
X275517Y315500D01*
X275850Y315583D01*
X276142Y315833D01*
X276350Y316208D01*
X276433Y316583D01*
Y317042D01*
X276350Y317417D01*
X276142Y317750D01*
X275892Y317917D01*
X275600Y318000D01*
X275267Y317917D01*
X275017Y317750D01*
X274850Y317500D01*
X274767Y317167D01*
X274850Y316875D01*
X275058Y316583D01*
X275308Y316417D01*
X275600Y316375D01*
X275933Y316458D01*
X276183Y316667D01*
X276433Y317042D01*
G01X265998Y313314D02*
X264198Y311214D01*
X261998Y313314D01*
G01X253767Y321792D02*
X253517Y321917D01*
X253225Y322000D01*
X252892D01*
X252517Y321875D01*
X252225Y321667D01*
X252017Y321417D01*
X251850Y321000D01*
X251808Y320625D01*
X251892Y320250D01*
X252017Y320000D01*
X252267Y319750D01*
X252558Y319583D01*
X252850Y319500D01*
X253142D01*
X253433Y319583D01*
X253683Y319708D01*
X253892Y319875D01*
G01X255158Y321583D02*
X255408Y321833D01*
X255700Y321958D01*
X256033Y322000D01*
X256450Y321917D01*
X256742Y321708D01*
X256825Y321458D01*
X256783Y321208D01*
X256617Y321000D01*
X255783Y320583D01*
X255408Y320292D01*
X255158Y319875D01*
X255075Y319500D01*
X256825D01*
G01X258133Y319875D02*
X258383Y319667D01*
X258675Y319542D01*
X259050Y319500D01*
X259425Y319583D01*
X259717Y319750D01*
X259925Y320042D01*
X259967Y320375D01*
X259883Y320708D01*
X259675Y320917D01*
X259383Y321083D01*
X259092Y321125D01*
X258800Y321083D01*
X258425Y320917D01*
X258550Y322000D01*
X259675D01*
G01X261233Y319875D02*
X261483Y319667D01*
X261775Y319542D01*
X262150Y319500D01*
X262525Y319583D01*
X262817Y319750D01*
X263025Y320042D01*
X263067Y320375D01*
X262983Y320708D01*
X262775Y320917D01*
X262483Y321083D01*
X262192Y321125D01*
X261900Y321083D01*
X261525Y320917D01*
X261650Y322000D01*
X262775D01*
G01X258607Y369050D02*
Y371550D01*
X260191D01*
G01X259607Y370342D02*
X258607D01*
G01X261707Y371133D02*
X261957Y371383D01*
X262249Y371508D01*
X262582Y371550D01*
X262999Y371467D01*
X263291Y371258D01*
X263374Y371008D01*
X263332Y370758D01*
X263166Y370550D01*
X262332Y370133D01*
X261957Y369842D01*
X261707Y369425D01*
X261624Y369050D01*
X263374D01*
G01X265599Y371550D02*
X265266Y371467D01*
X265016Y371258D01*
X264849Y371008D01*
X264724Y370675D01*
X264682Y370300D01*
X264724Y369925D01*
X264849Y369592D01*
X265016Y369342D01*
X265266Y369133D01*
X265599Y369050D01*
X265932Y369133D01*
X266182Y369342D01*
X266349Y369592D01*
X266474Y369925D01*
X266516Y370300D01*
X266474Y370675D01*
X266349Y371008D01*
X266182Y371258D01*
X265932Y371467D01*
X265599Y371550D01*
G01X252900Y691000D02*
X252567Y691042D01*
X252275Y691208D01*
X252025Y691458D01*
X251858Y691750D01*
X251775Y692083D01*
Y692417D01*
X251858Y692750D01*
X252025Y693042D01*
X252275Y693292D01*
X252567Y693458D01*
X252900Y693500D01*
X253233Y693458D01*
X253525Y693292D01*
X253775Y693042D01*
X253942Y692750D01*
X254025Y692417D01*
Y692083D01*
X253942Y691750D01*
X253775Y691458D01*
X253525Y691208D01*
X253233Y691042D01*
X252900Y691000D01*
G01X253233Y691667D02*
X253733Y691000D01*
G01X255208Y692042D02*
X255500Y692333D01*
X255750Y692500D01*
X256083Y692583D01*
X256375Y692500D01*
X256583Y692333D01*
X256750Y692083D01*
X256792Y691792D01*
X256750Y691542D01*
X256583Y691292D01*
X256333Y691083D01*
X256042Y691000D01*
X255708Y691083D01*
X255417Y691333D01*
X255250Y691708D01*
X255208Y692125D01*
X255292Y692667D01*
X255417Y692958D01*
X255625Y693250D01*
X255917Y693458D01*
X256208Y693500D01*
X256500Y693417D01*
X256708Y693208D01*
G01X258308Y693083D02*
X258558Y693333D01*
X258850Y693458D01*
X259183Y693500D01*
X259600Y693417D01*
X259892Y693208D01*
X259975Y692958D01*
X259933Y692708D01*
X259767Y692500D01*
X258933Y692083D01*
X258558Y691792D01*
X258308Y691375D01*
X258225Y691000D01*
X259975D01*
G01X258899Y719850D02*
Y700650D01*
X270099D01*
Y719850D01*
X258899D01*
Y719450D01*
G01X252017Y695500D02*
Y698000D01*
X253058D01*
X253392Y697875D01*
X253600Y697708D01*
X253683Y697375D01*
X253600Y697042D01*
X253350Y696833D01*
X253058Y696708D01*
X252017D01*
G01X253058D02*
X253683Y695500D01*
G01X255033Y695875D02*
X255283Y695667D01*
X255575Y695542D01*
X255950Y695500D01*
X256325Y695583D01*
X256617Y695750D01*
X256825Y696042D01*
X256867Y696375D01*
X256783Y696708D01*
X256575Y696917D01*
X256283Y697083D01*
X255992Y697125D01*
X255700Y697083D01*
X255325Y696917D01*
X255450Y698000D01*
X256575D01*
G01X258258Y697583D02*
X258508Y697833D01*
X258800Y697958D01*
X259133Y698000D01*
X259550Y697917D01*
X259842Y697708D01*
X259925Y697458D01*
X259883Y697208D01*
X259717Y697000D01*
X258883Y696583D01*
X258508Y696292D01*
X258258Y695875D01*
X258175Y695500D01*
X259925D01*
G01X262150D02*
X262442Y695542D01*
X262775Y695667D01*
X262983Y695875D01*
X263067Y696167D01*
X262983Y696458D01*
X262733Y696708D01*
X262358Y696833D01*
X261942D01*
X261692Y696917D01*
X261483Y697125D01*
X261400Y697417D01*
X261525Y697708D01*
X261817Y697917D01*
X262150Y698000D01*
X262483Y697917D01*
X262775Y697708D01*
X262900Y697417D01*
X262817Y697125D01*
X262608Y696917D01*
X262358Y696833D01*
X261942D01*
X261567Y696708D01*
X261317Y696458D01*
X261233Y696167D01*
X261317Y695875D01*
X261525Y695667D01*
X261858Y695542D01*
X262150Y695500D01*
G01X263399Y722050D02*
X263066Y722092D01*
X262774Y722258D01*
X262524Y722508D01*
X262357Y722800D01*
X262274Y723133D01*
Y723467D01*
X262357Y723800D01*
X262524Y724092D01*
X262774Y724342D01*
X263066Y724508D01*
X263399Y724550D01*
X263732Y724508D01*
X264024Y724342D01*
X264274Y724092D01*
X264441Y723800D01*
X264524Y723467D01*
Y723133D01*
X264441Y722800D01*
X264274Y722508D01*
X264024Y722258D01*
X263732Y722092D01*
X263399Y722050D01*
G01X263732Y722717D02*
X264232Y722050D01*
G01X266499D02*
Y724550D01*
X265999Y724050D01*
G01Y722050D02*
X266999D01*
G01X269516D02*
X269599Y722592D01*
X269724Y723050D01*
X269891Y723467D01*
X270099Y723925D01*
X270432Y724550D01*
X268766D01*
G01X266499Y719750D02*
X264699Y717650D01*
X262499Y719750D01*
G01X254767Y729792D02*
X254517Y729917D01*
X254225Y730000D01*
X253892D01*
X253517Y729875D01*
X253225Y729667D01*
X253017Y729417D01*
X252850Y729000D01*
X252808Y728625D01*
X252892Y728250D01*
X253017Y728000D01*
X253267Y727750D01*
X253558Y727583D01*
X253850Y727500D01*
X254142D01*
X254433Y727583D01*
X254683Y727708D01*
X254892Y727875D01*
G01X256158Y729583D02*
X256408Y729833D01*
X256700Y729958D01*
X257033Y730000D01*
X257450Y729917D01*
X257742Y729708D01*
X257825Y729458D01*
X257783Y729208D01*
X257617Y729000D01*
X256783Y728583D01*
X256408Y728292D01*
X256158Y727875D01*
X256075Y727500D01*
X257825D01*
G01X259133Y728000D02*
X259383Y727708D01*
X259717Y727542D01*
X260092Y727500D01*
X260425Y727542D01*
X260758Y727750D01*
X260967Y728000D01*
X261008Y728250D01*
X260925Y728542D01*
X260633Y728750D01*
X260342Y728833D01*
X259967D01*
G01X260342D02*
X260592Y728958D01*
X260800Y729167D01*
X260883Y729417D01*
X260800Y729667D01*
X260592Y729875D01*
X260217Y730000D01*
X259842Y729958D01*
X259467Y729792D01*
G01X262442Y727792D02*
X262733Y727583D01*
X263067Y727500D01*
X263400Y727583D01*
X263692Y727833D01*
X263900Y728208D01*
X263983Y728583D01*
Y729042D01*
X263900Y729417D01*
X263692Y729750D01*
X263442Y729917D01*
X263150Y730000D01*
X262817Y729917D01*
X262567Y729750D01*
X262400Y729500D01*
X262317Y729167D01*
X262400Y728875D01*
X262608Y728583D01*
X262858Y728417D01*
X263150Y728375D01*
X263483Y728458D01*
X263733Y728667D01*
X263983Y729042D01*
G01X252499Y732650D02*
Y771450D01*
G01X275499Y732650D02*
X252499D01*
G01Y771450D02*
X275499D01*
G01X260608Y773500D02*
Y776000D01*
X262192D01*
G01X261608Y774792D02*
X260608D01*
G01X264500Y773500D02*
Y776000D01*
X264000Y775500D01*
G01Y773500D02*
X265000D01*
G01X267600D02*
X267892Y773542D01*
X268225Y773667D01*
X268433Y773875D01*
X268517Y774167D01*
X268433Y774458D01*
X268183Y774708D01*
X267808Y774833D01*
X267392D01*
X267142Y774917D01*
X266933Y775125D01*
X266850Y775417D01*
X266975Y775708D01*
X267267Y775917D01*
X267600Y776000D01*
X267933Y775917D01*
X268225Y775708D01*
X268350Y775417D01*
X268267Y775125D01*
X268058Y774917D01*
X267808Y774833D01*
X267392D01*
X267017Y774708D01*
X266767Y774458D01*
X266683Y774167D01*
X266767Y773875D01*
X266975Y773667D01*
X267308Y773542D01*
X267600Y773500D01*
G01X255916Y873050D02*
Y878050D01*
X259082D01*
G01X257916Y875633D02*
X255916D01*
G01X261516Y877217D02*
X262016Y877717D01*
X262599Y877967D01*
X263266Y878050D01*
X264099Y877883D01*
X264682Y877467D01*
X264849Y876967D01*
X264766Y876467D01*
X264432Y876050D01*
X262766Y875217D01*
X262016Y874633D01*
X261516Y873800D01*
X261349Y873050D01*
X264849D01*
G01X267116Y875133D02*
X267699Y875717D01*
X268199Y876050D01*
X268866Y876217D01*
X269449Y876050D01*
X269866Y875717D01*
X270199Y875217D01*
X270282Y874633D01*
X270199Y874133D01*
X269866Y873633D01*
X269366Y873217D01*
X268782Y873050D01*
X268116Y873217D01*
X267532Y873717D01*
X267199Y874467D01*
X267116Y875300D01*
X267282Y876383D01*
X267532Y876967D01*
X267949Y877550D01*
X268532Y877967D01*
X269116Y878050D01*
X269699Y877883D01*
X270116Y877467D01*
G01X274299Y872883D02*
X274132Y872967D01*
Y873133D01*
X274299Y873217D01*
X274466Y873133D01*
Y872967D01*
X274299Y872883D01*
G01Y875133D02*
X274132Y875217D01*
Y875383D01*
X274299Y875467D01*
X274466Y875383D01*
Y875217D01*
X274299Y875133D01*
G01X278066Y874050D02*
X278566Y873467D01*
X279232Y873133D01*
X279982Y873050D01*
X280649Y873133D01*
X281316Y873550D01*
X281732Y874050D01*
X281816Y874550D01*
X281649Y875133D01*
X281066Y875550D01*
X280482Y875717D01*
X279732D01*
G01X280482D02*
X280982Y875967D01*
X281399Y876383D01*
X281566Y876883D01*
X281399Y877383D01*
X280982Y877800D01*
X280232Y878050D01*
X279482Y877967D01*
X278732Y877633D01*
G01X283416Y873050D02*
X285499Y878050D01*
X287582Y873050D01*
G01X286832Y874800D02*
X284166D01*
G01X289599Y872883D02*
X292599Y878050D01*
G01X296699Y873050D02*
Y878050D01*
X295699Y877050D01*
G01Y873050D02*
X297699D01*
G01X300466Y873800D02*
X300966Y873383D01*
X301549Y873133D01*
X302299Y873050D01*
X303049Y873217D01*
X303632Y873550D01*
X304049Y874133D01*
X304132Y874800D01*
X303966Y875467D01*
X303549Y875883D01*
X302966Y876217D01*
X302382Y876300D01*
X301799Y876217D01*
X301049Y875883D01*
X301299Y878050D01*
X303549D01*
G01X305816D02*
X307899Y873050D01*
X309982Y878050D01*
G01X255916Y882550D02*
Y887550D01*
X259082D01*
G01X257916Y885133D02*
X255916D01*
G01X261516Y886717D02*
X262016Y887217D01*
X262599Y887467D01*
X263266Y887550D01*
X264099Y887383D01*
X264682Y886967D01*
X264849Y886467D01*
X264766Y885967D01*
X264432Y885550D01*
X262766Y884717D01*
X262016Y884133D01*
X261516Y883300D01*
X261349Y882550D01*
X264849D01*
G01X266866Y883300D02*
X267366Y882883D01*
X267949Y882633D01*
X268699Y882550D01*
X269449Y882717D01*
X270032Y883050D01*
X270449Y883633D01*
X270532Y884300D01*
X270366Y884967D01*
X269949Y885383D01*
X269366Y885717D01*
X268782Y885800D01*
X268199Y885717D01*
X267449Y885383D01*
X267699Y887550D01*
X269949D01*
G01X274299Y882383D02*
X274132Y882467D01*
Y882633D01*
X274299Y882717D01*
X274466Y882633D01*
Y882467D01*
X274299Y882383D01*
G01Y884633D02*
X274132Y884717D01*
Y884883D01*
X274299Y884967D01*
X274466Y884883D01*
Y884717D01*
X274299Y884633D01*
G01X278316Y886717D02*
X278816Y887217D01*
X279399Y887467D01*
X280066Y887550D01*
X280899Y887383D01*
X281482Y886967D01*
X281649Y886467D01*
X281566Y885967D01*
X281232Y885550D01*
X279566Y884717D01*
X278816Y884133D01*
X278316Y883300D01*
X278149Y882550D01*
X281649D01*
G01X283416D02*
X285499Y887550D01*
X287582Y882550D01*
G01X286832Y884300D02*
X284166D01*
G01X289599Y882383D02*
X292599Y887550D01*
G01X295116Y884633D02*
X295699Y885217D01*
X296199Y885550D01*
X296866Y885717D01*
X297449Y885550D01*
X297866Y885217D01*
X298199Y884717D01*
X298282Y884133D01*
X298199Y883633D01*
X297866Y883133D01*
X297366Y882717D01*
X296782Y882550D01*
X296116Y882717D01*
X295532Y883217D01*
X295199Y883967D01*
X295116Y884800D01*
X295282Y885883D01*
X295532Y886467D01*
X295949Y887050D01*
X296532Y887467D01*
X297116Y887550D01*
X297699Y887383D01*
X298116Y886967D01*
G01X300216Y887550D02*
X302299Y882550D01*
X304382Y887550D01*
G01X269227Y1100727D02*
Y1103227D01*
G01X270977D02*
Y1100727D01*
G01Y1101977D02*
X269227D01*
G01X273202Y1100727D02*
X273494Y1100769D01*
X273827Y1100894D01*
X274035Y1101102D01*
X274119Y1101394D01*
X274035Y1101685D01*
X273785Y1101935D01*
X273410Y1102060D01*
X272994D01*
X272744Y1102144D01*
X272535Y1102352D01*
X272452Y1102644D01*
X272577Y1102935D01*
X272869Y1103144D01*
X273202Y1103227D01*
X273535Y1103144D01*
X273827Y1102935D01*
X273952Y1102644D01*
X273869Y1102352D01*
X273660Y1102144D01*
X273410Y1102060D01*
X272994D01*
X272619Y1101935D01*
X272369Y1101685D01*
X272285Y1101394D01*
X272369Y1101102D01*
X272577Y1100894D01*
X272910Y1100769D01*
X273202Y1100727D01*
G01X255708Y1118267D02*
X255583Y1118017D01*
X255500Y1117725D01*
Y1117392D01*
X255625Y1117017D01*
X255833Y1116725D01*
X256083Y1116517D01*
X256500Y1116350D01*
X256875Y1116308D01*
X257250Y1116392D01*
X257500Y1116517D01*
X257750Y1116767D01*
X257917Y1117058D01*
X258000Y1117350D01*
Y1117642D01*
X257917Y1117933D01*
X257792Y1118183D01*
X257625Y1118392D01*
G01X255917Y1119658D02*
X255667Y1119908D01*
X255542Y1120200D01*
X255500Y1120533D01*
X255583Y1120950D01*
X255792Y1121242D01*
X256042Y1121325D01*
X256292Y1121283D01*
X256500Y1121117D01*
X256917Y1120283D01*
X257208Y1119908D01*
X257625Y1119658D01*
X258000Y1119575D01*
Y1121325D01*
G01X255917Y1122758D02*
X255667Y1123008D01*
X255542Y1123300D01*
X255500Y1123633D01*
X255583Y1124050D01*
X255792Y1124342D01*
X256042Y1124425D01*
X256292Y1124383D01*
X256500Y1124217D01*
X256917Y1123383D01*
X257208Y1123008D01*
X257625Y1122758D01*
X258000Y1122675D01*
Y1124425D01*
G01X255500Y1126650D02*
X255583Y1126317D01*
X255792Y1126067D01*
X256042Y1125900D01*
X256375Y1125775D01*
X256750Y1125733D01*
X257125Y1125775D01*
X257458Y1125900D01*
X257708Y1126067D01*
X257917Y1126317D01*
X258000Y1126650D01*
X257917Y1126983D01*
X257708Y1127233D01*
X257458Y1127400D01*
X257125Y1127525D01*
X256750Y1127567D01*
X256375Y1127525D01*
X256042Y1127400D01*
X255792Y1127233D01*
X255583Y1126983D01*
X255500Y1126650D01*
G01X259708Y1118267D02*
X259583Y1118017D01*
X259500Y1117725D01*
Y1117392D01*
X259625Y1117017D01*
X259833Y1116725D01*
X260083Y1116517D01*
X260500Y1116350D01*
X260875Y1116308D01*
X261250Y1116392D01*
X261500Y1116517D01*
X261750Y1116767D01*
X261917Y1117058D01*
X262000Y1117350D01*
Y1117642D01*
X261917Y1117933D01*
X261792Y1118183D01*
X261625Y1118392D01*
G01X259917Y1119658D02*
X259667Y1119908D01*
X259542Y1120200D01*
X259500Y1120533D01*
X259583Y1120950D01*
X259792Y1121242D01*
X260042Y1121325D01*
X260292Y1121283D01*
X260500Y1121117D01*
X260917Y1120283D01*
X261208Y1119908D01*
X261625Y1119658D01*
X262000Y1119575D01*
Y1121325D01*
G01X259917Y1122758D02*
X259667Y1123008D01*
X259542Y1123300D01*
X259500Y1123633D01*
X259583Y1124050D01*
X259792Y1124342D01*
X260042Y1124425D01*
X260292Y1124383D01*
X260500Y1124217D01*
X260917Y1123383D01*
X261208Y1123008D01*
X261625Y1122758D01*
X262000Y1122675D01*
Y1124425D01*
G01Y1126650D02*
X259500D01*
X260000Y1126150D01*
G01X262000D02*
Y1127150D01*
G01X270000Y1116558D02*
X267500D01*
Y1118142D01*
G01X268708Y1117558D02*
Y1116558D01*
G01X270000Y1120450D02*
X267500D01*
X268000Y1119950D01*
G01X270000D02*
Y1120950D01*
G01X269625Y1122633D02*
X269833Y1122883D01*
X269958Y1123175D01*
X270000Y1123550D01*
X269917Y1123925D01*
X269750Y1124217D01*
X269458Y1124425D01*
X269125Y1124467D01*
X268792Y1124383D01*
X268583Y1124175D01*
X268417Y1123883D01*
X268375Y1123592D01*
X268417Y1123300D01*
X268583Y1122925D01*
X267500Y1123050D01*
Y1124175D01*
G01X266000Y1116517D02*
X263500D01*
Y1117558D01*
X263625Y1117892D01*
X263792Y1118100D01*
X264125Y1118183D01*
X264458Y1118100D01*
X264667Y1117850D01*
X264792Y1117558D01*
Y1116517D01*
G01Y1117558D02*
X266000Y1118183D01*
G01X265625Y1119533D02*
X265833Y1119783D01*
X265958Y1120075D01*
X266000Y1120450D01*
X265917Y1120825D01*
X265750Y1121117D01*
X265458Y1121325D01*
X265125Y1121367D01*
X264792Y1121283D01*
X264583Y1121075D01*
X264417Y1120783D01*
X264375Y1120492D01*
X264417Y1120200D01*
X264583Y1119825D01*
X263500Y1119950D01*
Y1121075D01*
G01X263917Y1122758D02*
X263667Y1123008D01*
X263542Y1123300D01*
X263500Y1123633D01*
X263583Y1124050D01*
X263792Y1124342D01*
X264042Y1124425D01*
X264292Y1124383D01*
X264500Y1124217D01*
X264917Y1123383D01*
X265208Y1123008D01*
X265625Y1122758D01*
X266000Y1122675D01*
Y1124425D01*
G01X264958Y1125858D02*
X264667Y1126150D01*
X264500Y1126400D01*
X264417Y1126733D01*
X264500Y1127025D01*
X264667Y1127233D01*
X264917Y1127400D01*
X265208Y1127442D01*
X265458Y1127400D01*
X265708Y1127233D01*
X265917Y1126983D01*
X266000Y1126692D01*
X265917Y1126358D01*
X265667Y1126067D01*
X265292Y1125900D01*
X264875Y1125858D01*
X264333Y1125942D01*
X264042Y1126067D01*
X263750Y1126275D01*
X263542Y1126567D01*
X263500Y1126858D01*
X263583Y1127150D01*
X263792Y1127358D01*
G01X261416Y1134550D02*
Y1139550D01*
X264582D01*
G01X263416Y1137133D02*
X261416D01*
G01X268599Y1134550D02*
Y1139550D01*
X267599Y1138550D01*
G01Y1134550D02*
X269599D01*
G01X272366Y1135300D02*
X272866Y1134883D01*
X273449Y1134633D01*
X274199Y1134550D01*
X274949Y1134717D01*
X275532Y1135050D01*
X275949Y1135633D01*
X276032Y1136300D01*
X275866Y1136967D01*
X275449Y1137383D01*
X274866Y1137717D01*
X274282Y1137800D01*
X273699Y1137717D01*
X272949Y1137383D01*
X273199Y1139550D01*
X275449D01*
G01X279799Y1134383D02*
X279632Y1134467D01*
Y1134633D01*
X279799Y1134717D01*
X279966Y1134633D01*
Y1134467D01*
X279799Y1134383D01*
G01Y1136633D02*
X279632Y1136717D01*
Y1136883D01*
X279799Y1136967D01*
X279966Y1136883D01*
Y1136717D01*
X279799Y1136633D01*
G01X283816Y1138717D02*
X284316Y1139217D01*
X284899Y1139467D01*
X285566Y1139550D01*
X286399Y1139383D01*
X286982Y1138967D01*
X287149Y1138467D01*
X287066Y1137967D01*
X286732Y1137550D01*
X285066Y1136717D01*
X284316Y1136133D01*
X283816Y1135300D01*
X283649Y1134550D01*
X287149D01*
G01X288916D02*
X290999Y1139550D01*
X293082Y1134550D01*
G01X292332Y1136300D02*
X289666D01*
G01X295099Y1134383D02*
X298099Y1139550D01*
G01X300616Y1136633D02*
X301199Y1137217D01*
X301699Y1137550D01*
X302366Y1137717D01*
X302949Y1137550D01*
X303366Y1137217D01*
X303699Y1136717D01*
X303782Y1136133D01*
X303699Y1135633D01*
X303366Y1135133D01*
X302866Y1134717D01*
X302282Y1134550D01*
X301616Y1134717D01*
X301032Y1135217D01*
X300699Y1135967D01*
X300616Y1136800D01*
X300782Y1137883D01*
X301032Y1138467D01*
X301449Y1139050D01*
X302032Y1139467D01*
X302616Y1139550D01*
X303199Y1139383D01*
X303616Y1138967D01*
G01X305716Y1139550D02*
X307799Y1134550D01*
X309882Y1139550D01*
G01X255799Y1144550D02*
X255757Y1144217D01*
X255591Y1143925D01*
X255341Y1143675D01*
X255049Y1143508D01*
X254716Y1143425D01*
X254382D01*
X254049Y1143508D01*
X253757Y1143675D01*
X253507Y1143925D01*
X253341Y1144217D01*
X253299Y1144550D01*
X253341Y1144883D01*
X253507Y1145175D01*
X253757Y1145425D01*
X254049Y1145592D01*
X254382Y1145675D01*
X254716D01*
X255049Y1145592D01*
X255341Y1145425D01*
X255591Y1145175D01*
X255757Y1144883D01*
X255799Y1144550D01*
G01X255132Y1144883D02*
X255799Y1145383D01*
G01Y1147650D02*
X253299D01*
X253799Y1147150D01*
G01X255799D02*
Y1148150D01*
G01X255424Y1149833D02*
X255632Y1150083D01*
X255757Y1150375D01*
X255799Y1150750D01*
X255716Y1151125D01*
X255549Y1151417D01*
X255257Y1151625D01*
X254924Y1151667D01*
X254591Y1151583D01*
X254382Y1151375D01*
X254216Y1151083D01*
X254174Y1150792D01*
X254216Y1150500D01*
X254382Y1150125D01*
X253299Y1150250D01*
Y1151375D01*
G01X269267Y1535792D02*
X269017Y1535917D01*
X268725Y1536000D01*
X268392D01*
X268017Y1535875D01*
X267725Y1535667D01*
X267517Y1535417D01*
X267350Y1535000D01*
X267308Y1534625D01*
X267392Y1534250D01*
X267517Y1534000D01*
X267767Y1533750D01*
X268058Y1533583D01*
X268350Y1533500D01*
X268642D01*
X268933Y1533583D01*
X269183Y1533708D01*
X269392Y1533875D01*
G01X270658Y1535583D02*
X270908Y1535833D01*
X271200Y1535958D01*
X271533Y1536000D01*
X271950Y1535917D01*
X272242Y1535708D01*
X272325Y1535458D01*
X272283Y1535208D01*
X272117Y1535000D01*
X271283Y1534583D01*
X270908Y1534292D01*
X270658Y1533875D01*
X270575Y1533500D01*
X272325D01*
G01X274550D02*
Y1536000D01*
X274050Y1535500D01*
G01Y1533500D02*
X275050D01*
G01X277650D02*
Y1536000D01*
X277150Y1535500D01*
G01Y1533500D02*
X278150D01*
G01X264999Y1531250D02*
X263199Y1529150D01*
X260999Y1531250D01*
G01X257399Y1531350D02*
Y1512150D01*
X268599D01*
Y1531350D01*
X257399D01*
Y1530950D01*
G01X264767Y1539792D02*
X264517Y1539917D01*
X264225Y1540000D01*
X263892D01*
X263517Y1539875D01*
X263225Y1539667D01*
X263017Y1539417D01*
X262850Y1539000D01*
X262808Y1538625D01*
X262892Y1538250D01*
X263017Y1538000D01*
X263267Y1537750D01*
X263558Y1537583D01*
X263850Y1537500D01*
X264142D01*
X264433Y1537583D01*
X264683Y1537708D01*
X264892Y1537875D01*
G01X266158Y1539583D02*
X266408Y1539833D01*
X266700Y1539958D01*
X267033Y1540000D01*
X267450Y1539917D01*
X267742Y1539708D01*
X267825Y1539458D01*
X267783Y1539208D01*
X267617Y1539000D01*
X266783Y1538583D01*
X266408Y1538292D01*
X266158Y1537875D01*
X266075Y1537500D01*
X267825D01*
G01X270050Y1540000D02*
X269717Y1539917D01*
X269467Y1539708D01*
X269300Y1539458D01*
X269175Y1539125D01*
X269133Y1538750D01*
X269175Y1538375D01*
X269300Y1538042D01*
X269467Y1537792D01*
X269717Y1537583D01*
X270050Y1537500D01*
X270383Y1537583D01*
X270633Y1537792D01*
X270800Y1538042D01*
X270925Y1538375D01*
X270967Y1538750D01*
X270925Y1539125D01*
X270800Y1539458D01*
X270633Y1539708D01*
X270383Y1539917D01*
X270050Y1540000D01*
G01X273067Y1537500D02*
X273150Y1538042D01*
X273275Y1538500D01*
X273442Y1538917D01*
X273650Y1539375D01*
X273983Y1540000D01*
X272317D01*
G01X258607Y1586050D02*
Y1588550D01*
X260191D01*
G01X259607Y1587342D02*
X258607D01*
G01X262499Y1586050D02*
Y1588550D01*
X261999Y1588050D01*
G01Y1586050D02*
X262999D01*
G01X266099D02*
Y1588550D01*
X264557Y1586758D01*
X266641D01*
G01X255599Y1909417D02*
X255266Y1909459D01*
X254974Y1909625D01*
X254724Y1909875D01*
X254557Y1910167D01*
X254474Y1910500D01*
Y1910834D01*
X254557Y1911167D01*
X254724Y1911459D01*
X254974Y1911709D01*
X255266Y1911875D01*
X255599Y1911917D01*
X255932Y1911875D01*
X256224Y1911709D01*
X256474Y1911459D01*
X256641Y1911167D01*
X256724Y1910834D01*
Y1910500D01*
X256641Y1910167D01*
X256474Y1909875D01*
X256224Y1909625D01*
X255932Y1909459D01*
X255599Y1909417D01*
G01X255932Y1910084D02*
X256432Y1909417D01*
G01X258699D02*
Y1911917D01*
X258199Y1911417D01*
G01Y1909417D02*
X259199D01*
G01X261799D02*
Y1911917D01*
X261299Y1911417D01*
G01Y1909417D02*
X262299D01*
G01X267777Y1935391D02*
X265977Y1933291D01*
X263777Y1935391D01*
G01X260177Y1935491D02*
Y1916291D01*
X271377D01*
Y1935491D01*
X260177D01*
Y1935091D01*
G01X258607Y1981550D02*
Y1984050D01*
X260191D01*
G01X259607Y1982842D02*
X258607D01*
G01X262499Y1981550D02*
Y1984050D01*
X261999Y1983550D01*
G01Y1981550D02*
X262999D01*
G01X264807Y1983633D02*
X265057Y1983883D01*
X265349Y1984008D01*
X265682Y1984050D01*
X266099Y1983967D01*
X266391Y1983758D01*
X266474Y1983508D01*
X266432Y1983258D01*
X266266Y1983050D01*
X265432Y1982633D01*
X265057Y1982342D01*
X264807Y1981925D01*
X264724Y1981550D01*
X266474D01*
G01X282307Y21817D02*
X282182Y21567D01*
X282099Y21275D01*
Y20942D01*
X282224Y20567D01*
X282432Y20275D01*
X282682Y20067D01*
X283099Y19900D01*
X283474Y19858D01*
X283849Y19942D01*
X284099Y20067D01*
X284349Y20317D01*
X284516Y20608D01*
X284599Y20900D01*
Y21192D01*
X284516Y21483D01*
X284391Y21733D01*
X284224Y21942D01*
G01X284099Y23083D02*
X284391Y23333D01*
X284557Y23667D01*
X284599Y24042D01*
X284557Y24375D01*
X284349Y24708D01*
X284099Y24917D01*
X283849Y24958D01*
X283557Y24875D01*
X283349Y24583D01*
X283266Y24292D01*
Y23917D01*
G01Y24292D02*
X283141Y24542D01*
X282932Y24750D01*
X282682Y24833D01*
X282432Y24750D01*
X282224Y24542D01*
X282099Y24167D01*
X282141Y23792D01*
X282307Y23417D01*
G01X284099Y26183D02*
X284391Y26433D01*
X284557Y26767D01*
X284599Y27142D01*
X284557Y27475D01*
X284349Y27808D01*
X284099Y28017D01*
X283849Y28058D01*
X283557Y27975D01*
X283349Y27683D01*
X283266Y27392D01*
Y27017D01*
G01Y27392D02*
X283141Y27642D01*
X282932Y27850D01*
X282682Y27933D01*
X282432Y27850D01*
X282224Y27642D01*
X282099Y27267D01*
X282141Y26892D01*
X282307Y26517D01*
G01X284599Y30200D02*
X284557Y30492D01*
X284432Y30825D01*
X284224Y31033D01*
X283932Y31117D01*
X283641Y31033D01*
X283391Y30783D01*
X283266Y30408D01*
Y29992D01*
X283182Y29742D01*
X282974Y29533D01*
X282682Y29450D01*
X282391Y29575D01*
X282182Y29867D01*
X282099Y30200D01*
X282182Y30533D01*
X282391Y30825D01*
X282682Y30950D01*
X282974Y30867D01*
X283182Y30658D01*
X283266Y30408D01*
Y29992D01*
X283391Y29617D01*
X283641Y29367D01*
X283932Y29283D01*
X284224Y29367D01*
X284432Y29575D01*
X284557Y29908D01*
X284599Y30200D01*
G01X292099Y30913D02*
Y36413D01*
G01Y18813D02*
Y24313D01*
G01X300099Y18813D02*
X292099D01*
G01X279000Y41017D02*
X276500D01*
Y42058D01*
X276625Y42392D01*
X276792Y42600D01*
X277125Y42683D01*
X277458Y42600D01*
X277667Y42350D01*
X277792Y42058D01*
Y41017D01*
G01Y42058D02*
X279000Y42683D01*
G01X278500Y44033D02*
X278792Y44283D01*
X278958Y44617D01*
X279000Y44992D01*
X278958Y45325D01*
X278750Y45658D01*
X278500Y45867D01*
X278250Y45908D01*
X277958Y45825D01*
X277750Y45533D01*
X277667Y45242D01*
Y44867D01*
G01Y45242D02*
X277542Y45492D01*
X277333Y45700D01*
X277083Y45783D01*
X276833Y45700D01*
X276625Y45492D01*
X276500Y45117D01*
X276542Y44742D01*
X276708Y44367D01*
G01X276500Y48050D02*
X276583Y47717D01*
X276792Y47467D01*
X277042Y47300D01*
X277375Y47175D01*
X277750Y47133D01*
X278125Y47175D01*
X278458Y47300D01*
X278708Y47467D01*
X278917Y47717D01*
X279000Y48050D01*
X278917Y48383D01*
X278708Y48633D01*
X278458Y48800D01*
X278125Y48925D01*
X277750Y48967D01*
X277375Y48925D01*
X277042Y48800D01*
X276792Y48633D01*
X276583Y48383D01*
X276500Y48050D01*
G01X279000Y51650D02*
X276500D01*
X278292Y50108D01*
Y52192D01*
G01X291499Y37113D02*
X317499D01*
G01X291499Y50113D02*
Y37113D01*
G01X317499Y50113D02*
X291499D01*
G01X281208Y42767D02*
X281083Y42517D01*
X281000Y42225D01*
Y41892D01*
X281125Y41517D01*
X281333Y41225D01*
X281583Y41017D01*
X282000Y40850D01*
X282375Y40808D01*
X282750Y40892D01*
X283000Y41017D01*
X283250Y41267D01*
X283417Y41558D01*
X283500Y41850D01*
Y42142D01*
X283417Y42433D01*
X283292Y42683D01*
X283125Y42892D01*
G01X283000Y44033D02*
X283292Y44283D01*
X283458Y44617D01*
X283500Y44992D01*
X283458Y45325D01*
X283250Y45658D01*
X283000Y45867D01*
X282750Y45908D01*
X282458Y45825D01*
X282250Y45533D01*
X282167Y45242D01*
Y44867D01*
G01Y45242D02*
X282042Y45492D01*
X281833Y45700D01*
X281583Y45783D01*
X281333Y45700D01*
X281125Y45492D01*
X281000Y45117D01*
X281042Y44742D01*
X281208Y44367D01*
G01X283000Y47133D02*
X283292Y47383D01*
X283458Y47717D01*
X283500Y48092D01*
X283458Y48425D01*
X283250Y48758D01*
X283000Y48967D01*
X282750Y49008D01*
X282458Y48925D01*
X282250Y48633D01*
X282167Y48342D01*
Y47967D01*
G01Y48342D02*
X282042Y48592D01*
X281833Y48800D01*
X281583Y48883D01*
X281333Y48800D01*
X281125Y48592D01*
X281000Y48217D01*
X281042Y47842D01*
X281208Y47467D01*
G01X283000Y50233D02*
X283292Y50483D01*
X283458Y50817D01*
X283500Y51192D01*
X283458Y51525D01*
X283250Y51858D01*
X283000Y52067D01*
X282750Y52108D01*
X282458Y52025D01*
X282250Y51733D01*
X282167Y51442D01*
Y51067D01*
G01Y51442D02*
X282042Y51692D01*
X281833Y51900D01*
X281583Y51983D01*
X281333Y51900D01*
X281125Y51692D01*
X281000Y51317D01*
X281042Y50942D01*
X281208Y50567D01*
G01X292099Y36413D02*
X300099D01*
G01X283707Y56817D02*
X283582Y56567D01*
X283499Y56275D01*
Y55942D01*
X283624Y55567D01*
X283832Y55275D01*
X284082Y55067D01*
X284499Y54900D01*
X284874Y54858D01*
X285249Y54942D01*
X285499Y55067D01*
X285749Y55317D01*
X285916Y55608D01*
X285999Y55900D01*
Y56192D01*
X285916Y56483D01*
X285791Y56733D01*
X285624Y56942D01*
G01X285499Y58083D02*
X285791Y58333D01*
X285957Y58667D01*
X285999Y59042D01*
X285957Y59375D01*
X285749Y59708D01*
X285499Y59917D01*
X285249Y59958D01*
X284957Y59875D01*
X284749Y59583D01*
X284666Y59292D01*
Y58917D01*
G01Y59292D02*
X284541Y59542D01*
X284332Y59750D01*
X284082Y59833D01*
X283832Y59750D01*
X283624Y59542D01*
X283499Y59167D01*
X283541Y58792D01*
X283707Y58417D01*
G01X285499Y61183D02*
X285791Y61433D01*
X285957Y61767D01*
X285999Y62142D01*
X285957Y62475D01*
X285749Y62808D01*
X285499Y63017D01*
X285249Y63058D01*
X284957Y62975D01*
X284749Y62683D01*
X284666Y62392D01*
Y62017D01*
G01Y62392D02*
X284541Y62642D01*
X284332Y62850D01*
X284082Y62933D01*
X283832Y62850D01*
X283624Y62642D01*
X283499Y62267D01*
X283541Y61892D01*
X283707Y61517D01*
G01X283499Y65200D02*
X283582Y64867D01*
X283791Y64617D01*
X284041Y64450D01*
X284374Y64325D01*
X284749Y64283D01*
X285124Y64325D01*
X285457Y64450D01*
X285707Y64617D01*
X285916Y64867D01*
X285999Y65200D01*
X285916Y65533D01*
X285707Y65783D01*
X285457Y65950D01*
X285124Y66075D01*
X284749Y66117D01*
X284374Y66075D01*
X284041Y65950D01*
X283791Y65783D01*
X283582Y65533D01*
X283499Y65200D01*
G01X291499Y70613D02*
X317499D01*
G01X291499Y83613D02*
Y70613D01*
G01X287708Y57267D02*
X287583Y57017D01*
X287500Y56725D01*
Y56392D01*
X287625Y56017D01*
X287833Y55725D01*
X288083Y55517D01*
X288500Y55350D01*
X288875Y55308D01*
X289250Y55392D01*
X289500Y55517D01*
X289750Y55767D01*
X289917Y56058D01*
X290000Y56350D01*
Y56642D01*
X289917Y56933D01*
X289792Y57183D01*
X289625Y57392D01*
G01X289500Y58533D02*
X289792Y58783D01*
X289958Y59117D01*
X290000Y59492D01*
X289958Y59825D01*
X289750Y60158D01*
X289500Y60367D01*
X289250Y60408D01*
X288958Y60325D01*
X288750Y60033D01*
X288667Y59742D01*
Y59367D01*
G01Y59742D02*
X288542Y59992D01*
X288333Y60200D01*
X288083Y60283D01*
X287833Y60200D01*
X287625Y59992D01*
X287500Y59617D01*
X287542Y59242D01*
X287708Y58867D01*
G01X289500Y61633D02*
X289792Y61883D01*
X289958Y62217D01*
X290000Y62592D01*
X289958Y62925D01*
X289750Y63258D01*
X289500Y63467D01*
X289250Y63508D01*
X288958Y63425D01*
X288750Y63133D01*
X288667Y62842D01*
Y62467D01*
G01Y62842D02*
X288542Y63092D01*
X288333Y63300D01*
X288083Y63383D01*
X287833Y63300D01*
X287625Y63092D01*
X287500Y62717D01*
X287542Y62342D01*
X287708Y61967D01*
G01X290000Y65650D02*
X287500D01*
X288000Y65150D01*
G01X290000D02*
Y66150D01*
G01X278516Y76550D02*
Y79050D01*
X279557D01*
X279891Y78925D01*
X280099Y78758D01*
X280182Y78425D01*
X280099Y78092D01*
X279849Y77883D01*
X279557Y77758D01*
X278516D01*
G01X279557D02*
X280182Y76550D01*
G01X281532Y77050D02*
X281782Y76758D01*
X282116Y76592D01*
X282491Y76550D01*
X282824Y76592D01*
X283157Y76800D01*
X283366Y77050D01*
X283407Y77300D01*
X283324Y77592D01*
X283032Y77800D01*
X282741Y77883D01*
X282366D01*
G01X282741D02*
X282991Y78008D01*
X283199Y78217D01*
X283282Y78467D01*
X283199Y78717D01*
X282991Y78925D01*
X282616Y79050D01*
X282241Y79008D01*
X281866Y78842D01*
G01X285549Y79050D02*
X285216Y78967D01*
X284966Y78758D01*
X284799Y78508D01*
X284674Y78175D01*
X284632Y77800D01*
X284674Y77425D01*
X284799Y77092D01*
X284966Y76842D01*
X285216Y76633D01*
X285549Y76550D01*
X285882Y76633D01*
X286132Y76842D01*
X286299Y77092D01*
X286424Y77425D01*
X286466Y77800D01*
X286424Y78175D01*
X286299Y78508D01*
X286132Y78758D01*
X285882Y78967D01*
X285549Y79050D01*
G01X287857Y78633D02*
X288107Y78883D01*
X288399Y79008D01*
X288732Y79050D01*
X289149Y78967D01*
X289441Y78758D01*
X289524Y78508D01*
X289482Y78258D01*
X289316Y78050D01*
X288482Y77633D01*
X288107Y77342D01*
X287857Y76925D01*
X287774Y76550D01*
X289524D01*
G01X317499Y83613D02*
X291499D01*
G01X281017Y94000D02*
Y96500D01*
X282058D01*
X282392Y96375D01*
X282600Y96208D01*
X282683Y95875D01*
X282600Y95542D01*
X282350Y95333D01*
X282058Y95208D01*
X281017D01*
G01X282058D02*
X282683Y94000D01*
G01X284033Y94500D02*
X284283Y94208D01*
X284617Y94042D01*
X284992Y94000D01*
X285325Y94042D01*
X285658Y94250D01*
X285867Y94500D01*
X285908Y94750D01*
X285825Y95042D01*
X285533Y95250D01*
X285242Y95333D01*
X284867D01*
G01X285242D02*
X285492Y95458D01*
X285700Y95667D01*
X285783Y95917D01*
X285700Y96167D01*
X285492Y96375D01*
X285117Y96500D01*
X284742Y96458D01*
X284367Y96292D01*
G01X288050Y96500D02*
X287717Y96417D01*
X287467Y96208D01*
X287300Y95958D01*
X287175Y95625D01*
X287133Y95250D01*
X287175Y94875D01*
X287300Y94542D01*
X287467Y94292D01*
X287717Y94083D01*
X288050Y94000D01*
X288383Y94083D01*
X288633Y94292D01*
X288800Y94542D01*
X288925Y94875D01*
X288967Y95250D01*
X288925Y95625D01*
X288800Y95958D01*
X288633Y96208D01*
X288383Y96417D01*
X288050Y96500D01*
G01X291150Y94000D02*
Y96500D01*
X290650Y96000D01*
G01Y94000D02*
X291650D01*
G01X278500Y92517D02*
X276000D01*
Y93558D01*
X276125Y93892D01*
X276292Y94100D01*
X276625Y94183D01*
X276958Y94100D01*
X277167Y93850D01*
X277292Y93558D01*
Y92517D01*
G01Y93558D02*
X278500Y94183D01*
G01X278000Y95533D02*
X278292Y95783D01*
X278458Y96117D01*
X278500Y96492D01*
X278458Y96825D01*
X278250Y97158D01*
X278000Y97367D01*
X277750Y97408D01*
X277458Y97325D01*
X277250Y97033D01*
X277167Y96742D01*
Y96367D01*
G01Y96742D02*
X277042Y96992D01*
X276833Y97200D01*
X276583Y97283D01*
X276333Y97200D01*
X276125Y96992D01*
X276000Y96617D01*
X276042Y96242D01*
X276208Y95867D01*
G01X276000Y99550D02*
X276083Y99217D01*
X276292Y98967D01*
X276542Y98800D01*
X276875Y98675D01*
X277250Y98633D01*
X277625Y98675D01*
X277958Y98800D01*
X278208Y98967D01*
X278417Y99217D01*
X278500Y99550D01*
X278417Y99883D01*
X278208Y100133D01*
X277958Y100300D01*
X277625Y100425D01*
X277250Y100467D01*
X276875Y100425D01*
X276542Y100300D01*
X276292Y100133D01*
X276083Y99883D01*
X276000Y99550D01*
G01X278000Y101733D02*
X278292Y101983D01*
X278458Y102317D01*
X278500Y102692D01*
X278458Y103025D01*
X278250Y103358D01*
X278000Y103567D01*
X277750Y103608D01*
X277458Y103525D01*
X277250Y103233D01*
X277167Y102942D01*
Y102567D01*
G01Y102942D02*
X277042Y103192D01*
X276833Y103400D01*
X276583Y103483D01*
X276333Y103400D01*
X276125Y103192D01*
X276000Y102817D01*
X276042Y102442D01*
X276208Y102067D01*
G01X286916Y117050D02*
Y122050D01*
X290082D01*
G01X288916Y119633D02*
X286916D01*
G01X292516Y121217D02*
X293016Y121717D01*
X293599Y121967D01*
X294266Y122050D01*
X295099Y121883D01*
X295682Y121467D01*
X295849Y120967D01*
X295766Y120467D01*
X295432Y120050D01*
X293766Y119217D01*
X293016Y118633D01*
X292516Y117800D01*
X292349Y117050D01*
X295849D01*
G01X298282Y117633D02*
X298866Y117217D01*
X299532Y117050D01*
X300199Y117217D01*
X300782Y117717D01*
X301199Y118467D01*
X301366Y119217D01*
Y120133D01*
X301199Y120883D01*
X300782Y121550D01*
X300282Y121883D01*
X299699Y122050D01*
X299032Y121883D01*
X298532Y121550D01*
X298199Y121050D01*
X298032Y120383D01*
X298199Y119800D01*
X298616Y119217D01*
X299116Y118883D01*
X299699Y118800D01*
X300366Y118967D01*
X300866Y119383D01*
X301366Y120133D01*
G01X305299Y116883D02*
X305132Y116967D01*
Y117133D01*
X305299Y117217D01*
X305466Y117133D01*
Y116967D01*
X305299Y116883D01*
G01Y119133D02*
X305132Y119217D01*
Y119383D01*
X305299Y119467D01*
X305466Y119383D01*
Y119217D01*
X305299Y119133D01*
G01X309316Y121217D02*
X309816Y121717D01*
X310399Y121967D01*
X311066Y122050D01*
X311899Y121883D01*
X312482Y121467D01*
X312649Y120967D01*
X312566Y120467D01*
X312232Y120050D01*
X310566Y119217D01*
X309816Y118633D01*
X309316Y117800D01*
X309149Y117050D01*
X312649D01*
G01X314416D02*
X316499Y122050D01*
X318582Y117050D01*
G01X317832Y118800D02*
X315166D01*
G01X320599Y116883D02*
X323599Y122050D01*
G01X326116Y119133D02*
X326699Y119717D01*
X327199Y120050D01*
X327866Y120217D01*
X328449Y120050D01*
X328866Y119717D01*
X329199Y119217D01*
X329282Y118633D01*
X329199Y118133D01*
X328866Y117633D01*
X328366Y117217D01*
X327782Y117050D01*
X327116Y117217D01*
X326532Y117717D01*
X326199Y118467D01*
X326116Y119300D01*
X326282Y120383D01*
X326532Y120967D01*
X326949Y121550D01*
X327532Y121967D01*
X328116Y122050D01*
X328699Y121883D01*
X329116Y121467D01*
G01X331216Y122050D02*
X333299Y117050D01*
X335382Y122050D01*
G01X281017Y98000D02*
Y100500D01*
X282058D01*
X282392Y100375D01*
X282600Y100208D01*
X282683Y99875D01*
X282600Y99542D01*
X282350Y99333D01*
X282058Y99208D01*
X281017D01*
G01X282058D02*
X282683Y98000D01*
G01X285450D02*
Y100500D01*
X283908Y98708D01*
X285992D01*
G01X288050Y100500D02*
X287717Y100417D01*
X287467Y100208D01*
X287300Y99958D01*
X287175Y99625D01*
X287133Y99250D01*
X287175Y98875D01*
X287300Y98542D01*
X287467Y98292D01*
X287717Y98083D01*
X288050Y98000D01*
X288383Y98083D01*
X288633Y98292D01*
X288800Y98542D01*
X288925Y98875D01*
X288967Y99250D01*
X288925Y99625D01*
X288800Y99958D01*
X288633Y100208D01*
X288383Y100417D01*
X288050Y100500D01*
G01X291650Y98000D02*
Y100500D01*
X290108Y98708D01*
X292192D01*
G01X293474Y263517D02*
Y266017D01*
G01X295224D02*
Y263517D01*
G01Y264767D02*
X293474D01*
G01X296741Y263809D02*
X297032Y263600D01*
X297366Y263517D01*
X297699Y263600D01*
X297991Y263850D01*
X298199Y264225D01*
X298282Y264600D01*
Y265059D01*
X298199Y265434D01*
X297991Y265767D01*
X297741Y265934D01*
X297449Y266017D01*
X297116Y265934D01*
X296866Y265767D01*
X296699Y265517D01*
X296616Y265184D01*
X296699Y264892D01*
X296907Y264600D01*
X297157Y264434D01*
X297449Y264392D01*
X297782Y264475D01*
X298032Y264684D01*
X298282Y265059D01*
G01X282490Y299788D02*
X279990D01*
Y300829D01*
X280115Y301163D01*
X280282Y301371D01*
X280615Y301454D01*
X280948Y301371D01*
X281157Y301121D01*
X281282Y300829D01*
Y299788D01*
G01Y300829D02*
X282490Y301454D01*
G01Y304221D02*
X279990D01*
X281782Y302679D01*
Y304763D01*
G01X282115Y305904D02*
X282323Y306154D01*
X282448Y306446D01*
X282490Y306821D01*
X282407Y307196D01*
X282240Y307488D01*
X281948Y307696D01*
X281615Y307738D01*
X281282Y307654D01*
X281073Y307446D01*
X280907Y307154D01*
X280865Y306863D01*
X280907Y306571D01*
X281073Y306196D01*
X279990Y306321D01*
Y307446D01*
G01X281448Y309129D02*
X281157Y309421D01*
X280990Y309671D01*
X280907Y310004D01*
X280990Y310296D01*
X281157Y310504D01*
X281407Y310671D01*
X281698Y310713D01*
X281948Y310671D01*
X282198Y310504D01*
X282407Y310254D01*
X282490Y309963D01*
X282407Y309629D01*
X282157Y309338D01*
X281782Y309171D01*
X281365Y309129D01*
X280823Y309213D01*
X280532Y309338D01*
X280240Y309546D01*
X280032Y309838D01*
X279990Y310129D01*
X280073Y310421D01*
X280282Y310629D01*
G01X286490Y299788D02*
X283990D01*
Y300829D01*
X284115Y301163D01*
X284282Y301371D01*
X284615Y301454D01*
X284948Y301371D01*
X285157Y301121D01*
X285282Y300829D01*
Y299788D01*
G01Y300829D02*
X286490Y301454D01*
G01Y304221D02*
X283990D01*
X285782Y302679D01*
Y304763D01*
G01X286115Y305904D02*
X286323Y306154D01*
X286448Y306446D01*
X286490Y306821D01*
X286407Y307196D01*
X286240Y307488D01*
X285948Y307696D01*
X285615Y307738D01*
X285282Y307654D01*
X285073Y307446D01*
X284907Y307154D01*
X284865Y306863D01*
X284907Y306571D01*
X285073Y306196D01*
X283990Y306321D01*
Y307446D01*
G01X286490Y309838D02*
X285948Y309921D01*
X285490Y310046D01*
X285073Y310213D01*
X284615Y310421D01*
X283990Y310754D01*
Y309088D01*
G01X279973Y297771D02*
Y295979D01*
X280140Y295604D01*
X280473Y295354D01*
X280890Y295271D01*
X281307Y295354D01*
X281640Y295604D01*
X281807Y295979D01*
Y297771D01*
G01X283198Y297354D02*
X283448Y297604D01*
X283740Y297729D01*
X284073Y297771D01*
X284490Y297688D01*
X284782Y297479D01*
X284865Y297229D01*
X284823Y296979D01*
X284657Y296771D01*
X283823Y296354D01*
X283448Y296063D01*
X283198Y295646D01*
X283115Y295271D01*
X284865D01*
G01X287090D02*
X287382Y295313D01*
X287715Y295438D01*
X287923Y295646D01*
X288007Y295938D01*
X287923Y296229D01*
X287673Y296479D01*
X287298Y296604D01*
X286882D01*
X286632Y296688D01*
X286423Y296896D01*
X286340Y297188D01*
X286465Y297479D01*
X286757Y297688D01*
X287090Y297771D01*
X287423Y297688D01*
X287715Y297479D01*
X287840Y297188D01*
X287757Y296896D01*
X287548Y296688D01*
X287298Y296604D01*
X286882D01*
X286507Y296479D01*
X286257Y296229D01*
X286173Y295938D01*
X286257Y295646D01*
X286465Y295438D01*
X286798Y295313D01*
X287090Y295271D01*
G01X289500Y300350D02*
X292000D01*
G01X289500Y299392D02*
Y301308D01*
G01X292000Y302617D02*
X289500D01*
Y303617D01*
X289625Y303950D01*
X289917Y304200D01*
X290250Y304283D01*
X290583Y304200D01*
X290833Y303992D01*
X290958Y303617D01*
Y302617D01*
G01X291500Y305633D02*
X291792Y305883D01*
X291958Y306217D01*
X292000Y306592D01*
X291958Y306925D01*
X291750Y307258D01*
X291500Y307467D01*
X291250Y307508D01*
X290958Y307425D01*
X290750Y307133D01*
X290667Y306842D01*
Y306467D01*
G01Y306842D02*
X290542Y307092D01*
X290333Y307300D01*
X290083Y307383D01*
X289833Y307300D01*
X289625Y307092D01*
X289500Y306717D01*
X289542Y306342D01*
X289708Y305967D01*
G01X292000Y310150D02*
X289500D01*
X291292Y308608D01*
Y310692D01*
G01X276499Y323850D02*
Y337250D01*
G01X286499Y323850D02*
X276499D01*
G01X286499Y337250D02*
Y323850D01*
G01X274498Y366014D02*
Y327214D01*
G01X282499Y347250D02*
X278499D01*
Y339850D01*
G01X286999Y347250D02*
X282999D01*
Y339850D01*
G01X276499Y337250D02*
X286499D01*
G01X287999Y347750D02*
X289999Y349750D01*
X291999Y347750D01*
G01X295599D02*
Y366950D01*
X284399D01*
Y347750D01*
X295599D01*
G01X287482Y375050D02*
Y373258D01*
X287649Y372883D01*
X287982Y372633D01*
X288399Y372550D01*
X288816Y372633D01*
X289149Y372883D01*
X289316Y373258D01*
Y375050D01*
G01X290707Y374633D02*
X290957Y374883D01*
X291249Y375008D01*
X291582Y375050D01*
X291999Y374967D01*
X292291Y374758D01*
X292374Y374508D01*
X292332Y374258D01*
X292166Y374050D01*
X291332Y373633D01*
X290957Y373342D01*
X290707Y372925D01*
X290624Y372550D01*
X292374D01*
G01X293891Y372842D02*
X294182Y372633D01*
X294516Y372550D01*
X294849Y372633D01*
X295141Y372883D01*
X295349Y373258D01*
X295432Y373633D01*
Y374092D01*
X295349Y374467D01*
X295141Y374800D01*
X294891Y374967D01*
X294599Y375050D01*
X294266Y374967D01*
X294016Y374800D01*
X293849Y374550D01*
X293766Y374217D01*
X293849Y373925D01*
X294057Y373633D01*
X294307Y373467D01*
X294599Y373425D01*
X294932Y373508D01*
X295182Y373717D01*
X295432Y374092D01*
G01X288575Y685500D02*
Y688000D01*
G01X290325D02*
Y685500D01*
G01Y686750D02*
X288575D01*
G01X293050Y685500D02*
Y688000D01*
X291508Y686208D01*
X293592D01*
G01X289999Y707067D02*
X287499D01*
Y708108D01*
X287624Y708442D01*
X287791Y708650D01*
X288124Y708733D01*
X288457Y708650D01*
X288666Y708400D01*
X288791Y708108D01*
Y707067D01*
G01Y708108D02*
X289999Y708733D01*
G01Y711500D02*
X287499D01*
X289291Y709958D01*
Y712042D01*
G01X289624Y713183D02*
X289832Y713433D01*
X289957Y713725D01*
X289999Y714100D01*
X289916Y714475D01*
X289749Y714767D01*
X289457Y714975D01*
X289124Y715017D01*
X288791Y714933D01*
X288582Y714725D01*
X288416Y714433D01*
X288374Y714142D01*
X288416Y713850D01*
X288582Y713475D01*
X287499Y713600D01*
Y714725D01*
G01X287916Y716408D02*
X287666Y716658D01*
X287541Y716950D01*
X287499Y717283D01*
X287582Y717700D01*
X287791Y717992D01*
X288041Y718075D01*
X288291Y718033D01*
X288499Y717867D01*
X288916Y717033D01*
X289207Y716658D01*
X289624Y716408D01*
X289999Y716325D01*
Y718075D01*
G01X293999Y707067D02*
X291499D01*
Y708108D01*
X291624Y708442D01*
X291791Y708650D01*
X292124Y708733D01*
X292457Y708650D01*
X292666Y708400D01*
X292791Y708108D01*
Y707067D01*
G01Y708108D02*
X293999Y708733D01*
G01Y711500D02*
X291499D01*
X293291Y709958D01*
Y712042D01*
G01X293624Y713183D02*
X293832Y713433D01*
X293957Y713725D01*
X293999Y714100D01*
X293916Y714475D01*
X293749Y714767D01*
X293457Y714975D01*
X293124Y715017D01*
X292791Y714933D01*
X292582Y714725D01*
X292416Y714433D01*
X292374Y714142D01*
X292416Y713850D01*
X292582Y713475D01*
X291499Y713600D01*
Y714725D01*
G01X293499Y716283D02*
X293791Y716533D01*
X293957Y716867D01*
X293999Y717242D01*
X293957Y717575D01*
X293749Y717908D01*
X293499Y718117D01*
X293249Y718158D01*
X292957Y718075D01*
X292749Y717783D01*
X292666Y717492D01*
Y717117D01*
G01Y717492D02*
X292541Y717742D01*
X292332Y717950D01*
X292082Y718033D01*
X291832Y717950D01*
X291624Y717742D01*
X291499Y717367D01*
X291541Y716992D01*
X291707Y716617D01*
G01X284482Y704550D02*
Y702758D01*
X284649Y702383D01*
X284982Y702133D01*
X285399Y702050D01*
X285816Y702133D01*
X286149Y702383D01*
X286316Y702758D01*
Y704550D01*
G01X287707Y704133D02*
X287957Y704383D01*
X288249Y704508D01*
X288582Y704550D01*
X288999Y704467D01*
X289291Y704258D01*
X289374Y704008D01*
X289332Y703758D01*
X289166Y703550D01*
X288332Y703133D01*
X287957Y702842D01*
X287707Y702425D01*
X287624Y702050D01*
X289374D01*
G01X290682Y702425D02*
X290932Y702217D01*
X291224Y702092D01*
X291599Y702050D01*
X291974Y702133D01*
X292266Y702300D01*
X292474Y702592D01*
X292516Y702925D01*
X292432Y703258D01*
X292224Y703467D01*
X291932Y703633D01*
X291641Y703675D01*
X291349Y703633D01*
X290974Y703467D01*
X291099Y704550D01*
X292224D01*
G01X282000Y714350D02*
X284500D01*
G01X282000Y713392D02*
Y715308D01*
G01X284500Y716617D02*
X282000D01*
Y717617D01*
X282125Y717950D01*
X282417Y718200D01*
X282750Y718283D01*
X283083Y718200D01*
X283333Y717992D01*
X283458Y717617D01*
Y716617D01*
G01X284000Y719633D02*
X284292Y719883D01*
X284458Y720217D01*
X284500Y720592D01*
X284458Y720925D01*
X284250Y721258D01*
X284000Y721467D01*
X283750Y721508D01*
X283458Y721425D01*
X283250Y721133D01*
X283167Y720842D01*
Y720467D01*
G01Y720842D02*
X283042Y721092D01*
X282833Y721300D01*
X282583Y721383D01*
X282333Y721300D01*
X282125Y721092D01*
X282000Y720717D01*
X282042Y720342D01*
X282208Y719967D01*
G01X284000Y722733D02*
X284292Y722983D01*
X284458Y723317D01*
X284500Y723692D01*
X284458Y724025D01*
X284250Y724358D01*
X284000Y724567D01*
X283750Y724608D01*
X283458Y724525D01*
X283250Y724233D01*
X283167Y723942D01*
Y723567D01*
G01Y723942D02*
X283042Y724192D01*
X282833Y724400D01*
X282583Y724483D01*
X282333Y724400D01*
X282125Y724192D01*
X282000Y723817D01*
X282042Y723442D01*
X282208Y723067D01*
G01X292708Y732267D02*
X292583Y732017D01*
X292500Y731725D01*
Y731392D01*
X292625Y731017D01*
X292833Y730725D01*
X293083Y730517D01*
X293500Y730350D01*
X293875Y730308D01*
X294250Y730392D01*
X294500Y730517D01*
X294750Y730767D01*
X294917Y731058D01*
X295000Y731350D01*
Y731642D01*
X294917Y731933D01*
X294792Y732183D01*
X294625Y732392D01*
G01X292917Y733658D02*
X292667Y733908D01*
X292542Y734200D01*
X292500Y734533D01*
X292583Y734950D01*
X292792Y735242D01*
X293042Y735325D01*
X293292Y735283D01*
X293500Y735117D01*
X293917Y734283D01*
X294208Y733908D01*
X294625Y733658D01*
X295000Y733575D01*
Y735325D01*
G01X292917Y736758D02*
X292667Y737008D01*
X292542Y737300D01*
X292500Y737633D01*
X292583Y738050D01*
X292792Y738342D01*
X293042Y738425D01*
X293292Y738383D01*
X293500Y738217D01*
X293917Y737383D01*
X294208Y737008D01*
X294625Y736758D01*
X295000Y736675D01*
Y738425D01*
G01X294708Y739942D02*
X294917Y740233D01*
X295000Y740567D01*
X294917Y740900D01*
X294667Y741192D01*
X294292Y741400D01*
X293917Y741483D01*
X293458D01*
X293083Y741400D01*
X292750Y741192D01*
X292583Y740942D01*
X292500Y740650D01*
X292583Y740317D01*
X292750Y740067D01*
X293000Y739900D01*
X293333Y739817D01*
X293625Y739900D01*
X293917Y740108D01*
X294083Y740358D01*
X294125Y740650D01*
X294042Y740983D01*
X293833Y741233D01*
X293458Y741483D01*
G01X283499Y753750D02*
X279499D01*
Y746350D01*
G01X287499Y753750D02*
X283499D01*
Y746350D01*
G01X277499Y730350D02*
Y743750D01*
G01X287499Y730350D02*
X277499D01*
G01X287499Y743750D02*
Y730350D01*
G01X277499Y743750D02*
X287499D01*
G01X275499Y771450D02*
Y732650D01*
G01X288999Y754250D02*
X290999Y756250D01*
X292999Y754250D01*
G01X296599D02*
Y773450D01*
X285399D01*
Y754250D01*
X296599D01*
G01X286982Y780550D02*
Y778758D01*
X287149Y778383D01*
X287482Y778133D01*
X287899Y778050D01*
X288316Y778133D01*
X288649Y778383D01*
X288816Y778758D01*
Y780550D01*
G01X290207Y780133D02*
X290457Y780383D01*
X290749Y780508D01*
X291082Y780550D01*
X291499Y780467D01*
X291791Y780258D01*
X291874Y780008D01*
X291832Y779758D01*
X291666Y779550D01*
X290832Y779133D01*
X290457Y778842D01*
X290207Y778425D01*
X290124Y778050D01*
X291874D01*
G01X293307Y779092D02*
X293599Y779383D01*
X293849Y779550D01*
X294182Y779633D01*
X294474Y779550D01*
X294682Y779383D01*
X294849Y779133D01*
X294891Y778842D01*
X294849Y778592D01*
X294682Y778342D01*
X294432Y778133D01*
X294141Y778050D01*
X293807Y778133D01*
X293516Y778383D01*
X293349Y778758D01*
X293307Y779175D01*
X293391Y779717D01*
X293516Y780008D01*
X293724Y780300D01*
X294016Y780508D01*
X294307Y780550D01*
X294599Y780467D01*
X294807Y780258D01*
G01X279575Y1502500D02*
Y1505000D01*
G01X281325D02*
Y1502500D01*
G01Y1503750D02*
X279575D01*
G01X282633Y1503000D02*
X282883Y1502708D01*
X283217Y1502542D01*
X283592Y1502500D01*
X283925Y1502542D01*
X284258Y1502750D01*
X284467Y1503000D01*
X284508Y1503250D01*
X284425Y1503542D01*
X284133Y1503750D01*
X283842Y1503833D01*
X283467D01*
G01X283842D02*
X284092Y1503958D01*
X284300Y1504167D01*
X284383Y1504417D01*
X284300Y1504667D01*
X284092Y1504875D01*
X283717Y1505000D01*
X283342Y1504958D01*
X282967Y1504792D01*
G01X279900Y1525000D02*
X279567Y1525042D01*
X279275Y1525208D01*
X279025Y1525458D01*
X278858Y1525750D01*
X278775Y1526083D01*
Y1526417D01*
X278858Y1526750D01*
X279025Y1527042D01*
X279275Y1527292D01*
X279567Y1527458D01*
X279900Y1527500D01*
X280233Y1527458D01*
X280525Y1527292D01*
X280775Y1527042D01*
X280942Y1526750D01*
X281025Y1526417D01*
Y1526083D01*
X280942Y1525750D01*
X280775Y1525458D01*
X280525Y1525208D01*
X280233Y1525042D01*
X279900Y1525000D01*
G01X280233Y1525667D02*
X280733Y1525000D01*
G01X283000D02*
Y1527500D01*
X282500Y1527000D01*
G01Y1525000D02*
X283500D01*
G01X285183Y1525500D02*
X285433Y1525208D01*
X285767Y1525042D01*
X286142Y1525000D01*
X286475Y1525042D01*
X286808Y1525250D01*
X287017Y1525500D01*
X287058Y1525750D01*
X286975Y1526042D01*
X286683Y1526250D01*
X286392Y1526333D01*
X286017D01*
G01X286392D02*
X286642Y1526458D01*
X286850Y1526667D01*
X286933Y1526917D01*
X286850Y1527167D01*
X286642Y1527375D01*
X286267Y1527500D01*
X285892Y1527458D01*
X285517Y1527292D01*
G01X289000Y1538983D02*
X290792D01*
X291167Y1539150D01*
X291417Y1539483D01*
X291500Y1539900D01*
X291417Y1540317D01*
X291167Y1540650D01*
X290792Y1540817D01*
X289000D01*
G01X291500Y1543000D02*
X289000D01*
X289500Y1542500D01*
G01X291500D02*
Y1543500D01*
G01X291208Y1545392D02*
X291417Y1545683D01*
X291500Y1546017D01*
X291417Y1546350D01*
X291167Y1546642D01*
X290792Y1546850D01*
X290417Y1546933D01*
X289958D01*
X289583Y1546850D01*
X289250Y1546642D01*
X289083Y1546392D01*
X289000Y1546100D01*
X289083Y1545767D01*
X289250Y1545517D01*
X289500Y1545350D01*
X289833Y1545267D01*
X290125Y1545350D01*
X290417Y1545558D01*
X290583Y1545808D01*
X290625Y1546100D01*
X290542Y1546433D01*
X290333Y1546683D01*
X289958Y1546933D01*
G01X276499Y1541350D02*
Y1554750D01*
G01X286499Y1541350D02*
X276499D01*
G01X286499Y1554750D02*
Y1541350D01*
G01X274499Y1582450D02*
Y1543650D01*
G01X286016Y1560550D02*
Y1563050D01*
X287057D01*
X287391Y1562925D01*
X287599Y1562758D01*
X287682Y1562425D01*
X287599Y1562092D01*
X287349Y1561883D01*
X287057Y1561758D01*
X286016D01*
G01X287057D02*
X287682Y1560550D01*
G01X290449D02*
Y1563050D01*
X288907Y1561258D01*
X290991D01*
G01X293549Y1560550D02*
Y1563050D01*
X292007Y1561258D01*
X294091D01*
G01X295357Y1561592D02*
X295649Y1561883D01*
X295899Y1562050D01*
X296232Y1562133D01*
X296524Y1562050D01*
X296732Y1561883D01*
X296899Y1561633D01*
X296941Y1561342D01*
X296899Y1561092D01*
X296732Y1560842D01*
X296482Y1560633D01*
X296191Y1560550D01*
X295857Y1560633D01*
X295566Y1560883D01*
X295399Y1561258D01*
X295357Y1561675D01*
X295441Y1562217D01*
X295566Y1562508D01*
X295774Y1562800D01*
X296066Y1563008D01*
X296357Y1563050D01*
X296649Y1562967D01*
X296857Y1562758D01*
G01X280499Y1564750D02*
X276499D01*
Y1557350D01*
G01X286017Y1556500D02*
Y1559000D01*
X287058D01*
X287392Y1558875D01*
X287600Y1558708D01*
X287683Y1558375D01*
X287600Y1558042D01*
X287350Y1557833D01*
X287058Y1557708D01*
X286017D01*
G01X287058D02*
X287683Y1556500D01*
G01X290450D02*
Y1559000D01*
X288908Y1557208D01*
X290992D01*
G01X293550Y1556500D02*
Y1559000D01*
X292008Y1557208D01*
X294092D01*
G01X296067Y1556500D02*
X296150Y1557042D01*
X296275Y1557500D01*
X296442Y1557917D01*
X296650Y1558375D01*
X296983Y1559000D01*
X295317D01*
G01X284499Y1564750D02*
X280499D01*
Y1557350D01*
G01X276499Y1554750D02*
X286499D01*
G01X287999Y1565250D02*
X289999Y1567250D01*
X291999Y1565250D01*
G01X295599D02*
Y1584450D01*
X284399D01*
Y1565250D01*
X295599D01*
G01X285982Y1592550D02*
Y1590758D01*
X286149Y1590383D01*
X286482Y1590133D01*
X286899Y1590050D01*
X287316Y1590133D01*
X287649Y1590383D01*
X287816Y1590758D01*
Y1592550D01*
G01X289207Y1592133D02*
X289457Y1592383D01*
X289749Y1592508D01*
X290082Y1592550D01*
X290499Y1592467D01*
X290791Y1592258D01*
X290874Y1592008D01*
X290832Y1591758D01*
X290666Y1591550D01*
X289832Y1591133D01*
X289457Y1590842D01*
X289207Y1590425D01*
X289124Y1590050D01*
X290874D01*
G01X293099Y1592550D02*
X292766Y1592467D01*
X292516Y1592258D01*
X292349Y1592008D01*
X292224Y1591675D01*
X292182Y1591300D01*
X292224Y1590925D01*
X292349Y1590592D01*
X292516Y1590342D01*
X292766Y1590133D01*
X293099Y1590050D01*
X293432Y1590133D01*
X293682Y1590342D01*
X293849Y1590592D01*
X293974Y1590925D01*
X294016Y1591300D01*
X293974Y1591675D01*
X293849Y1592008D01*
X293682Y1592258D01*
X293432Y1592467D01*
X293099Y1592550D01*
G01X292324Y1874717D02*
Y1877217D01*
G01X294074D02*
Y1874717D01*
G01Y1875967D02*
X292324D01*
G01X296299Y1874717D02*
Y1877217D01*
X295799Y1876717D01*
G01Y1874717D02*
X296799D01*
G01X298607Y1876800D02*
X298857Y1877050D01*
X299149Y1877175D01*
X299482Y1877217D01*
X299899Y1877134D01*
X300191Y1876925D01*
X300274Y1876675D01*
X300232Y1876425D01*
X300066Y1876217D01*
X299232Y1875800D01*
X298857Y1875509D01*
X298607Y1875092D01*
X298524Y1874717D01*
X300274D01*
G01X293416Y1896550D02*
Y1901550D01*
X296582D01*
G01X295416Y1899133D02*
X293416D01*
G01X300599Y1896550D02*
Y1901550D01*
X299599Y1900550D01*
G01Y1896550D02*
X301599D01*
G01X306199D02*
Y1901550D01*
X305199Y1900550D01*
G01Y1896550D02*
X307199D01*
G01X311799Y1896383D02*
X311632Y1896467D01*
Y1896633D01*
X311799Y1896717D01*
X311966Y1896633D01*
Y1896467D01*
X311799Y1896383D01*
G01Y1898633D02*
X311632Y1898717D01*
Y1898883D01*
X311799Y1898967D01*
X311966Y1898883D01*
Y1898717D01*
X311799Y1898633D01*
G01X315816Y1900717D02*
X316316Y1901217D01*
X316899Y1901467D01*
X317566Y1901550D01*
X318399Y1901383D01*
X318982Y1900967D01*
X319149Y1900467D01*
X319066Y1899967D01*
X318732Y1899550D01*
X317066Y1898717D01*
X316316Y1898133D01*
X315816Y1897300D01*
X315649Y1896550D01*
X319149D01*
G01X320916D02*
X322999Y1901550D01*
X325082Y1896550D01*
G01X324332Y1898300D02*
X321666D01*
G01X327099Y1896383D02*
X330099Y1901550D01*
G01X332616Y1898633D02*
X333199Y1899217D01*
X333699Y1899550D01*
X334366Y1899717D01*
X334949Y1899550D01*
X335366Y1899217D01*
X335699Y1898717D01*
X335782Y1898133D01*
X335699Y1897633D01*
X335366Y1897133D01*
X334866Y1896717D01*
X334282Y1896550D01*
X333616Y1896717D01*
X333032Y1897217D01*
X332699Y1897967D01*
X332616Y1898800D01*
X332782Y1899883D01*
X333032Y1900467D01*
X333449Y1901050D01*
X334032Y1901467D01*
X334616Y1901550D01*
X335199Y1901383D01*
X335616Y1900967D01*
G01X337716Y1901550D02*
X339799Y1896550D01*
X341882Y1901550D01*
G01X282482Y1913050D02*
Y1911258D01*
X282649Y1910883D01*
X282982Y1910633D01*
X283399Y1910550D01*
X283816Y1910633D01*
X284149Y1910883D01*
X284316Y1911258D01*
Y1913050D01*
G01X286499Y1910550D02*
Y1913050D01*
X285999Y1912550D01*
G01Y1910550D02*
X286999D01*
G01X288807Y1911592D02*
X289099Y1911883D01*
X289349Y1912050D01*
X289682Y1912133D01*
X289974Y1912050D01*
X290182Y1911883D01*
X290349Y1911633D01*
X290391Y1911342D01*
X290349Y1911092D01*
X290182Y1910842D01*
X289932Y1910633D01*
X289641Y1910550D01*
X289307Y1910633D01*
X289016Y1910883D01*
X288849Y1911258D01*
X288807Y1911675D01*
X288891Y1912217D01*
X289016Y1912508D01*
X289224Y1912800D01*
X289516Y1913008D01*
X289807Y1913050D01*
X290099Y1912967D01*
X290307Y1912758D01*
G01X284999Y1915067D02*
X282499D01*
Y1916108D01*
X282624Y1916442D01*
X282791Y1916650D01*
X283124Y1916733D01*
X283457Y1916650D01*
X283666Y1916400D01*
X283791Y1916108D01*
Y1915067D01*
G01Y1916108D02*
X284999Y1916733D01*
G01Y1919500D02*
X282499D01*
X284291Y1917958D01*
Y1920042D01*
G01X284999Y1922600D02*
X282499D01*
X284291Y1921058D01*
Y1923142D01*
G01X282916Y1924408D02*
X282666Y1924658D01*
X282541Y1924950D01*
X282499Y1925283D01*
X282582Y1925700D01*
X282791Y1925992D01*
X283041Y1926075D01*
X283291Y1926033D01*
X283499Y1925867D01*
X283916Y1925033D01*
X284207Y1924658D01*
X284624Y1924408D01*
X284999Y1924325D01*
Y1926075D01*
G01X288499Y1915067D02*
X285999D01*
Y1916108D01*
X286124Y1916442D01*
X286291Y1916650D01*
X286624Y1916733D01*
X286957Y1916650D01*
X287166Y1916400D01*
X287291Y1916108D01*
Y1915067D01*
G01Y1916108D02*
X288499Y1916733D01*
G01Y1919500D02*
X285999D01*
X287791Y1917958D01*
Y1920042D01*
G01X288499Y1922600D02*
X285999D01*
X287791Y1921058D01*
Y1923142D01*
G01X287999Y1924283D02*
X288291Y1924533D01*
X288457Y1924867D01*
X288499Y1925242D01*
X288457Y1925575D01*
X288249Y1925908D01*
X287999Y1926117D01*
X287749Y1926158D01*
X287457Y1926075D01*
X287249Y1925783D01*
X287166Y1925492D01*
Y1925117D01*
G01Y1925492D02*
X287041Y1925742D01*
X286832Y1925950D01*
X286582Y1926033D01*
X286332Y1925950D01*
X286124Y1925742D01*
X285999Y1925367D01*
X286041Y1924992D01*
X286207Y1924617D01*
G01X281149Y1932750D02*
Y1946150D01*
G01X291149Y1932750D02*
X281149D01*
G01X291149Y1946150D02*
Y1932750D01*
G01X286358Y1957028D02*
X282358D01*
Y1949628D01*
G01X290358Y1957028D02*
X286358D01*
Y1949628D01*
G01X281149Y1946150D02*
X291149D01*
G01X274499Y1978950D02*
Y1940150D01*
G01X287777Y1957891D02*
X289777Y1959891D01*
X291777Y1957891D01*
G01X295377D02*
Y1977091D01*
X284177D01*
Y1957891D01*
X295377D01*
G01X286482Y1985550D02*
Y1983758D01*
X286649Y1983383D01*
X286982Y1983133D01*
X287399Y1983050D01*
X287816Y1983133D01*
X288149Y1983383D01*
X288316Y1983758D01*
Y1985550D01*
G01X290499Y1983050D02*
Y1985550D01*
X289999Y1985050D01*
G01Y1983050D02*
X290999D01*
G01X293516D02*
X293599Y1983592D01*
X293724Y1984050D01*
X293891Y1984467D01*
X294099Y1984925D01*
X294432Y1985550D01*
X292766D01*
G01X313307Y7480D02*
X313182Y7230D01*
X313099Y6938D01*
Y6605D01*
X313224Y6230D01*
X313432Y5938D01*
X313682Y5730D01*
X314099Y5563D01*
X314474Y5521D01*
X314849Y5605D01*
X315099Y5730D01*
X315349Y5980D01*
X315516Y6271D01*
X315599Y6563D01*
Y6855D01*
X315516Y7146D01*
X315391Y7396D01*
X315224Y7605D01*
G01X315099Y8746D02*
X315391Y8996D01*
X315557Y9330D01*
X315599Y9705D01*
X315557Y10038D01*
X315349Y10371D01*
X315099Y10580D01*
X314849Y10621D01*
X314557Y10538D01*
X314349Y10246D01*
X314266Y9955D01*
Y9580D01*
G01Y9955D02*
X314141Y10205D01*
X313932Y10413D01*
X313682Y10496D01*
X313432Y10413D01*
X313224Y10205D01*
X313099Y9830D01*
X313141Y9455D01*
X313307Y9080D01*
G01X315099Y11846D02*
X315391Y12096D01*
X315557Y12430D01*
X315599Y12805D01*
X315557Y13138D01*
X315349Y13471D01*
X315099Y13680D01*
X314849Y13721D01*
X314557Y13638D01*
X314349Y13346D01*
X314266Y13055D01*
Y12680D01*
G01Y13055D02*
X314141Y13305D01*
X313932Y13513D01*
X313682Y13596D01*
X313432Y13513D01*
X313224Y13305D01*
X313099Y12930D01*
X313141Y12555D01*
X313307Y12180D01*
G01X315599Y16363D02*
X313099D01*
X314891Y14821D01*
Y16905D01*
G01X304307Y7480D02*
X304182Y7230D01*
X304099Y6938D01*
Y6605D01*
X304224Y6230D01*
X304432Y5938D01*
X304682Y5730D01*
X305099Y5563D01*
X305474Y5521D01*
X305849Y5605D01*
X306099Y5730D01*
X306349Y5980D01*
X306516Y6271D01*
X306599Y6563D01*
Y6855D01*
X306516Y7146D01*
X306391Y7396D01*
X306224Y7605D01*
G01X306099Y8746D02*
X306391Y8996D01*
X306557Y9330D01*
X306599Y9705D01*
X306557Y10038D01*
X306349Y10371D01*
X306099Y10580D01*
X305849Y10621D01*
X305557Y10538D01*
X305349Y10246D01*
X305266Y9955D01*
Y9580D01*
G01Y9955D02*
X305141Y10205D01*
X304932Y10413D01*
X304682Y10496D01*
X304432Y10413D01*
X304224Y10205D01*
X304099Y9830D01*
X304141Y9455D01*
X304307Y9080D01*
G01X306099Y11846D02*
X306391Y12096D01*
X306557Y12430D01*
X306599Y12805D01*
X306557Y13138D01*
X306349Y13471D01*
X306099Y13680D01*
X305849Y13721D01*
X305557Y13638D01*
X305349Y13346D01*
X305266Y13055D01*
Y12680D01*
G01Y13055D02*
X305141Y13305D01*
X304932Y13513D01*
X304682Y13596D01*
X304432Y13513D01*
X304224Y13305D01*
X304099Y12930D01*
X304141Y12555D01*
X304307Y12180D01*
G01X306224Y14946D02*
X306432Y15196D01*
X306557Y15488D01*
X306599Y15863D01*
X306516Y16238D01*
X306349Y16530D01*
X306057Y16738D01*
X305724Y16780D01*
X305391Y16696D01*
X305182Y16488D01*
X305016Y16196D01*
X304974Y15905D01*
X305016Y15613D01*
X305182Y15238D01*
X304099Y15363D01*
Y16488D01*
G01X295307Y7480D02*
X295182Y7230D01*
X295099Y6938D01*
Y6605D01*
X295224Y6230D01*
X295432Y5938D01*
X295682Y5730D01*
X296099Y5563D01*
X296474Y5521D01*
X296849Y5605D01*
X297099Y5730D01*
X297349Y5980D01*
X297516Y6271D01*
X297599Y6563D01*
Y6855D01*
X297516Y7146D01*
X297391Y7396D01*
X297224Y7605D01*
G01X297099Y8746D02*
X297391Y8996D01*
X297557Y9330D01*
X297599Y9705D01*
X297557Y10038D01*
X297349Y10371D01*
X297099Y10580D01*
X296849Y10621D01*
X296557Y10538D01*
X296349Y10246D01*
X296266Y9955D01*
Y9580D01*
G01Y9955D02*
X296141Y10205D01*
X295932Y10413D01*
X295682Y10496D01*
X295432Y10413D01*
X295224Y10205D01*
X295099Y9830D01*
X295141Y9455D01*
X295307Y9080D01*
G01X297099Y11846D02*
X297391Y12096D01*
X297557Y12430D01*
X297599Y12805D01*
X297557Y13138D01*
X297349Y13471D01*
X297099Y13680D01*
X296849Y13721D01*
X296557Y13638D01*
X296349Y13346D01*
X296266Y13055D01*
Y12680D01*
G01Y13055D02*
X296141Y13305D01*
X295932Y13513D01*
X295682Y13596D01*
X295432Y13513D01*
X295224Y13305D01*
X295099Y12930D01*
X295141Y12555D01*
X295307Y12180D01*
G01X296557Y15071D02*
X296266Y15363D01*
X296099Y15613D01*
X296016Y15946D01*
X296099Y16238D01*
X296266Y16446D01*
X296516Y16613D01*
X296807Y16655D01*
X297057Y16613D01*
X297307Y16446D01*
X297516Y16196D01*
X297599Y15905D01*
X297516Y15571D01*
X297266Y15280D01*
X296891Y15113D01*
X296474Y15071D01*
X295932Y15155D01*
X295641Y15280D01*
X295349Y15488D01*
X295141Y15780D01*
X295099Y16071D01*
X295182Y16363D01*
X295391Y16571D01*
G01X310099Y30913D02*
Y36413D01*
G01Y18813D02*
Y24313D01*
G01X318099Y18813D02*
X310099D01*
G01X309099Y36413D02*
Y30913D01*
G01X301099D02*
Y36413D01*
G01Y18813D02*
Y24313D01*
G01X309099Y18813D02*
X301099D01*
G01X309099Y24313D02*
Y18813D01*
G01X300099Y36413D02*
Y30913D01*
G01Y24313D02*
Y18813D01*
G01X310099Y36413D02*
X318099D01*
G01X301099D02*
X309099D01*
G01X296999Y52313D02*
Y57813D01*
G01X304999Y52313D02*
X296999D01*
G01X304999Y57813D02*
Y52313D01*
G01Y69913D02*
Y64413D01*
G01X296999Y69913D02*
X304999D01*
G01X296999Y64413D02*
Y69913D01*
G01X306649Y68863D02*
Y59363D01*
X324349D01*
Y68863D01*
X306649D01*
G01X314400Y89200D02*
X327800D01*
G01X314400Y100600D02*
Y89200D01*
G01X307699Y84613D02*
Y88613D01*
X300299D01*
G01X300300Y92700D02*
Y88700D01*
X307700D01*
G01X300500Y108400D02*
Y94400D01*
G01X313500D02*
Y108400D01*
G01X300500Y94400D02*
X313500D01*
G01X327800Y100600D02*
X314400D01*
G01X321600Y103200D02*
Y107200D01*
X314200D01*
G01X295900Y110500D02*
X295567Y110542D01*
X295275Y110708D01*
X295025Y110958D01*
X294858Y111250D01*
X294775Y111583D01*
Y111917D01*
X294858Y112250D01*
X295025Y112542D01*
X295275Y112792D01*
X295567Y112958D01*
X295900Y113000D01*
X296233Y112958D01*
X296525Y112792D01*
X296775Y112542D01*
X296942Y112250D01*
X297025Y111917D01*
Y111583D01*
X296942Y111250D01*
X296775Y110958D01*
X296525Y110708D01*
X296233Y110542D01*
X295900Y110500D01*
G01X296233Y111167D02*
X296733Y110500D01*
G01X298917D02*
X299000Y111042D01*
X299125Y111500D01*
X299292Y111917D01*
X299500Y112375D01*
X299833Y113000D01*
X298167D01*
G01X301183Y110875D02*
X301433Y110667D01*
X301725Y110542D01*
X302100Y110500D01*
X302475Y110583D01*
X302767Y110750D01*
X302975Y111042D01*
X303017Y111375D01*
X302933Y111708D01*
X302725Y111917D01*
X302433Y112083D01*
X302142Y112125D01*
X301850Y112083D01*
X301475Y111917D01*
X301600Y113000D01*
X302725D01*
G01X313500Y108400D02*
X300500D01*
G01X298708Y322767D02*
X298583Y322517D01*
X298500Y322225D01*
Y321892D01*
X298625Y321517D01*
X298833Y321225D01*
X299083Y321017D01*
X299500Y320850D01*
X299875Y320808D01*
X300250Y320892D01*
X300500Y321017D01*
X300750Y321267D01*
X300917Y321558D01*
X301000Y321850D01*
Y322142D01*
X300917Y322433D01*
X300792Y322683D01*
X300625Y322892D01*
G01X298917Y324158D02*
X298667Y324408D01*
X298542Y324700D01*
X298500Y325033D01*
X298583Y325450D01*
X298792Y325742D01*
X299042Y325825D01*
X299292Y325783D01*
X299500Y325617D01*
X299917Y324783D01*
X300208Y324408D01*
X300625Y324158D01*
X301000Y324075D01*
Y325825D01*
G01Y328550D02*
X298500D01*
X300292Y327008D01*
Y329092D01*
G01X300625Y330233D02*
X300833Y330483D01*
X300958Y330775D01*
X301000Y331150D01*
X300917Y331525D01*
X300750Y331817D01*
X300458Y332025D01*
X300125Y332067D01*
X299792Y331983D01*
X299583Y331775D01*
X299417Y331483D01*
X299375Y331192D01*
X299417Y330900D01*
X299583Y330525D01*
X298500Y330650D01*
Y331775D01*
G01X310699Y332050D02*
Y336050D01*
X303299D01*
G01Y345550D02*
Y341550D01*
X310699D01*
G01Y337050D02*
Y341050D01*
X303299D01*
G01X311798Y341614D02*
X325198D01*
G01X311798Y331614D02*
Y341614D01*
G01X325198Y331614D02*
X311798D01*
G01X312799Y349350D02*
X324199D01*
G01X312799Y362750D02*
Y349350D01*
G01X324199Y362750D02*
X312799D01*
G01X304799Y362050D02*
Y358050D01*
X312199D01*
G01X304799D02*
Y354050D01*
X312199D01*
G01X320400Y363200D02*
Y367200D01*
X313000D01*
G01X301316Y372550D02*
Y375050D01*
X302357D01*
X302691Y374925D01*
X302899Y374758D01*
X302982Y374425D01*
X302899Y374092D01*
X302649Y373883D01*
X302357Y373758D01*
X301316D01*
G01X302357D02*
X302982Y372550D01*
G01X304457Y374633D02*
X304707Y374883D01*
X304999Y375008D01*
X305332Y375050D01*
X305749Y374967D01*
X306041Y374758D01*
X306124Y374508D01*
X306082Y374258D01*
X305916Y374050D01*
X305082Y373633D01*
X304707Y373342D01*
X304457Y372925D01*
X304374Y372550D01*
X306124D01*
G01X307432Y373050D02*
X307682Y372758D01*
X308016Y372592D01*
X308391Y372550D01*
X308724Y372592D01*
X309057Y372800D01*
X309266Y373050D01*
X309307Y373300D01*
X309224Y373592D01*
X308932Y373800D01*
X308641Y373883D01*
X308266D01*
G01X308641D02*
X308891Y374008D01*
X309099Y374217D01*
X309182Y374467D01*
X309099Y374717D01*
X308891Y374925D01*
X308516Y375050D01*
X308141Y375008D01*
X307766Y374842D01*
G01X311449Y372550D02*
Y375050D01*
X310949Y374550D01*
G01Y372550D02*
X311949D01*
G01X301316Y388550D02*
Y391050D01*
X302357D01*
X302691Y390925D01*
X302899Y390758D01*
X302982Y390425D01*
X302899Y390092D01*
X302649Y389883D01*
X302357Y389758D01*
X301316D01*
G01X302357D02*
X302982Y388550D01*
G01X304457Y390633D02*
X304707Y390883D01*
X304999Y391008D01*
X305332Y391050D01*
X305749Y390967D01*
X306041Y390758D01*
X306124Y390508D01*
X306082Y390258D01*
X305916Y390050D01*
X305082Y389633D01*
X304707Y389342D01*
X304457Y388925D01*
X304374Y388550D01*
X306124D01*
G01X307432Y389050D02*
X307682Y388758D01*
X308016Y388592D01*
X308391Y388550D01*
X308724Y388592D01*
X309057Y388800D01*
X309266Y389050D01*
X309307Y389300D01*
X309224Y389592D01*
X308932Y389800D01*
X308641Y389883D01*
X308266D01*
G01X308641D02*
X308891Y390008D01*
X309099Y390217D01*
X309182Y390467D01*
X309099Y390717D01*
X308891Y390925D01*
X308516Y391050D01*
X308141Y391008D01*
X307766Y390842D01*
G01X310657Y390633D02*
X310907Y390883D01*
X311199Y391008D01*
X311532Y391050D01*
X311949Y390967D01*
X312241Y390758D01*
X312324Y390508D01*
X312282Y390258D01*
X312116Y390050D01*
X311282Y389633D01*
X310907Y389342D01*
X310657Y388925D01*
X310574Y388550D01*
X312324D01*
G01X301316Y384550D02*
Y387050D01*
X302357D01*
X302691Y386925D01*
X302899Y386758D01*
X302982Y386425D01*
X302899Y386092D01*
X302649Y385883D01*
X302357Y385758D01*
X301316D01*
G01X302357D02*
X302982Y384550D01*
G01X304457Y386633D02*
X304707Y386883D01*
X304999Y387008D01*
X305332Y387050D01*
X305749Y386967D01*
X306041Y386758D01*
X306124Y386508D01*
X306082Y386258D01*
X305916Y386050D01*
X305082Y385633D01*
X304707Y385342D01*
X304457Y384925D01*
X304374Y384550D01*
X306124D01*
G01X307432Y385050D02*
X307682Y384758D01*
X308016Y384592D01*
X308391Y384550D01*
X308724Y384592D01*
X309057Y384800D01*
X309266Y385050D01*
X309307Y385300D01*
X309224Y385592D01*
X308932Y385800D01*
X308641Y385883D01*
X308266D01*
G01X308641D02*
X308891Y386008D01*
X309099Y386217D01*
X309182Y386467D01*
X309099Y386717D01*
X308891Y386925D01*
X308516Y387050D01*
X308141Y387008D01*
X307766Y386842D01*
G01X310532Y385050D02*
X310782Y384758D01*
X311116Y384592D01*
X311491Y384550D01*
X311824Y384592D01*
X312157Y384800D01*
X312366Y385050D01*
X312407Y385300D01*
X312324Y385592D01*
X312032Y385800D01*
X311741Y385883D01*
X311366D01*
G01X311741D02*
X311991Y386008D01*
X312199Y386217D01*
X312282Y386467D01*
X312199Y386717D01*
X311991Y386925D01*
X311616Y387050D01*
X311241Y387008D01*
X310866Y386842D01*
G01X301316Y380550D02*
Y383050D01*
X302357D01*
X302691Y382925D01*
X302899Y382758D01*
X302982Y382425D01*
X302899Y382092D01*
X302649Y381883D01*
X302357Y381758D01*
X301316D01*
G01X302357D02*
X302982Y380550D01*
G01X304457Y382633D02*
X304707Y382883D01*
X304999Y383008D01*
X305332Y383050D01*
X305749Y382967D01*
X306041Y382758D01*
X306124Y382508D01*
X306082Y382258D01*
X305916Y382050D01*
X305082Y381633D01*
X304707Y381342D01*
X304457Y380925D01*
X304374Y380550D01*
X306124D01*
G01X307432Y381050D02*
X307682Y380758D01*
X308016Y380592D01*
X308391Y380550D01*
X308724Y380592D01*
X309057Y380800D01*
X309266Y381050D01*
X309307Y381300D01*
X309224Y381592D01*
X308932Y381800D01*
X308641Y381883D01*
X308266D01*
G01X308641D02*
X308891Y382008D01*
X309099Y382217D01*
X309182Y382467D01*
X309099Y382717D01*
X308891Y382925D01*
X308516Y383050D01*
X308141Y383008D01*
X307766Y382842D01*
G01X311449Y380550D02*
X311741Y380592D01*
X312074Y380717D01*
X312282Y380925D01*
X312366Y381217D01*
X312282Y381508D01*
X312032Y381758D01*
X311657Y381883D01*
X311241D01*
X310991Y381967D01*
X310782Y382175D01*
X310699Y382467D01*
X310824Y382758D01*
X311116Y382967D01*
X311449Y383050D01*
X311782Y382967D01*
X312074Y382758D01*
X312199Y382467D01*
X312116Y382175D01*
X311907Y381967D01*
X311657Y381883D01*
X311241D01*
X310866Y381758D01*
X310616Y381508D01*
X310532Y381217D01*
X310616Y380925D01*
X310824Y380717D01*
X311157Y380592D01*
X311449Y380550D01*
G01X301316Y376550D02*
Y379050D01*
X302357D01*
X302691Y378925D01*
X302899Y378758D01*
X302982Y378425D01*
X302899Y378092D01*
X302649Y377883D01*
X302357Y377758D01*
X301316D01*
G01X302357D02*
X302982Y376550D01*
G01X304457Y378633D02*
X304707Y378883D01*
X304999Y379008D01*
X305332Y379050D01*
X305749Y378967D01*
X306041Y378758D01*
X306124Y378508D01*
X306082Y378258D01*
X305916Y378050D01*
X305082Y377633D01*
X304707Y377342D01*
X304457Y376925D01*
X304374Y376550D01*
X306124D01*
G01X307432Y377050D02*
X307682Y376758D01*
X308016Y376592D01*
X308391Y376550D01*
X308724Y376592D01*
X309057Y376800D01*
X309266Y377050D01*
X309307Y377300D01*
X309224Y377592D01*
X308932Y377800D01*
X308641Y377883D01*
X308266D01*
G01X308641D02*
X308891Y378008D01*
X309099Y378217D01*
X309182Y378467D01*
X309099Y378717D01*
X308891Y378925D01*
X308516Y379050D01*
X308141Y379008D01*
X307766Y378842D01*
G01X310741Y376842D02*
X311032Y376633D01*
X311366Y376550D01*
X311699Y376633D01*
X311991Y376883D01*
X312199Y377258D01*
X312282Y377633D01*
Y378092D01*
X312199Y378467D01*
X311991Y378800D01*
X311741Y378967D01*
X311449Y379050D01*
X311116Y378967D01*
X310866Y378800D01*
X310699Y378550D01*
X310616Y378217D01*
X310699Y377925D01*
X310907Y377633D01*
X311157Y377467D01*
X311449Y377425D01*
X311782Y377508D01*
X312032Y377717D01*
X312282Y378092D01*
G01X312208Y721767D02*
X312083Y721517D01*
X312000Y721225D01*
Y720892D01*
X312125Y720517D01*
X312333Y720225D01*
X312583Y720017D01*
X313000Y719850D01*
X313375Y719808D01*
X313750Y719892D01*
X314000Y720017D01*
X314250Y720267D01*
X314417Y720558D01*
X314500Y720850D01*
Y721142D01*
X314417Y721433D01*
X314292Y721683D01*
X314125Y721892D01*
G01X312417Y723158D02*
X312167Y723408D01*
X312042Y723700D01*
X312000Y724033D01*
X312083Y724450D01*
X312292Y724742D01*
X312542Y724825D01*
X312792Y724783D01*
X313000Y724617D01*
X313417Y723783D01*
X313708Y723408D01*
X314125Y723158D01*
X314500Y723075D01*
Y724825D01*
G01X314000Y726133D02*
X314292Y726383D01*
X314458Y726717D01*
X314500Y727092D01*
X314458Y727425D01*
X314250Y727758D01*
X314000Y727967D01*
X313750Y728008D01*
X313458Y727925D01*
X313250Y727633D01*
X313167Y727342D01*
Y726967D01*
G01Y727342D02*
X313042Y727592D01*
X312833Y727800D01*
X312583Y727883D01*
X312333Y727800D01*
X312125Y727592D01*
X312000Y727217D01*
X312042Y726842D01*
X312208Y726467D01*
G01X314125Y729233D02*
X314333Y729483D01*
X314458Y729775D01*
X314500Y730150D01*
X314417Y730525D01*
X314250Y730817D01*
X313958Y731025D01*
X313625Y731067D01*
X313292Y730983D01*
X313083Y730775D01*
X312917Y730483D01*
X312875Y730192D01*
X312917Y729900D01*
X313083Y729525D01*
X312000Y729650D01*
Y730775D01*
G01X312199Y740050D02*
Y744050D01*
X304799D01*
G01Y752050D02*
Y748050D01*
X312199D01*
G01Y744050D02*
Y748050D01*
X304799D01*
G01X313299Y748550D02*
X326699D01*
G01X313299Y738550D02*
Y748550D01*
G01X326699Y738550D02*
X313299D01*
G01X313799Y756350D02*
X325199D01*
G01X313799Y769750D02*
Y756350D01*
G01X325199Y769750D02*
X313799D01*
G01X305799Y769050D02*
Y765050D01*
X313199D01*
G01X305799Y764550D02*
Y760550D01*
X313199D01*
G01X321400Y770200D02*
Y774200D01*
X314000D01*
G01X295416Y1503050D02*
Y1508050D01*
X298582D01*
G01X297416Y1505633D02*
X295416D01*
G01X302599Y1503050D02*
Y1508050D01*
X301599Y1507050D01*
G01Y1503050D02*
X303599D01*
G01X306366Y1504050D02*
X306866Y1503467D01*
X307532Y1503133D01*
X308282Y1503050D01*
X308949Y1503133D01*
X309616Y1503550D01*
X310032Y1504050D01*
X310116Y1504550D01*
X309949Y1505133D01*
X309366Y1505550D01*
X308782Y1505717D01*
X308032D01*
G01X308782D02*
X309282Y1505967D01*
X309699Y1506383D01*
X309866Y1506883D01*
X309699Y1507383D01*
X309282Y1507800D01*
X308532Y1508050D01*
X307782Y1507967D01*
X307032Y1507633D01*
G01X313799Y1502883D02*
X313632Y1502967D01*
Y1503133D01*
X313799Y1503217D01*
X313966Y1503133D01*
Y1502967D01*
X313799Y1502883D01*
G01Y1505133D02*
X313632Y1505217D01*
Y1505383D01*
X313799Y1505467D01*
X313966Y1505383D01*
Y1505217D01*
X313799Y1505133D01*
G01X317816Y1507217D02*
X318316Y1507717D01*
X318899Y1507967D01*
X319566Y1508050D01*
X320399Y1507883D01*
X320982Y1507467D01*
X321149Y1506967D01*
X321066Y1506467D01*
X320732Y1506050D01*
X319066Y1505217D01*
X318316Y1504633D01*
X317816Y1503800D01*
X317649Y1503050D01*
X321149D01*
G01X322916D02*
X324999Y1508050D01*
X327082Y1503050D01*
G01X326332Y1504800D02*
X323666D01*
G01X329099Y1502883D02*
X332099Y1508050D01*
G01X334616Y1505133D02*
X335199Y1505717D01*
X335699Y1506050D01*
X336366Y1506217D01*
X336949Y1506050D01*
X337366Y1505717D01*
X337699Y1505217D01*
X337782Y1504633D01*
X337699Y1504133D01*
X337366Y1503633D01*
X336866Y1503217D01*
X336282Y1503050D01*
X335616Y1503217D01*
X335032Y1503717D01*
X334699Y1504467D01*
X334616Y1505300D01*
X334782Y1506383D01*
X335032Y1506967D01*
X335449Y1507550D01*
X336032Y1507967D01*
X336616Y1508050D01*
X337199Y1507883D01*
X337616Y1507467D01*
G01X339716Y1508050D02*
X341799Y1503050D01*
X343882Y1508050D01*
G01X296208Y1532317D02*
X296083Y1532067D01*
X296000Y1531775D01*
Y1531442D01*
X296125Y1531067D01*
X296333Y1530775D01*
X296583Y1530567D01*
X297000Y1530400D01*
X297375Y1530358D01*
X297750Y1530442D01*
X298000Y1530567D01*
X298250Y1530817D01*
X298417Y1531108D01*
X298500Y1531400D01*
Y1531692D01*
X298417Y1531983D01*
X298292Y1532233D01*
X298125Y1532442D01*
G01X296417Y1533708D02*
X296167Y1533958D01*
X296042Y1534250D01*
X296000Y1534583D01*
X296083Y1535000D01*
X296292Y1535292D01*
X296542Y1535375D01*
X296792Y1535333D01*
X297000Y1535167D01*
X297417Y1534333D01*
X297708Y1533958D01*
X298125Y1533708D01*
X298500Y1533625D01*
Y1535375D01*
G01X296000Y1537600D02*
X296083Y1537267D01*
X296292Y1537017D01*
X296542Y1536850D01*
X296875Y1536725D01*
X297250Y1536683D01*
X297625Y1536725D01*
X297958Y1536850D01*
X298208Y1537017D01*
X298417Y1537267D01*
X298500Y1537600D01*
X298417Y1537933D01*
X298208Y1538183D01*
X297958Y1538350D01*
X297625Y1538475D01*
X297250Y1538517D01*
X296875Y1538475D01*
X296542Y1538350D01*
X296292Y1538183D01*
X296083Y1537933D01*
X296000Y1537600D01*
G01X298000Y1539783D02*
X298292Y1540033D01*
X298458Y1540367D01*
X298500Y1540742D01*
X298458Y1541075D01*
X298250Y1541408D01*
X298000Y1541617D01*
X297750Y1541658D01*
X297458Y1541575D01*
X297250Y1541283D01*
X297167Y1540992D01*
Y1540617D01*
G01Y1540992D02*
X297042Y1541242D01*
X296833Y1541450D01*
X296583Y1541533D01*
X296333Y1541450D01*
X296125Y1541242D01*
X296000Y1540867D01*
X296042Y1540492D01*
X296208Y1540117D01*
G01X310208Y1517267D02*
X310083Y1517017D01*
X310000Y1516725D01*
Y1516392D01*
X310125Y1516017D01*
X310333Y1515725D01*
X310583Y1515517D01*
X311000Y1515350D01*
X311375Y1515308D01*
X311750Y1515392D01*
X312000Y1515517D01*
X312250Y1515767D01*
X312417Y1516058D01*
X312500Y1516350D01*
Y1516642D01*
X312417Y1516933D01*
X312292Y1517183D01*
X312125Y1517392D01*
G01X312500Y1519450D02*
X310000D01*
X310500Y1518950D01*
G01X312500D02*
Y1519950D01*
G01X312208Y1521842D02*
X312417Y1522133D01*
X312500Y1522467D01*
X312417Y1522800D01*
X312167Y1523092D01*
X311792Y1523300D01*
X311417Y1523383D01*
X310958D01*
X310583Y1523300D01*
X310250Y1523092D01*
X310083Y1522842D01*
X310000Y1522550D01*
X310083Y1522217D01*
X310250Y1521967D01*
X310500Y1521800D01*
X310833Y1521717D01*
X311125Y1521800D01*
X311417Y1522008D01*
X311583Y1522258D01*
X311625Y1522550D01*
X311542Y1522883D01*
X311333Y1523133D01*
X310958Y1523383D01*
G01X312500Y1525567D02*
X311958Y1525650D01*
X311500Y1525775D01*
X311083Y1525942D01*
X310625Y1526150D01*
X310000Y1526483D01*
Y1524817D01*
G01X308699Y1552550D02*
Y1556550D01*
X301299D01*
G01X309799Y1552050D02*
Y1562050D01*
G01X323199Y1552050D02*
X309799D01*
G01X312799Y1566850D02*
X324199D01*
G01X312799Y1580250D02*
Y1566850D01*
G01X304799Y1579050D02*
Y1575050D01*
X312199D01*
G01X304799D02*
Y1571050D01*
X312199D01*
G01X301299Y1564550D02*
Y1560550D01*
X308699D01*
G01Y1556550D02*
Y1560550D01*
X301299D01*
G01X309799Y1562050D02*
X323199D01*
G01X324199Y1580250D02*
X312799D01*
G01X305437Y1590450D02*
Y1592950D01*
X306478D01*
X306812Y1592825D01*
X307020Y1592658D01*
X307103Y1592325D01*
X307020Y1591992D01*
X306770Y1591783D01*
X306478Y1591658D01*
X305437D01*
G01X306478D02*
X307103Y1590450D01*
G01X309370D02*
Y1592950D01*
X308870Y1592450D01*
G01Y1590450D02*
X309870D01*
G01X311762Y1590742D02*
X312053Y1590533D01*
X312387Y1590450D01*
X312720Y1590533D01*
X313012Y1590783D01*
X313220Y1591158D01*
X313303Y1591533D01*
Y1591992D01*
X313220Y1592367D01*
X313012Y1592700D01*
X312762Y1592867D01*
X312470Y1592950D01*
X312137Y1592867D01*
X311887Y1592700D01*
X311720Y1592450D01*
X311637Y1592117D01*
X311720Y1591825D01*
X311928Y1591533D01*
X312178Y1591367D01*
X312470Y1591325D01*
X312803Y1591408D01*
X313053Y1591617D01*
X313303Y1591992D01*
G01X314653Y1590950D02*
X314903Y1590658D01*
X315237Y1590492D01*
X315612Y1590450D01*
X315945Y1590492D01*
X316278Y1590700D01*
X316487Y1590950D01*
X316528Y1591200D01*
X316445Y1591492D01*
X316153Y1591700D01*
X315862Y1591783D01*
X315487D01*
G01X315862D02*
X316112Y1591908D01*
X316320Y1592117D01*
X316403Y1592367D01*
X316320Y1592617D01*
X316112Y1592825D01*
X315737Y1592950D01*
X315362Y1592908D01*
X314987Y1592742D01*
G01X305437Y1586450D02*
Y1588950D01*
X306478D01*
X306812Y1588825D01*
X307020Y1588658D01*
X307103Y1588325D01*
X307020Y1587992D01*
X306770Y1587783D01*
X306478Y1587658D01*
X305437D01*
G01X306478D02*
X307103Y1586450D01*
G01X309370D02*
Y1588950D01*
X308870Y1588450D01*
G01Y1586450D02*
X309870D01*
G01X311762Y1586742D02*
X312053Y1586533D01*
X312387Y1586450D01*
X312720Y1586533D01*
X313012Y1586783D01*
X313220Y1587158D01*
X313303Y1587533D01*
Y1587992D01*
X313220Y1588367D01*
X313012Y1588700D01*
X312762Y1588867D01*
X312470Y1588950D01*
X312137Y1588867D01*
X311887Y1588700D01*
X311720Y1588450D01*
X311637Y1588117D01*
X311720Y1587825D01*
X311928Y1587533D01*
X312178Y1587367D01*
X312470Y1587325D01*
X312803Y1587408D01*
X313053Y1587617D01*
X313303Y1587992D01*
G01X316070Y1586450D02*
Y1588950D01*
X314528Y1587158D01*
X316612D01*
G01X320400Y1580600D02*
Y1584600D01*
X313000D01*
G01X313208Y1913267D02*
X313083Y1913017D01*
X313000Y1912725D01*
Y1912392D01*
X313125Y1912017D01*
X313333Y1911725D01*
X313583Y1911517D01*
X314000Y1911350D01*
X314375Y1911308D01*
X314750Y1911392D01*
X315000Y1911517D01*
X315250Y1911767D01*
X315417Y1912058D01*
X315500Y1912350D01*
Y1912642D01*
X315417Y1912933D01*
X315292Y1913183D01*
X315125Y1913392D01*
G01X315500Y1915450D02*
X313000D01*
X313500Y1914950D01*
G01X315500D02*
Y1915950D01*
G01Y1918550D02*
X315458Y1918842D01*
X315333Y1919175D01*
X315125Y1919383D01*
X314833Y1919467D01*
X314542Y1919383D01*
X314292Y1919133D01*
X314167Y1918758D01*
Y1918342D01*
X314083Y1918092D01*
X313875Y1917883D01*
X313583Y1917800D01*
X313292Y1917925D01*
X313083Y1918217D01*
X313000Y1918550D01*
X313083Y1918883D01*
X313292Y1919175D01*
X313583Y1919300D01*
X313875Y1919217D01*
X314083Y1919008D01*
X314167Y1918758D01*
Y1918342D01*
X314292Y1917967D01*
X314542Y1917717D01*
X314833Y1917633D01*
X315125Y1917717D01*
X315333Y1917925D01*
X315458Y1918258D01*
X315500Y1918550D01*
G01Y1921650D02*
X313000D01*
X313500Y1921150D01*
G01X315500D02*
Y1922150D01*
G01X296708Y1927767D02*
X296583Y1927517D01*
X296500Y1927225D01*
Y1926892D01*
X296625Y1926517D01*
X296833Y1926225D01*
X297083Y1926017D01*
X297500Y1925850D01*
X297875Y1925808D01*
X298250Y1925892D01*
X298500Y1926017D01*
X298750Y1926267D01*
X298917Y1926558D01*
X299000Y1926850D01*
Y1927142D01*
X298917Y1927433D01*
X298792Y1927683D01*
X298625Y1927892D01*
G01X299000Y1929950D02*
X296500D01*
X297000Y1929450D01*
G01X299000D02*
Y1930450D01*
G01Y1933050D02*
X298958Y1933342D01*
X298833Y1933675D01*
X298625Y1933883D01*
X298333Y1933967D01*
X298042Y1933883D01*
X297792Y1933633D01*
X297667Y1933258D01*
Y1932842D01*
X297583Y1932592D01*
X297375Y1932383D01*
X297083Y1932300D01*
X296792Y1932425D01*
X296583Y1932717D01*
X296500Y1933050D01*
X296583Y1933383D01*
X296792Y1933675D01*
X297083Y1933800D01*
X297375Y1933717D01*
X297583Y1933508D01*
X297667Y1933258D01*
Y1932842D01*
X297792Y1932467D01*
X298042Y1932217D01*
X298333Y1932133D01*
X298625Y1932217D01*
X298833Y1932425D01*
X298958Y1932758D01*
X299000Y1933050D01*
G01Y1936067D02*
X298458Y1936150D01*
X298000Y1936275D01*
X297583Y1936442D01*
X297125Y1936650D01*
X296500Y1936983D01*
Y1935317D01*
G01X315921Y1942909D02*
Y1946909D01*
X308521D01*
G01X308158Y1955328D02*
Y1951328D01*
X315558D01*
G01X315921Y1946909D02*
Y1950909D01*
X308521D01*
G01X308077Y1968191D02*
Y1964191D01*
X315477D01*
G01X308077D02*
Y1960191D01*
X315477D01*
G01X331916Y2550D02*
Y7550D01*
X335082D01*
G01X333916Y5133D02*
X331916D01*
G01X337266Y3550D02*
X337766Y2967D01*
X338432Y2633D01*
X339182Y2550D01*
X339849Y2633D01*
X340516Y3050D01*
X340932Y3550D01*
X341016Y4050D01*
X340849Y4633D01*
X340266Y5050D01*
X339682Y5217D01*
X338932D01*
G01X339682D02*
X340182Y5467D01*
X340599Y5883D01*
X340766Y6383D01*
X340599Y6883D01*
X340182Y7300D01*
X339432Y7550D01*
X338682Y7467D01*
X337932Y7133D01*
G01X344699Y7550D02*
X344032Y7383D01*
X343532Y6967D01*
X343199Y6467D01*
X342949Y5800D01*
X342866Y5050D01*
X342949Y4300D01*
X343199Y3633D01*
X343532Y3133D01*
X344032Y2717D01*
X344699Y2550D01*
X345366Y2717D01*
X345866Y3133D01*
X346199Y3633D01*
X346449Y4300D01*
X346532Y5050D01*
X346449Y5800D01*
X346199Y6467D01*
X345866Y6967D01*
X345366Y7383D01*
X344699Y7550D01*
G01X350299Y2383D02*
X350132Y2467D01*
Y2633D01*
X350299Y2717D01*
X350466Y2633D01*
Y2467D01*
X350299Y2383D01*
G01Y4633D02*
X350132Y4717D01*
Y4883D01*
X350299Y4967D01*
X350466Y4883D01*
Y4717D01*
X350299Y4633D01*
G01X354066Y3550D02*
X354566Y2967D01*
X355232Y2633D01*
X355982Y2550D01*
X356649Y2633D01*
X357316Y3050D01*
X357732Y3550D01*
X357816Y4050D01*
X357649Y4633D01*
X357066Y5050D01*
X356482Y5217D01*
X355732D01*
G01X356482D02*
X356982Y5467D01*
X357399Y5883D01*
X357566Y6383D01*
X357399Y6883D01*
X356982Y7300D01*
X356232Y7550D01*
X355482Y7467D01*
X354732Y7133D01*
G01X359416Y2550D02*
X361499Y7550D01*
X363582Y2550D01*
G01X362832Y4300D02*
X360166D01*
G01X365599Y2383D02*
X368599Y7550D01*
G01X372699Y2550D02*
Y7550D01*
X371699Y6550D01*
G01Y2550D02*
X373699D01*
G01X376466Y3300D02*
X376966Y2883D01*
X377549Y2633D01*
X378299Y2550D01*
X379049Y2717D01*
X379632Y3050D01*
X380049Y3633D01*
X380132Y4300D01*
X379966Y4967D01*
X379549Y5383D01*
X378966Y5717D01*
X378382Y5800D01*
X377799Y5717D01*
X377049Y5383D01*
X377299Y7550D01*
X379549D01*
G01X381816D02*
X383899Y2550D01*
X385982Y7550D01*
G01X323500Y6017D02*
X321000D01*
Y7058D01*
X321125Y7392D01*
X321292Y7600D01*
X321625Y7683D01*
X321958Y7600D01*
X322167Y7350D01*
X322292Y7058D01*
Y6017D01*
G01Y7058D02*
X323500Y7683D01*
G01X323125Y9033D02*
X323333Y9283D01*
X323458Y9575D01*
X323500Y9950D01*
X323417Y10325D01*
X323250Y10617D01*
X322958Y10825D01*
X322625Y10867D01*
X322292Y10783D01*
X322083Y10575D01*
X321917Y10283D01*
X321875Y9992D01*
X321917Y9700D01*
X322083Y9325D01*
X321000Y9450D01*
Y10575D01*
G01X323500Y13550D02*
X321000D01*
X322792Y12008D01*
Y14092D01*
G01X323500Y16150D02*
X321000D01*
X321500Y15650D01*
G01X323500D02*
Y16650D01*
G01X336607Y12550D02*
Y15050D01*
X338191D01*
G01X337607Y13842D02*
X336607D01*
G01X339582Y13050D02*
X339832Y12758D01*
X340166Y12592D01*
X340541Y12550D01*
X340874Y12592D01*
X341207Y12800D01*
X341416Y13050D01*
X341457Y13300D01*
X341374Y13592D01*
X341082Y13800D01*
X340791Y13883D01*
X340416D01*
G01X340791D02*
X341041Y14008D01*
X341249Y14217D01*
X341332Y14467D01*
X341249Y14717D01*
X341041Y14925D01*
X340666Y15050D01*
X340291Y15008D01*
X339916Y14842D01*
G01X343599Y15050D02*
X343266Y14967D01*
X343016Y14758D01*
X342849Y14508D01*
X342724Y14175D01*
X342682Y13800D01*
X342724Y13425D01*
X342849Y13092D01*
X343016Y12842D01*
X343266Y12633D01*
X343599Y12550D01*
X343932Y12633D01*
X344182Y12842D01*
X344349Y13092D01*
X344474Y13425D01*
X344516Y13800D01*
X344474Y14175D01*
X344349Y14508D01*
X344182Y14758D01*
X343932Y14967D01*
X343599Y15050D01*
G01X350999Y18650D02*
X327999D01*
G01D02*
Y57450D01*
G01X318099Y36413D02*
Y30913D01*
G01Y24313D02*
Y18813D01*
G01X318900Y36400D02*
Y18800D01*
G01X326900D02*
Y36400D01*
G01X318900Y18800D02*
X326900D01*
G01X317499Y37113D02*
Y50113D01*
G01X318499Y40313D02*
Y45813D01*
G01X326499Y40313D02*
X318499D01*
G01X326499Y45813D02*
Y40313D01*
G01X326900Y36400D02*
X318900D01*
G01X317499Y70613D02*
Y83613D01*
G01X335016Y72050D02*
Y74550D01*
X336057D01*
X336391Y74425D01*
X336599Y74258D01*
X336682Y73925D01*
X336599Y73592D01*
X336349Y73383D01*
X336057Y73258D01*
X335016D01*
G01X336057D02*
X336682Y72050D01*
G01X339449D02*
Y74550D01*
X337907Y72758D01*
X339991D01*
G01X341966Y72050D02*
X342049Y72592D01*
X342174Y73050D01*
X342341Y73467D01*
X342549Y73925D01*
X342882Y74550D01*
X341216D01*
G01X345649Y72050D02*
Y74550D01*
X344107Y72758D01*
X346191D01*
G01X332299Y65050D02*
Y61050D01*
X339699D01*
G01X332299Y69050D02*
Y65050D01*
X339699D01*
G01X327999Y57450D02*
X350999D01*
G01X326499Y57913D02*
Y52413D01*
G01X318499Y57913D02*
X326499D01*
G01X318499Y52413D02*
Y57913D01*
G01X329000Y61108D02*
X326500D01*
Y62692D01*
G01X327708Y62108D02*
Y61108D01*
G01X326917Y64208D02*
X326667Y64458D01*
X326542Y64750D01*
X326500Y65083D01*
X326583Y65500D01*
X326792Y65792D01*
X327042Y65875D01*
X327292Y65833D01*
X327500Y65667D01*
X327917Y64833D01*
X328208Y64458D01*
X328625Y64208D01*
X329000Y64125D01*
Y65875D01*
G01X328708Y67392D02*
X328917Y67683D01*
X329000Y68017D01*
X328917Y68350D01*
X328667Y68642D01*
X328292Y68850D01*
X327917Y68933D01*
X327458D01*
X327083Y68850D01*
X326750Y68642D01*
X326583Y68392D01*
X326500Y68100D01*
X326583Y67767D01*
X326750Y67517D01*
X327000Y67350D01*
X327333Y67267D01*
X327625Y67350D01*
X327917Y67558D01*
X328083Y67808D01*
X328125Y68100D01*
X328042Y68433D01*
X327833Y68683D01*
X327458Y68933D01*
G01X327800Y89200D02*
Y100600D01*
G01X335016Y76050D02*
Y78550D01*
X336057D01*
X336391Y78425D01*
X336599Y78258D01*
X336682Y77925D01*
X336599Y77592D01*
X336349Y77383D01*
X336057Y77258D01*
X335016D01*
G01X336057D02*
X336682Y76050D01*
G01X339449D02*
Y78550D01*
X337907Y76758D01*
X339991D01*
G01X341966Y76050D02*
X342049Y76592D01*
X342174Y77050D01*
X342341Y77467D01*
X342549Y77925D01*
X342882Y78550D01*
X341216D01*
G01X344232Y76425D02*
X344482Y76217D01*
X344774Y76092D01*
X345149Y76050D01*
X345524Y76133D01*
X345816Y76300D01*
X346024Y76592D01*
X346066Y76925D01*
X345982Y77258D01*
X345774Y77467D01*
X345482Y77633D01*
X345191Y77675D01*
X344899Y77633D01*
X344524Y77467D01*
X344649Y78550D01*
X345774D01*
G01X328017Y85000D02*
Y87500D01*
X329058D01*
X329392Y87375D01*
X329600Y87208D01*
X329683Y86875D01*
X329600Y86542D01*
X329350Y86333D01*
X329058Y86208D01*
X328017D01*
G01X329058D02*
X329683Y85000D01*
G01X331033Y85375D02*
X331283Y85167D01*
X331575Y85042D01*
X331950Y85000D01*
X332325Y85083D01*
X332617Y85250D01*
X332825Y85542D01*
X332867Y85875D01*
X332783Y86208D01*
X332575Y86417D01*
X332283Y86583D01*
X331992Y86625D01*
X331700Y86583D01*
X331325Y86417D01*
X331450Y87500D01*
X332575D01*
G01X335550Y85000D02*
Y87500D01*
X334008Y85708D01*
X336092D01*
G01X338150Y87500D02*
X337817Y87417D01*
X337567Y87208D01*
X337400Y86958D01*
X337275Y86625D01*
X337233Y86250D01*
X337275Y85875D01*
X337400Y85542D01*
X337567Y85292D01*
X337817Y85083D01*
X338150Y85000D01*
X338483Y85083D01*
X338733Y85292D01*
X338900Y85542D01*
X339025Y85875D01*
X339067Y86250D01*
X339025Y86625D01*
X338900Y86958D01*
X338733Y87208D01*
X338483Y87417D01*
X338150Y87500D01*
G01X331900Y83000D02*
Y76000D01*
X318500D01*
Y83000D01*
X331900D01*
G01X325400Y102500D02*
X325067Y102542D01*
X324775Y102708D01*
X324525Y102958D01*
X324358Y103250D01*
X324275Y103583D01*
Y103917D01*
X324358Y104250D01*
X324525Y104542D01*
X324775Y104792D01*
X325067Y104958D01*
X325400Y105000D01*
X325733Y104958D01*
X326025Y104792D01*
X326275Y104542D01*
X326442Y104250D01*
X326525Y103917D01*
Y103583D01*
X326442Y103250D01*
X326275Y102958D01*
X326025Y102708D01*
X325733Y102542D01*
X325400Y102500D01*
G01X325733Y103167D02*
X326233Y102500D01*
G01X328417D02*
X328500Y103042D01*
X328625Y103500D01*
X328792Y103917D01*
X329000Y104375D01*
X329333Y105000D01*
X327667D01*
G01X332100Y102500D02*
Y105000D01*
X330558Y103208D01*
X332642D01*
G01X316517Y109500D02*
Y112000D01*
X317558D01*
X317892Y111875D01*
X318100Y111708D01*
X318183Y111375D01*
X318100Y111042D01*
X317850Y110833D01*
X317558Y110708D01*
X316517D01*
G01X317558D02*
X318183Y109500D01*
G01X320950D02*
Y112000D01*
X319408Y110208D01*
X321492D01*
G01X323550Y112000D02*
X323217Y111917D01*
X322967Y111708D01*
X322800Y111458D01*
X322675Y111125D01*
X322633Y110750D01*
X322675Y110375D01*
X322800Y110042D01*
X322967Y109792D01*
X323217Y109583D01*
X323550Y109500D01*
X323883Y109583D01*
X324133Y109792D01*
X324300Y110042D01*
X324425Y110375D01*
X324467Y110750D01*
X324425Y111125D01*
X324300Y111458D01*
X324133Y111708D01*
X323883Y111917D01*
X323550Y112000D01*
G01X325733Y109875D02*
X325983Y109667D01*
X326275Y109542D01*
X326650Y109500D01*
X327025Y109583D01*
X327317Y109750D01*
X327525Y110042D01*
X327567Y110375D01*
X327483Y110708D01*
X327275Y110917D01*
X326983Y111083D01*
X326692Y111125D01*
X326400Y111083D01*
X326025Y110917D01*
X326150Y112000D01*
X327275D01*
G01X316708Y314267D02*
X316583Y314017D01*
X316500Y313725D01*
Y313392D01*
X316625Y313017D01*
X316833Y312725D01*
X317083Y312517D01*
X317500Y312350D01*
X317875Y312308D01*
X318250Y312392D01*
X318500Y312517D01*
X318750Y312767D01*
X318917Y313058D01*
X319000Y313350D01*
Y313642D01*
X318917Y313933D01*
X318792Y314183D01*
X318625Y314392D01*
G01X316917Y315658D02*
X316667Y315908D01*
X316542Y316200D01*
X316500Y316533D01*
X316583Y316950D01*
X316792Y317242D01*
X317042Y317325D01*
X317292Y317283D01*
X317500Y317117D01*
X317917Y316283D01*
X318208Y315908D01*
X318625Y315658D01*
X319000Y315575D01*
Y317325D01*
G01X318625Y318633D02*
X318833Y318883D01*
X318958Y319175D01*
X319000Y319550D01*
X318917Y319925D01*
X318750Y320217D01*
X318458Y320425D01*
X318125Y320467D01*
X317792Y320383D01*
X317583Y320175D01*
X317417Y319883D01*
X317375Y319592D01*
X317417Y319300D01*
X317583Y318925D01*
X316500Y319050D01*
Y320175D01*
G01X318500Y321733D02*
X318792Y321983D01*
X318958Y322317D01*
X319000Y322692D01*
X318958Y323025D01*
X318750Y323358D01*
X318500Y323567D01*
X318250Y323608D01*
X317958Y323525D01*
X317750Y323233D01*
X317667Y322942D01*
Y322567D01*
G01Y322942D02*
X317542Y323192D01*
X317333Y323400D01*
X317083Y323483D01*
X316833Y323400D01*
X316625Y323192D01*
X316500Y322817D01*
X316542Y322442D01*
X316708Y322067D01*
G01X335198Y335114D02*
Y339114D01*
X327798D01*
G01X335198Y331114D02*
Y335114D01*
X327798D01*
G01X323924Y346555D02*
Y344763D01*
X324091Y344388D01*
X324424Y344138D01*
X324841Y344055D01*
X325258Y344138D01*
X325591Y344388D01*
X325758Y344763D01*
Y346555D01*
G01X327024Y344555D02*
X327274Y344263D01*
X327608Y344097D01*
X327983Y344055D01*
X328316Y344097D01*
X328649Y344305D01*
X328858Y344555D01*
X328899Y344805D01*
X328816Y345097D01*
X328524Y345305D01*
X328233Y345388D01*
X327858D01*
G01X328233D02*
X328483Y345513D01*
X328691Y345722D01*
X328774Y345972D01*
X328691Y346222D01*
X328483Y346430D01*
X328108Y346555D01*
X327733Y346513D01*
X327358Y346347D01*
G01X331041Y346555D02*
X330708Y346472D01*
X330458Y346263D01*
X330291Y346013D01*
X330166Y345680D01*
X330124Y345305D01*
X330166Y344930D01*
X330291Y344597D01*
X330458Y344347D01*
X330708Y344138D01*
X331041Y344055D01*
X331374Y344138D01*
X331624Y344347D01*
X331791Y344597D01*
X331916Y344930D01*
X331958Y345305D01*
X331916Y345680D01*
X331791Y346013D01*
X331624Y346263D01*
X331374Y346472D01*
X331041Y346555D01*
G01X325198Y341614D02*
Y331614D01*
G01X329000Y349900D02*
X328958Y349567D01*
X328792Y349275D01*
X328542Y349025D01*
X328250Y348858D01*
X327917Y348775D01*
X327583D01*
X327250Y348858D01*
X326958Y349025D01*
X326708Y349275D01*
X326542Y349567D01*
X326500Y349900D01*
X326542Y350233D01*
X326708Y350525D01*
X326958Y350775D01*
X327250Y350942D01*
X327583Y351025D01*
X327917D01*
X328250Y350942D01*
X328542Y350775D01*
X328792Y350525D01*
X328958Y350233D01*
X329000Y349900D01*
G01X328333Y350233D02*
X329000Y350733D01*
G01X326917Y352208D02*
X326667Y352458D01*
X326542Y352750D01*
X326500Y353083D01*
X326583Y353500D01*
X326792Y353792D01*
X327042Y353875D01*
X327292Y353833D01*
X327500Y353667D01*
X327917Y352833D01*
X328208Y352458D01*
X328625Y352208D01*
X329000Y352125D01*
Y353875D01*
G01X326500Y356100D02*
X326583Y355767D01*
X326792Y355517D01*
X327042Y355350D01*
X327375Y355225D01*
X327750Y355183D01*
X328125Y355225D01*
X328458Y355350D01*
X328708Y355517D01*
X328917Y355767D01*
X329000Y356100D01*
X328917Y356433D01*
X328708Y356683D01*
X328458Y356850D01*
X328125Y356975D01*
X327750Y357017D01*
X327375Y356975D01*
X327042Y356850D01*
X326792Y356683D01*
X326583Y356433D01*
X326500Y356100D01*
G01X324199Y349350D02*
Y362750D01*
G01X324017Y364500D02*
Y367000D01*
X325058D01*
X325392Y366875D01*
X325600Y366708D01*
X325683Y366375D01*
X325600Y366042D01*
X325350Y365833D01*
X325058Y365708D01*
X324017D01*
G01X325058D02*
X325683Y364500D01*
G01X328450D02*
Y367000D01*
X326908Y365208D01*
X328992D01*
G01X331050Y364500D02*
Y367000D01*
X330550Y366500D01*
G01Y364500D02*
X331550D01*
G01X334067D02*
X334150Y365042D01*
X334275Y365500D01*
X334442Y365917D01*
X334650Y366375D01*
X334983Y367000D01*
X333317D01*
G01X336699Y743050D02*
Y747050D01*
X329299D01*
G01X336699Y739050D02*
Y743050D01*
X329299D01*
G01X326699Y748550D02*
Y738550D01*
G01X338500Y758900D02*
X338458Y758567D01*
X338292Y758275D01*
X338042Y758025D01*
X337750Y757858D01*
X337417Y757775D01*
X337083D01*
X336750Y757858D01*
X336458Y758025D01*
X336208Y758275D01*
X336042Y758567D01*
X336000Y758900D01*
X336042Y759233D01*
X336208Y759525D01*
X336458Y759775D01*
X336750Y759942D01*
X337083Y760025D01*
X337417D01*
X337750Y759942D01*
X338042Y759775D01*
X338292Y759525D01*
X338458Y759233D01*
X338500Y758900D01*
G01X337833Y759233D02*
X338500Y759733D01*
G01Y762000D02*
X336000D01*
X336500Y761500D01*
G01X338500D02*
Y762500D01*
G01Y765100D02*
X338458Y765392D01*
X338333Y765725D01*
X338125Y765933D01*
X337833Y766017D01*
X337542Y765933D01*
X337292Y765683D01*
X337167Y765308D01*
Y764892D01*
X337083Y764642D01*
X336875Y764433D01*
X336583Y764350D01*
X336292Y764475D01*
X336083Y764767D01*
X336000Y765100D01*
X336083Y765433D01*
X336292Y765725D01*
X336583Y765850D01*
X336875Y765767D01*
X337083Y765558D01*
X337167Y765308D01*
Y764892D01*
X337292Y764517D01*
X337542Y764267D01*
X337833Y764183D01*
X338125Y764267D01*
X338333Y764475D01*
X338458Y764808D01*
X338500Y765100D01*
G01X325199Y756350D02*
Y769750D01*
G01X334000Y757517D02*
X331500D01*
Y758558D01*
X331625Y758892D01*
X331792Y759100D01*
X332125Y759183D01*
X332458Y759100D01*
X332667Y758850D01*
X332792Y758558D01*
Y757517D01*
G01Y758558D02*
X334000Y759183D01*
G01X331917Y760658D02*
X331667Y760908D01*
X331542Y761200D01*
X331500Y761533D01*
X331583Y761950D01*
X331792Y762242D01*
X332042Y762325D01*
X332292Y762283D01*
X332500Y762117D01*
X332917Y761283D01*
X333208Y760908D01*
X333625Y760658D01*
X334000Y760575D01*
Y762325D01*
G01X331917Y763758D02*
X331667Y764008D01*
X331542Y764300D01*
X331500Y764633D01*
X331583Y765050D01*
X331792Y765342D01*
X332042Y765425D01*
X332292Y765383D01*
X332500Y765217D01*
X332917Y764383D01*
X333208Y764008D01*
X333625Y763758D01*
X334000Y763675D01*
Y765425D01*
G01Y767650D02*
X331500D01*
X332000Y767150D01*
G01X334000D02*
Y768150D01*
G01X330000Y757517D02*
X327500D01*
Y758558D01*
X327625Y758892D01*
X327792Y759100D01*
X328125Y759183D01*
X328458Y759100D01*
X328667Y758850D01*
X328792Y758558D01*
Y757517D01*
G01Y758558D02*
X330000Y759183D01*
G01X327917Y760658D02*
X327667Y760908D01*
X327542Y761200D01*
X327500Y761533D01*
X327583Y761950D01*
X327792Y762242D01*
X328042Y762325D01*
X328292Y762283D01*
X328500Y762117D01*
X328917Y761283D01*
X329208Y760908D01*
X329625Y760658D01*
X330000Y760575D01*
Y762325D01*
G01X327917Y763758D02*
X327667Y764008D01*
X327542Y764300D01*
X327500Y764633D01*
X327583Y765050D01*
X327792Y765342D01*
X328042Y765425D01*
X328292Y765383D01*
X328500Y765217D01*
X328917Y764383D01*
X329208Y764008D01*
X329625Y763758D01*
X330000Y763675D01*
Y765425D01*
G01X327917Y766858D02*
X327667Y767108D01*
X327542Y767400D01*
X327500Y767733D01*
X327583Y768150D01*
X327792Y768442D01*
X328042Y768525D01*
X328292Y768483D01*
X328500Y768317D01*
X328917Y767483D01*
X329208Y767108D01*
X329625Y766858D01*
X330000Y766775D01*
Y768525D01*
G01X315517Y776000D02*
Y778500D01*
X316558D01*
X316892Y778375D01*
X317100Y778208D01*
X317183Y777875D01*
X317100Y777542D01*
X316850Y777333D01*
X316558Y777208D01*
X315517D01*
G01X316558D02*
X317183Y776000D01*
G01X319950D02*
Y778500D01*
X318408Y776708D01*
X320492D01*
G01X322550Y776000D02*
Y778500D01*
X322050Y778000D01*
G01Y776000D02*
X323050D01*
G01X324858Y777042D02*
X325150Y777333D01*
X325400Y777500D01*
X325733Y777583D01*
X326025Y777500D01*
X326233Y777333D01*
X326400Y777083D01*
X326442Y776792D01*
X326400Y776542D01*
X326233Y776292D01*
X325983Y776083D01*
X325692Y776000D01*
X325358Y776083D01*
X325067Y776333D01*
X324900Y776708D01*
X324858Y777125D01*
X324942Y777667D01*
X325067Y777958D01*
X325275Y778250D01*
X325567Y778458D01*
X325858Y778500D01*
X326150Y778417D01*
X326358Y778208D01*
G01X336016Y1553550D02*
Y1556050D01*
X337057D01*
X337391Y1555925D01*
X337599Y1555758D01*
X337682Y1555425D01*
X337599Y1555092D01*
X337349Y1554883D01*
X337057Y1554758D01*
X336016D01*
G01X337057D02*
X337682Y1553550D01*
G01X339949D02*
Y1556050D01*
X339449Y1555550D01*
G01Y1553550D02*
X340449D01*
G01X342341Y1553842D02*
X342632Y1553633D01*
X342966Y1553550D01*
X343299Y1553633D01*
X343591Y1553883D01*
X343799Y1554258D01*
X343882Y1554633D01*
Y1555092D01*
X343799Y1555467D01*
X343591Y1555800D01*
X343341Y1555967D01*
X343049Y1556050D01*
X342716Y1555967D01*
X342466Y1555800D01*
X342299Y1555550D01*
X342216Y1555217D01*
X342299Y1554925D01*
X342507Y1554633D01*
X342757Y1554467D01*
X343049Y1554425D01*
X343382Y1554508D01*
X343632Y1554717D01*
X343882Y1555092D01*
G01X345357Y1555633D02*
X345607Y1555883D01*
X345899Y1556008D01*
X346232Y1556050D01*
X346649Y1555967D01*
X346941Y1555758D01*
X347024Y1555508D01*
X346982Y1555258D01*
X346816Y1555050D01*
X345982Y1554633D01*
X345607Y1554342D01*
X345357Y1553925D01*
X345274Y1553550D01*
X347024D01*
G01X333199Y1551550D02*
Y1555550D01*
X325799D01*
G01X323199Y1562050D02*
Y1552050D01*
G01X328999Y1571450D02*
X328957Y1571117D01*
X328791Y1570825D01*
X328541Y1570575D01*
X328249Y1570408D01*
X327916Y1570325D01*
X327582D01*
X327249Y1570408D01*
X326957Y1570575D01*
X326707Y1570825D01*
X326541Y1571117D01*
X326499Y1571450D01*
X326541Y1571783D01*
X326707Y1572075D01*
X326957Y1572325D01*
X327249Y1572492D01*
X327582Y1572575D01*
X327916D01*
X328249Y1572492D01*
X328541Y1572325D01*
X328791Y1572075D01*
X328957Y1571783D01*
X328999Y1571450D01*
G01X328332Y1571783D02*
X328999Y1572283D01*
G01Y1574550D02*
X326499D01*
X326999Y1574050D01*
G01X328999D02*
Y1575050D01*
G01Y1578150D02*
X326499D01*
X328291Y1576608D01*
Y1578692D01*
G01X324199Y1566850D02*
Y1580250D01*
G01X336016Y1561550D02*
Y1564050D01*
X337057D01*
X337391Y1563925D01*
X337599Y1563758D01*
X337682Y1563425D01*
X337599Y1563092D01*
X337349Y1562883D01*
X337057Y1562758D01*
X336016D01*
G01X337057D02*
X337682Y1561550D01*
G01X339949D02*
Y1564050D01*
X339449Y1563550D01*
G01Y1561550D02*
X340449D01*
G01X342341Y1561842D02*
X342632Y1561633D01*
X342966Y1561550D01*
X343299Y1561633D01*
X343591Y1561883D01*
X343799Y1562258D01*
X343882Y1562633D01*
Y1563092D01*
X343799Y1563467D01*
X343591Y1563800D01*
X343341Y1563967D01*
X343049Y1564050D01*
X342716Y1563967D01*
X342466Y1563800D01*
X342299Y1563550D01*
X342216Y1563217D01*
X342299Y1562925D01*
X342507Y1562633D01*
X342757Y1562467D01*
X343049Y1562425D01*
X343382Y1562508D01*
X343632Y1562717D01*
X343882Y1563092D01*
G01X345357Y1562592D02*
X345649Y1562883D01*
X345899Y1563050D01*
X346232Y1563133D01*
X346524Y1563050D01*
X346732Y1562883D01*
X346899Y1562633D01*
X346941Y1562342D01*
X346899Y1562092D01*
X346732Y1561842D01*
X346482Y1561633D01*
X346191Y1561550D01*
X345857Y1561633D01*
X345566Y1561883D01*
X345399Y1562258D01*
X345357Y1562675D01*
X345441Y1563217D01*
X345566Y1563508D01*
X345774Y1563800D01*
X346066Y1564008D01*
X346357Y1564050D01*
X346649Y1563967D01*
X346857Y1563758D01*
G01X336016Y1557550D02*
Y1560050D01*
X337057D01*
X337391Y1559925D01*
X337599Y1559758D01*
X337682Y1559425D01*
X337599Y1559092D01*
X337349Y1558883D01*
X337057Y1558758D01*
X336016D01*
G01X337057D02*
X337682Y1557550D01*
G01X339949D02*
Y1560050D01*
X339449Y1559550D01*
G01Y1557550D02*
X340449D01*
G01X342341Y1557842D02*
X342632Y1557633D01*
X342966Y1557550D01*
X343299Y1557633D01*
X343591Y1557883D01*
X343799Y1558258D01*
X343882Y1558633D01*
Y1559092D01*
X343799Y1559467D01*
X343591Y1559800D01*
X343341Y1559967D01*
X343049Y1560050D01*
X342716Y1559967D01*
X342466Y1559800D01*
X342299Y1559550D01*
X342216Y1559217D01*
X342299Y1558925D01*
X342507Y1558633D01*
X342757Y1558467D01*
X343049Y1558425D01*
X343382Y1558508D01*
X343632Y1558717D01*
X343882Y1559092D01*
G01X346066Y1557550D02*
X346149Y1558092D01*
X346274Y1558550D01*
X346441Y1558967D01*
X346649Y1559425D01*
X346982Y1560050D01*
X345316D01*
G01X333199Y1555550D02*
Y1559550D01*
X325799D01*
G01X320517Y1587000D02*
Y1589500D01*
X321558D01*
X321892Y1589375D01*
X322100Y1589208D01*
X322183Y1588875D01*
X322100Y1588542D01*
X321850Y1588333D01*
X321558Y1588208D01*
X320517D01*
G01X321558D02*
X322183Y1587000D01*
G01X324950D02*
Y1589500D01*
X323408Y1587708D01*
X325492D01*
G01X327550Y1587000D02*
Y1589500D01*
X327050Y1589000D01*
G01Y1587000D02*
X328050D01*
G01X331150D02*
Y1589500D01*
X329608Y1587708D01*
X331692D01*
G01X333917Y1922500D02*
Y1927500D01*
X337083D01*
G01X335917Y1925083D02*
X333917D01*
G01X341100Y1922500D02*
Y1927500D01*
X340100Y1926500D01*
G01Y1922500D02*
X342100D01*
G01X345117Y1926667D02*
X345617Y1927167D01*
X346200Y1927417D01*
X346867Y1927500D01*
X347700Y1927333D01*
X348283Y1926917D01*
X348450Y1926417D01*
X348367Y1925917D01*
X348033Y1925500D01*
X346367Y1924667D01*
X345617Y1924083D01*
X345117Y1923250D01*
X344950Y1922500D01*
X348450D01*
G01X352300Y1922333D02*
X352133Y1922417D01*
Y1922583D01*
X352300Y1922667D01*
X352467Y1922583D01*
Y1922417D01*
X352300Y1922333D01*
G01Y1924583D02*
X352133Y1924667D01*
Y1924833D01*
X352300Y1924917D01*
X352467Y1924833D01*
Y1924667D01*
X352300Y1924583D01*
G01X356067Y1923500D02*
X356567Y1922917D01*
X357233Y1922583D01*
X357983Y1922500D01*
X358650Y1922583D01*
X359317Y1923000D01*
X359733Y1923500D01*
X359817Y1924000D01*
X359650Y1924583D01*
X359067Y1925000D01*
X358483Y1925167D01*
X357733D01*
G01X358483D02*
X358983Y1925417D01*
X359400Y1925833D01*
X359567Y1926333D01*
X359400Y1926833D01*
X358983Y1927250D01*
X358233Y1927500D01*
X357483Y1927417D01*
X356733Y1927083D01*
G01X361417Y1922500D02*
X363500Y1927500D01*
X365583Y1922500D01*
G01X364833Y1924250D02*
X362167D01*
G01X367600Y1922333D02*
X370600Y1927500D01*
G01X374700Y1922500D02*
Y1927500D01*
X373700Y1926500D01*
G01Y1922500D02*
X375700D01*
G01X378467Y1923250D02*
X378967Y1922833D01*
X379550Y1922583D01*
X380300Y1922500D01*
X381050Y1922667D01*
X381633Y1923000D01*
X382050Y1923583D01*
X382133Y1924250D01*
X381967Y1924917D01*
X381550Y1925333D01*
X380967Y1925667D01*
X380383Y1925750D01*
X379800Y1925667D01*
X379050Y1925333D01*
X379300Y1927500D01*
X381550D01*
G01X383817D02*
X385900Y1922500D01*
X387983Y1927500D01*
G01X326044Y1936381D02*
Y1934589D01*
X326211Y1934214D01*
X326544Y1933964D01*
X326961Y1933881D01*
X327378Y1933964D01*
X327711Y1934214D01*
X327878Y1934589D01*
Y1936381D01*
G01X330061Y1933881D02*
Y1936381D01*
X329561Y1935881D01*
G01Y1933881D02*
X330561D01*
G01X333161D02*
X333453Y1933923D01*
X333786Y1934048D01*
X333994Y1934256D01*
X334078Y1934548D01*
X333994Y1934839D01*
X333744Y1935089D01*
X333369Y1935214D01*
X332953D01*
X332703Y1935298D01*
X332494Y1935506D01*
X332411Y1935798D01*
X332536Y1936089D01*
X332828Y1936298D01*
X333161Y1936381D01*
X333494Y1936298D01*
X333786Y1936089D01*
X333911Y1935798D01*
X333828Y1935506D01*
X333619Y1935298D01*
X333369Y1935214D01*
X332953D01*
X332578Y1935089D01*
X332328Y1934839D01*
X332244Y1934548D01*
X332328Y1934256D01*
X332536Y1934048D01*
X332869Y1933923D01*
X333161Y1933881D01*
G01X341421Y1945409D02*
Y1949409D01*
X334021D01*
G01X341421Y1941409D02*
Y1945409D01*
X334021D01*
G01X317021Y1951909D02*
X330421D01*
G01X317021Y1941909D02*
Y1951909D01*
G01X330421Y1941909D02*
X317021D01*
G01X330421Y1951909D02*
Y1941909D01*
G01X315940Y1956072D02*
X327340D01*
G01X315940Y1969472D02*
Y1956072D01*
G01X327340Y1969472D02*
X315940D01*
G01X327340Y1956072D02*
Y1969472D01*
G01X335017Y1961000D02*
Y1963500D01*
X336058D01*
X336392Y1963375D01*
X336600Y1963208D01*
X336683Y1962875D01*
X336600Y1962542D01*
X336350Y1962333D01*
X336058Y1962208D01*
X335017D01*
G01X336058D02*
X336683Y1961000D01*
G01X338950D02*
Y1963500D01*
X338450Y1963000D01*
G01Y1961000D02*
X339450D01*
G01X341967D02*
X342050Y1961542D01*
X342175Y1962000D01*
X342342Y1962417D01*
X342550Y1962875D01*
X342883Y1963500D01*
X341217D01*
G01X344442Y1961292D02*
X344733Y1961083D01*
X345067Y1961000D01*
X345400Y1961083D01*
X345692Y1961333D01*
X345900Y1961708D01*
X345983Y1962083D01*
Y1962542D01*
X345900Y1962917D01*
X345692Y1963250D01*
X345442Y1963417D01*
X345150Y1963500D01*
X344817Y1963417D01*
X344567Y1963250D01*
X344400Y1963000D01*
X344317Y1962667D01*
X344400Y1962375D01*
X344608Y1962083D01*
X344858Y1961917D01*
X345150Y1961875D01*
X345483Y1961958D01*
X345733Y1962167D01*
X345983Y1962542D01*
G01X335017Y1977000D02*
Y1979500D01*
X336058D01*
X336392Y1979375D01*
X336600Y1979208D01*
X336683Y1978875D01*
X336600Y1978542D01*
X336350Y1978333D01*
X336058Y1978208D01*
X335017D01*
G01X336058D02*
X336683Y1977000D01*
G01X338950D02*
Y1979500D01*
X338450Y1979000D01*
G01Y1977000D02*
X339450D01*
G01X342050D02*
X342342Y1977042D01*
X342675Y1977167D01*
X342883Y1977375D01*
X342967Y1977667D01*
X342883Y1977958D01*
X342633Y1978208D01*
X342258Y1978333D01*
X341842D01*
X341592Y1978417D01*
X341383Y1978625D01*
X341300Y1978917D01*
X341425Y1979208D01*
X341717Y1979417D01*
X342050Y1979500D01*
X342383Y1979417D01*
X342675Y1979208D01*
X342800Y1978917D01*
X342717Y1978625D01*
X342508Y1978417D01*
X342258Y1978333D01*
X341842D01*
X341467Y1978208D01*
X341217Y1977958D01*
X341133Y1977667D01*
X341217Y1977375D01*
X341425Y1977167D01*
X341758Y1977042D01*
X342050Y1977000D01*
G01X345150Y1979500D02*
X344817Y1979417D01*
X344567Y1979208D01*
X344400Y1978958D01*
X344275Y1978625D01*
X344233Y1978250D01*
X344275Y1977875D01*
X344400Y1977542D01*
X344567Y1977292D01*
X344817Y1977083D01*
X345150Y1977000D01*
X345483Y1977083D01*
X345733Y1977292D01*
X345900Y1977542D01*
X346025Y1977875D01*
X346067Y1978250D01*
X346025Y1978625D01*
X345900Y1978958D01*
X345733Y1979208D01*
X345483Y1979417D01*
X345150Y1979500D01*
G01X335017Y1973000D02*
Y1975500D01*
X336058D01*
X336392Y1975375D01*
X336600Y1975208D01*
X336683Y1974875D01*
X336600Y1974542D01*
X336350Y1974333D01*
X336058Y1974208D01*
X335017D01*
G01X336058D02*
X336683Y1973000D01*
G01X338950D02*
Y1975500D01*
X338450Y1975000D01*
G01Y1973000D02*
X339450D01*
G01X342050D02*
X342342Y1973042D01*
X342675Y1973167D01*
X342883Y1973375D01*
X342967Y1973667D01*
X342883Y1973958D01*
X342633Y1974208D01*
X342258Y1974333D01*
X341842D01*
X341592Y1974417D01*
X341383Y1974625D01*
X341300Y1974917D01*
X341425Y1975208D01*
X341717Y1975417D01*
X342050Y1975500D01*
X342383Y1975417D01*
X342675Y1975208D01*
X342800Y1974917D01*
X342717Y1974625D01*
X342508Y1974417D01*
X342258Y1974333D01*
X341842D01*
X341467Y1974208D01*
X341217Y1973958D01*
X341133Y1973667D01*
X341217Y1973375D01*
X341425Y1973167D01*
X341758Y1973042D01*
X342050Y1973000D01*
G01X345150D02*
Y1975500D01*
X344650Y1975000D01*
G01Y1973000D02*
X345650D01*
G01X335017Y1969000D02*
Y1971500D01*
X336058D01*
X336392Y1971375D01*
X336600Y1971208D01*
X336683Y1970875D01*
X336600Y1970542D01*
X336350Y1970333D01*
X336058Y1970208D01*
X335017D01*
G01X336058D02*
X336683Y1969000D01*
G01X338950D02*
Y1971500D01*
X338450Y1971000D01*
G01Y1969000D02*
X339450D01*
G01X342050D02*
X342342Y1969042D01*
X342675Y1969167D01*
X342883Y1969375D01*
X342967Y1969667D01*
X342883Y1969958D01*
X342633Y1970208D01*
X342258Y1970333D01*
X341842D01*
X341592Y1970417D01*
X341383Y1970625D01*
X341300Y1970917D01*
X341425Y1971208D01*
X341717Y1971417D01*
X342050Y1971500D01*
X342383Y1971417D01*
X342675Y1971208D01*
X342800Y1970917D01*
X342717Y1970625D01*
X342508Y1970417D01*
X342258Y1970333D01*
X341842D01*
X341467Y1970208D01*
X341217Y1969958D01*
X341133Y1969667D01*
X341217Y1969375D01*
X341425Y1969167D01*
X341758Y1969042D01*
X342050Y1969000D01*
G01X344358Y1971083D02*
X344608Y1971333D01*
X344900Y1971458D01*
X345233Y1971500D01*
X345650Y1971417D01*
X345942Y1971208D01*
X346025Y1970958D01*
X345983Y1970708D01*
X345817Y1970500D01*
X344983Y1970083D01*
X344608Y1969792D01*
X344358Y1969375D01*
X344275Y1969000D01*
X346025D01*
G01X335017Y1965000D02*
Y1967500D01*
X336058D01*
X336392Y1967375D01*
X336600Y1967208D01*
X336683Y1966875D01*
X336600Y1966542D01*
X336350Y1966333D01*
X336058Y1966208D01*
X335017D01*
G01X336058D02*
X336683Y1965000D01*
G01X338950D02*
Y1967500D01*
X338450Y1967000D01*
G01Y1965000D02*
X339450D01*
G01X342050D02*
X342342Y1965042D01*
X342675Y1965167D01*
X342883Y1965375D01*
X342967Y1965667D01*
X342883Y1965958D01*
X342633Y1966208D01*
X342258Y1966333D01*
X341842D01*
X341592Y1966417D01*
X341383Y1966625D01*
X341300Y1966917D01*
X341425Y1967208D01*
X341717Y1967417D01*
X342050Y1967500D01*
X342383Y1967417D01*
X342675Y1967208D01*
X342800Y1966917D01*
X342717Y1966625D01*
X342508Y1966417D01*
X342258Y1966333D01*
X341842D01*
X341467Y1966208D01*
X341217Y1965958D01*
X341133Y1965667D01*
X341217Y1965375D01*
X341425Y1965167D01*
X341758Y1965042D01*
X342050Y1965000D01*
G01X344233Y1965500D02*
X344483Y1965208D01*
X344817Y1965042D01*
X345192Y1965000D01*
X345525Y1965042D01*
X345858Y1965250D01*
X346067Y1965500D01*
X346108Y1965750D01*
X346025Y1966042D01*
X345733Y1966250D01*
X345442Y1966333D01*
X345067D01*
G01X345442D02*
X345692Y1966458D01*
X345900Y1966667D01*
X345983Y1966917D01*
X345900Y1967167D01*
X345692Y1967375D01*
X345317Y1967500D01*
X344942Y1967458D01*
X344567Y1967292D01*
G01X323600Y1969900D02*
Y1973900D01*
X316200D01*
G01X350999Y57450D02*
Y18650D01*
G01X357017Y45500D02*
Y48000D01*
X358058D01*
X358392Y47875D01*
X358600Y47708D01*
X358683Y47375D01*
X358600Y47042D01*
X358350Y46833D01*
X358058Y46708D01*
X357017D01*
G01X358058D02*
X358683Y45500D01*
G01X361450D02*
Y48000D01*
X359908Y46208D01*
X361992D01*
G01X364050Y45500D02*
X364342Y45542D01*
X364675Y45667D01*
X364883Y45875D01*
X364967Y46167D01*
X364883Y46458D01*
X364633Y46708D01*
X364258Y46833D01*
X363842D01*
X363592Y46917D01*
X363383Y47125D01*
X363300Y47417D01*
X363425Y47708D01*
X363717Y47917D01*
X364050Y48000D01*
X364383Y47917D01*
X364675Y47708D01*
X364800Y47417D01*
X364717Y47125D01*
X364508Y46917D01*
X364258Y46833D01*
X363842D01*
X363467Y46708D01*
X363217Y46458D01*
X363133Y46167D01*
X363217Y45875D01*
X363425Y45667D01*
X363758Y45542D01*
X364050Y45500D01*
G01X367150Y48000D02*
X366817Y47917D01*
X366567Y47708D01*
X366400Y47458D01*
X366275Y47125D01*
X366233Y46750D01*
X366275Y46375D01*
X366400Y46042D01*
X366567Y45792D01*
X366817Y45583D01*
X367150Y45500D01*
X367483Y45583D01*
X367733Y45792D01*
X367900Y46042D01*
X368025Y46375D01*
X368067Y46750D01*
X368025Y47125D01*
X367900Y47458D01*
X367733Y47708D01*
X367483Y47917D01*
X367150Y48000D01*
G01X356933Y44000D02*
Y42208D01*
X357100Y41833D01*
X357433Y41583D01*
X357850Y41500D01*
X358267Y41583D01*
X358600Y41833D01*
X358767Y42208D01*
Y44000D01*
G01X361450Y41500D02*
Y44000D01*
X359908Y42208D01*
X361992D01*
G01X364550Y41500D02*
Y44000D01*
X363008Y42208D01*
X365092D01*
G01X357699Y59550D02*
X344299D01*
G01Y69550D02*
X357699D01*
G01X344299Y59550D02*
Y69550D01*
G01X342799Y98550D02*
X344899Y96750D01*
X342799Y94550D01*
G01X342699Y90950D02*
X361899D01*
Y102150D01*
X342699D01*
Y90950D01*
X343099D01*
G01X337515Y336114D02*
Y338614D01*
X338556D01*
X338890Y338489D01*
X339098Y338322D01*
X339181Y337989D01*
X339098Y337656D01*
X338848Y337447D01*
X338556Y337322D01*
X337515D01*
G01X338556D02*
X339181Y336114D01*
G01X341948D02*
Y338614D01*
X340406Y336822D01*
X342490D01*
G01X343631Y336489D02*
X343881Y336281D01*
X344173Y336156D01*
X344548Y336114D01*
X344923Y336197D01*
X345215Y336364D01*
X345423Y336656D01*
X345465Y336989D01*
X345381Y337322D01*
X345173Y337531D01*
X344881Y337697D01*
X344590Y337739D01*
X344298Y337697D01*
X343923Y337531D01*
X344048Y338614D01*
X345173D01*
G01X347648Y336114D02*
X347940Y336156D01*
X348273Y336281D01*
X348481Y336489D01*
X348565Y336781D01*
X348481Y337072D01*
X348231Y337322D01*
X347856Y337447D01*
X347440D01*
X347190Y337531D01*
X346981Y337739D01*
X346898Y338031D01*
X347023Y338322D01*
X347315Y338531D01*
X347648Y338614D01*
X347981Y338531D01*
X348273Y338322D01*
X348398Y338031D01*
X348315Y337739D01*
X348106Y337531D01*
X347856Y337447D01*
X347440D01*
X347065Y337322D01*
X346815Y337072D01*
X346731Y336781D01*
X346815Y336489D01*
X347023Y336281D01*
X347356Y336156D01*
X347648Y336114D01*
G01X337515Y332114D02*
Y334614D01*
X338556D01*
X338890Y334489D01*
X339098Y334322D01*
X339181Y333989D01*
X339098Y333656D01*
X338848Y333447D01*
X338556Y333322D01*
X337515D01*
G01X338556D02*
X339181Y332114D01*
G01X341948D02*
Y334614D01*
X340406Y332822D01*
X342490D01*
G01X343631Y332489D02*
X343881Y332281D01*
X344173Y332156D01*
X344548Y332114D01*
X344923Y332197D01*
X345215Y332364D01*
X345423Y332656D01*
X345465Y332989D01*
X345381Y333322D01*
X345173Y333531D01*
X344881Y333697D01*
X344590Y333739D01*
X344298Y333697D01*
X343923Y333531D01*
X344048Y334614D01*
X345173D01*
G01X346940Y332406D02*
X347231Y332197D01*
X347565Y332114D01*
X347898Y332197D01*
X348190Y332447D01*
X348398Y332822D01*
X348481Y333197D01*
Y333656D01*
X348398Y334031D01*
X348190Y334364D01*
X347940Y334531D01*
X347648Y334614D01*
X347315Y334531D01*
X347065Y334364D01*
X346898Y334114D01*
X346815Y333781D01*
X346898Y333489D01*
X347106Y333197D01*
X347356Y333031D01*
X347648Y332989D01*
X347981Y333072D01*
X348231Y333281D01*
X348481Y333656D01*
G01X338517Y737500D02*
Y740000D01*
X339558D01*
X339892Y739875D01*
X340100Y739708D01*
X340183Y739375D01*
X340100Y739042D01*
X339850Y738833D01*
X339558Y738708D01*
X338517D01*
G01X339558D02*
X340183Y737500D01*
G01X341658Y739583D02*
X341908Y739833D01*
X342200Y739958D01*
X342533Y740000D01*
X342950Y739917D01*
X343242Y739708D01*
X343325Y739458D01*
X343283Y739208D01*
X343117Y739000D01*
X342283Y738583D01*
X341908Y738292D01*
X341658Y737875D01*
X341575Y737500D01*
X343325D01*
G01X344758Y739583D02*
X345008Y739833D01*
X345300Y739958D01*
X345633Y740000D01*
X346050Y739917D01*
X346342Y739708D01*
X346425Y739458D01*
X346383Y739208D01*
X346217Y739000D01*
X345383Y738583D01*
X345008Y738292D01*
X344758Y737875D01*
X344675Y737500D01*
X346425D01*
G01X348650Y740000D02*
X348317Y739917D01*
X348067Y739708D01*
X347900Y739458D01*
X347775Y739125D01*
X347733Y738750D01*
X347775Y738375D01*
X347900Y738042D01*
X348067Y737792D01*
X348317Y737583D01*
X348650Y737500D01*
X348983Y737583D01*
X349233Y737792D01*
X349400Y738042D01*
X349525Y738375D01*
X349567Y738750D01*
X349525Y739125D01*
X349400Y739458D01*
X349233Y739708D01*
X348983Y739917D01*
X348650Y740000D01*
G01X338517Y745500D02*
Y748000D01*
X339558D01*
X339892Y747875D01*
X340100Y747708D01*
X340183Y747375D01*
X340100Y747042D01*
X339850Y746833D01*
X339558Y746708D01*
X338517D01*
G01X339558D02*
X340183Y745500D01*
G01X341658Y747583D02*
X341908Y747833D01*
X342200Y747958D01*
X342533Y748000D01*
X342950Y747917D01*
X343242Y747708D01*
X343325Y747458D01*
X343283Y747208D01*
X343117Y747000D01*
X342283Y746583D01*
X341908Y746292D01*
X341658Y745875D01*
X341575Y745500D01*
X343325D01*
G01X344758Y747583D02*
X345008Y747833D01*
X345300Y747958D01*
X345633Y748000D01*
X346050Y747917D01*
X346342Y747708D01*
X346425Y747458D01*
X346383Y747208D01*
X346217Y747000D01*
X345383Y746583D01*
X345008Y746292D01*
X344758Y745875D01*
X344675Y745500D01*
X346425D01*
G01X349150D02*
Y748000D01*
X347608Y746208D01*
X349692D01*
G01X338517Y741500D02*
Y744000D01*
X339558D01*
X339892Y743875D01*
X340100Y743708D01*
X340183Y743375D01*
X340100Y743042D01*
X339850Y742833D01*
X339558Y742708D01*
X338517D01*
G01X339558D02*
X340183Y741500D01*
G01X341658Y743583D02*
X341908Y743833D01*
X342200Y743958D01*
X342533Y744000D01*
X342950Y743917D01*
X343242Y743708D01*
X343325Y743458D01*
X343283Y743208D01*
X343117Y743000D01*
X342283Y742583D01*
X341908Y742292D01*
X341658Y741875D01*
X341575Y741500D01*
X343325D01*
G01X344758Y743583D02*
X345008Y743833D01*
X345300Y743958D01*
X345633Y744000D01*
X346050Y743917D01*
X346342Y743708D01*
X346425Y743458D01*
X346383Y743208D01*
X346217Y743000D01*
X345383Y742583D01*
X345008Y742292D01*
X344758Y741875D01*
X344675Y741500D01*
X346425D01*
G01X347733Y741875D02*
X347983Y741667D01*
X348275Y741542D01*
X348650Y741500D01*
X349025Y741583D01*
X349317Y741750D01*
X349525Y742042D01*
X349567Y742375D01*
X349483Y742708D01*
X349275Y742917D01*
X348983Y743083D01*
X348692Y743125D01*
X348400Y743083D01*
X348025Y742917D01*
X348150Y744000D01*
X349275D01*
G01X357516Y743550D02*
Y746050D01*
X358557D01*
X358891Y745925D01*
X359099Y745758D01*
X359182Y745425D01*
X359099Y745092D01*
X358849Y744883D01*
X358557Y744758D01*
X357516D01*
G01X358557D02*
X359182Y743550D01*
G01X361949D02*
Y746050D01*
X360407Y744258D01*
X362491D01*
G01X363632Y743925D02*
X363882Y743717D01*
X364174Y743592D01*
X364549Y743550D01*
X364924Y743633D01*
X365216Y743800D01*
X365424Y744092D01*
X365466Y744425D01*
X365382Y744758D01*
X365174Y744967D01*
X364882Y745133D01*
X364591Y745175D01*
X364299Y745133D01*
X363924Y744967D01*
X364049Y746050D01*
X365174D01*
G01X368149Y743550D02*
Y746050D01*
X366607Y744258D01*
X368691D01*
G01X357516Y739550D02*
Y742050D01*
X358557D01*
X358891Y741925D01*
X359099Y741758D01*
X359182Y741425D01*
X359099Y741092D01*
X358849Y740883D01*
X358557Y740758D01*
X357516D01*
G01X358557D02*
X359182Y739550D01*
G01X361949D02*
Y742050D01*
X360407Y740258D01*
X362491D01*
G01X363632Y739925D02*
X363882Y739717D01*
X364174Y739592D01*
X364549Y739550D01*
X364924Y739633D01*
X365216Y739800D01*
X365424Y740092D01*
X365466Y740425D01*
X365382Y740758D01*
X365174Y740967D01*
X364882Y741133D01*
X364591Y741175D01*
X364299Y741133D01*
X363924Y740967D01*
X364049Y742050D01*
X365174D01*
G01X366732Y739925D02*
X366982Y739717D01*
X367274Y739592D01*
X367649Y739550D01*
X368024Y739633D01*
X368316Y739800D01*
X368524Y740092D01*
X368566Y740425D01*
X368482Y740758D01*
X368274Y740967D01*
X367982Y741133D01*
X367691Y741175D01*
X367399Y741133D01*
X367024Y740967D01*
X367149Y742050D01*
X368274D01*
G01X352000Y738983D02*
X353792D01*
X354167Y739150D01*
X354417Y739483D01*
X354500Y739900D01*
X354417Y740317D01*
X354167Y740650D01*
X353792Y740817D01*
X352000D01*
G01X352417Y742208D02*
X352167Y742458D01*
X352042Y742750D01*
X352000Y743083D01*
X352083Y743500D01*
X352292Y743792D01*
X352542Y743875D01*
X352792Y743833D01*
X353000Y743667D01*
X353417Y742833D01*
X353708Y742458D01*
X354125Y742208D01*
X354500Y742125D01*
Y743875D01*
G01Y746017D02*
X353958Y746100D01*
X353500Y746225D01*
X353083Y746392D01*
X352625Y746600D01*
X352000Y746933D01*
Y745267D01*
G01X353016Y1554050D02*
Y1556550D01*
X354057D01*
X354391Y1556425D01*
X354599Y1556258D01*
X354682Y1555925D01*
X354599Y1555592D01*
X354349Y1555383D01*
X354057Y1555258D01*
X353016D01*
G01X354057D02*
X354682Y1554050D01*
G01X357449D02*
Y1556550D01*
X355907Y1554758D01*
X357991D01*
G01X360549Y1554050D02*
Y1556550D01*
X359007Y1554758D01*
X361091D01*
G01X362441Y1554342D02*
X362732Y1554133D01*
X363066Y1554050D01*
X363399Y1554133D01*
X363691Y1554383D01*
X363899Y1554758D01*
X363982Y1555133D01*
Y1555592D01*
X363899Y1555967D01*
X363691Y1556300D01*
X363441Y1556467D01*
X363149Y1556550D01*
X362816Y1556467D01*
X362566Y1556300D01*
X362399Y1556050D01*
X362316Y1555717D01*
X362399Y1555425D01*
X362607Y1555133D01*
X362857Y1554967D01*
X363149Y1554925D01*
X363482Y1555008D01*
X363732Y1555217D01*
X363982Y1555592D01*
G01X348499Y1553533D02*
X350291D01*
X350666Y1553700D01*
X350916Y1554033D01*
X350999Y1554450D01*
X350916Y1554867D01*
X350666Y1555200D01*
X350291Y1555367D01*
X348499D01*
G01X348916Y1556758D02*
X348666Y1557008D01*
X348541Y1557300D01*
X348499Y1557633D01*
X348582Y1558050D01*
X348791Y1558342D01*
X349041Y1558425D01*
X349291Y1558383D01*
X349499Y1558217D01*
X349916Y1557383D01*
X350207Y1557008D01*
X350624Y1556758D01*
X350999Y1556675D01*
Y1558425D01*
G01Y1560650D02*
X348499D01*
X348999Y1560150D01*
G01X350999D02*
Y1561150D01*
G01X353016Y1558050D02*
Y1560550D01*
X354057D01*
X354391Y1560425D01*
X354599Y1560258D01*
X354682Y1559925D01*
X354599Y1559592D01*
X354349Y1559383D01*
X354057Y1559258D01*
X353016D01*
G01X354057D02*
X354682Y1558050D01*
G01X357449D02*
Y1560550D01*
X355907Y1558758D01*
X357991D01*
G01X360549Y1558050D02*
Y1560550D01*
X359007Y1558758D01*
X361091D01*
G01X363149Y1558050D02*
X363441Y1558092D01*
X363774Y1558217D01*
X363982Y1558425D01*
X364066Y1558717D01*
X363982Y1559008D01*
X363732Y1559258D01*
X363357Y1559383D01*
X362941D01*
X362691Y1559467D01*
X362482Y1559675D01*
X362399Y1559967D01*
X362524Y1560258D01*
X362816Y1560467D01*
X363149Y1560550D01*
X363482Y1560467D01*
X363774Y1560258D01*
X363899Y1559967D01*
X363816Y1559675D01*
X363607Y1559467D01*
X363357Y1559383D01*
X362941D01*
X362566Y1559258D01*
X362316Y1559008D01*
X362232Y1558717D01*
X362316Y1558425D01*
X362524Y1558217D01*
X362857Y1558092D01*
X363149Y1558050D01*
G01X343516Y1946550D02*
Y1949050D01*
X344557D01*
X344891Y1948925D01*
X345099Y1948758D01*
X345182Y1948425D01*
X345099Y1948092D01*
X344849Y1947883D01*
X344557Y1947758D01*
X343516D01*
G01X344557D02*
X345182Y1946550D01*
G01X347949D02*
Y1949050D01*
X346407Y1947258D01*
X348491D01*
G01X351049Y1946550D02*
Y1949050D01*
X349507Y1947258D01*
X351591D01*
G01X354149Y1946550D02*
Y1949050D01*
X352607Y1947258D01*
X354691D01*
G01X343516Y1942050D02*
Y1944550D01*
X344557D01*
X344891Y1944425D01*
X345099Y1944258D01*
X345182Y1943925D01*
X345099Y1943592D01*
X344849Y1943383D01*
X344557Y1943258D01*
X343516D01*
G01X344557D02*
X345182Y1942050D01*
G01X347949D02*
Y1944550D01*
X346407Y1942758D01*
X348491D01*
G01X351049Y1942050D02*
Y1944550D01*
X349507Y1942758D01*
X351591D01*
G01X352732Y1942425D02*
X352982Y1942217D01*
X353274Y1942092D01*
X353649Y1942050D01*
X354024Y1942133D01*
X354316Y1942300D01*
X354524Y1942592D01*
X354566Y1942925D01*
X354482Y1943258D01*
X354274Y1943467D01*
X353982Y1943633D01*
X353691Y1943675D01*
X353399Y1943633D01*
X353024Y1943467D01*
X353149Y1944550D01*
X354274D01*
G01X351000Y1962900D02*
X350958Y1962567D01*
X350792Y1962275D01*
X350542Y1962025D01*
X350250Y1961858D01*
X349917Y1961775D01*
X349583D01*
X349250Y1961858D01*
X348958Y1962025D01*
X348708Y1962275D01*
X348542Y1962567D01*
X348500Y1962900D01*
X348542Y1963233D01*
X348708Y1963525D01*
X348958Y1963775D01*
X349250Y1963942D01*
X349583Y1964025D01*
X349917D01*
X350250Y1963942D01*
X350542Y1963775D01*
X350792Y1963525D01*
X350958Y1963233D01*
X351000Y1962900D01*
G01X350333Y1963233D02*
X351000Y1963733D01*
G01Y1966000D02*
X348500D01*
X349000Y1965500D01*
G01X351000D02*
Y1966500D01*
G01X348917Y1968308D02*
X348667Y1968558D01*
X348542Y1968850D01*
X348500Y1969183D01*
X348583Y1969600D01*
X348792Y1969892D01*
X349042Y1969975D01*
X349292Y1969933D01*
X349500Y1969767D01*
X349917Y1968933D01*
X350208Y1968558D01*
X350625Y1968308D01*
X351000Y1968225D01*
Y1969975D01*
G01X349517Y1974500D02*
Y1977000D01*
X350558D01*
X350892Y1976875D01*
X351100Y1976708D01*
X351183Y1976375D01*
X351100Y1976042D01*
X350850Y1975833D01*
X350558Y1975708D01*
X349517D01*
G01X350558D02*
X351183Y1974500D01*
G01X353950D02*
Y1977000D01*
X352408Y1975208D01*
X354492D01*
G01X356550Y1974500D02*
Y1977000D01*
X356050Y1976500D01*
G01Y1974500D02*
X357050D01*
G01X358733Y1975000D02*
X358983Y1974708D01*
X359317Y1974542D01*
X359692Y1974500D01*
X360025Y1974542D01*
X360358Y1974750D01*
X360567Y1975000D01*
X360608Y1975250D01*
X360525Y1975542D01*
X360233Y1975750D01*
X359942Y1975833D01*
X359567D01*
G01X359942D02*
X360192Y1975958D01*
X360400Y1976167D01*
X360483Y1976417D01*
X360400Y1976667D01*
X360192Y1976875D01*
X359817Y1977000D01*
X359442Y1976958D01*
X359067Y1976792D01*
G01X364499Y18250D02*
X366499Y20250D01*
X368499Y18250D01*
G01X372099D02*
Y37450D01*
X360899D01*
Y18250D01*
X372099D01*
G01X361016Y51550D02*
Y54050D01*
X362057D01*
X362391Y53925D01*
X362599Y53758D01*
X362682Y53425D01*
X362599Y53092D01*
X362349Y52883D01*
X362057Y52758D01*
X361016D01*
G01X362057D02*
X362682Y51550D01*
G01X365449D02*
Y54050D01*
X363907Y52258D01*
X365991D01*
G01X367966Y51550D02*
X368049Y52092D01*
X368174Y52550D01*
X368341Y52967D01*
X368549Y53425D01*
X368882Y54050D01*
X367216D01*
G01X370357Y52592D02*
X370649Y52883D01*
X370899Y53050D01*
X371232Y53133D01*
X371524Y53050D01*
X371732Y52883D01*
X371899Y52633D01*
X371941Y52342D01*
X371899Y52092D01*
X371732Y51842D01*
X371482Y51633D01*
X371191Y51550D01*
X370857Y51633D01*
X370566Y51883D01*
X370399Y52258D01*
X370357Y52675D01*
X370441Y53217D01*
X370566Y53508D01*
X370774Y53800D01*
X371066Y54008D01*
X371357Y54050D01*
X371649Y53967D01*
X371857Y53758D01*
G01X373299Y55050D02*
Y51050D01*
X380699D01*
G01X380800Y40300D02*
Y44300D01*
X373400D01*
G01X372708Y69267D02*
X372583Y69017D01*
X372500Y68725D01*
Y68392D01*
X372625Y68017D01*
X372833Y67725D01*
X373083Y67517D01*
X373500Y67350D01*
X373875Y67308D01*
X374250Y67392D01*
X374500Y67517D01*
X374750Y67767D01*
X374917Y68058D01*
X375000Y68350D01*
Y68642D01*
X374917Y68933D01*
X374792Y69183D01*
X374625Y69392D01*
G01X374500Y70533D02*
X374792Y70783D01*
X374958Y71117D01*
X375000Y71492D01*
X374958Y71825D01*
X374750Y72158D01*
X374500Y72367D01*
X374250Y72408D01*
X373958Y72325D01*
X373750Y72033D01*
X373667Y71742D01*
Y71367D01*
G01Y71742D02*
X373542Y71992D01*
X373333Y72200D01*
X373083Y72283D01*
X372833Y72200D01*
X372625Y71992D01*
X372500Y71617D01*
X372542Y71242D01*
X372708Y70867D01*
G01X372917Y73758D02*
X372667Y74008D01*
X372542Y74300D01*
X372500Y74633D01*
X372583Y75050D01*
X372792Y75342D01*
X373042Y75425D01*
X373292Y75383D01*
X373500Y75217D01*
X373917Y74383D01*
X374208Y74008D01*
X374625Y73758D01*
X375000Y73675D01*
Y75425D01*
G01Y78150D02*
X372500D01*
X374292Y76608D01*
Y78692D01*
G01X361016Y55550D02*
Y58050D01*
X362057D01*
X362391Y57925D01*
X362599Y57758D01*
X362682Y57425D01*
X362599Y57092D01*
X362349Y56883D01*
X362057Y56758D01*
X361016D01*
G01X362057D02*
X362682Y55550D01*
G01X365449D02*
Y58050D01*
X363907Y56258D01*
X365991D01*
G01X367966Y55550D02*
X368049Y56092D01*
X368174Y56550D01*
X368341Y56967D01*
X368549Y57425D01*
X368882Y58050D01*
X367216D01*
G01X371066Y55550D02*
X371149Y56092D01*
X371274Y56550D01*
X371441Y56967D01*
X371649Y57425D01*
X371982Y58050D01*
X370316D01*
G01X373299Y59050D02*
Y55050D01*
X380699D01*
G01X359983Y65000D02*
Y63208D01*
X360150Y62833D01*
X360483Y62583D01*
X360900Y62500D01*
X361317Y62583D01*
X361650Y62833D01*
X361817Y63208D01*
Y65000D01*
G01X364500Y62500D02*
Y65000D01*
X362958Y63208D01*
X365042D01*
G01X366183Y63000D02*
X366433Y62708D01*
X366767Y62542D01*
X367142Y62500D01*
X367475Y62542D01*
X367808Y62750D01*
X368017Y63000D01*
X368058Y63250D01*
X367975Y63542D01*
X367683Y63750D01*
X367392Y63833D01*
X367017D01*
G01X367392D02*
X367642Y63958D01*
X367850Y64167D01*
X367933Y64417D01*
X367850Y64667D01*
X367642Y64875D01*
X367267Y65000D01*
X366892Y64958D01*
X366517Y64792D01*
G01X357699Y69550D02*
Y59550D01*
G01X367999Y92950D02*
X367957Y92617D01*
X367791Y92325D01*
X367541Y92075D01*
X367249Y91908D01*
X366916Y91825D01*
X366582D01*
X366249Y91908D01*
X365957Y92075D01*
X365707Y92325D01*
X365541Y92617D01*
X365499Y92950D01*
X365541Y93283D01*
X365707Y93575D01*
X365957Y93825D01*
X366249Y93992D01*
X366582Y94075D01*
X366916D01*
X367249Y93992D01*
X367541Y93825D01*
X367791Y93575D01*
X367957Y93283D01*
X367999Y92950D01*
G01X367332Y93283D02*
X367999Y93783D01*
G01X365916Y95258D02*
X365666Y95508D01*
X365541Y95800D01*
X365499Y96133D01*
X365582Y96550D01*
X365791Y96842D01*
X366041Y96925D01*
X366291Y96883D01*
X366499Y96717D01*
X366916Y95883D01*
X367207Y95508D01*
X367624Y95258D01*
X367999Y95175D01*
Y96925D01*
G01X367707Y98442D02*
X367916Y98733D01*
X367999Y99067D01*
X367916Y99400D01*
X367666Y99692D01*
X367291Y99900D01*
X366916Y99983D01*
X366457D01*
X366082Y99900D01*
X365749Y99692D01*
X365582Y99442D01*
X365499Y99150D01*
X365582Y98817D01*
X365749Y98567D01*
X365999Y98400D01*
X366332Y98317D01*
X366624Y98400D01*
X366916Y98608D01*
X367082Y98858D01*
X367124Y99150D01*
X367041Y99483D01*
X366832Y99733D01*
X366457Y99983D01*
G01X391516Y28550D02*
Y31050D01*
X392557D01*
X392891Y30925D01*
X393099Y30758D01*
X393182Y30425D01*
X393099Y30092D01*
X392849Y29883D01*
X392557Y29758D01*
X391516D01*
G01X392557D02*
X393182Y28550D01*
G01X394532Y29050D02*
X394782Y28758D01*
X395116Y28592D01*
X395491Y28550D01*
X395824Y28592D01*
X396157Y28800D01*
X396366Y29050D01*
X396407Y29300D01*
X396324Y29592D01*
X396032Y29800D01*
X395741Y29883D01*
X395366D01*
G01X395741D02*
X395991Y30008D01*
X396199Y30217D01*
X396282Y30467D01*
X396199Y30717D01*
X395991Y30925D01*
X395616Y31050D01*
X395241Y31008D01*
X394866Y30842D01*
G01X398549Y31050D02*
X398216Y30967D01*
X397966Y30758D01*
X397799Y30508D01*
X397674Y30175D01*
X397632Y29800D01*
X397674Y29425D01*
X397799Y29092D01*
X397966Y28842D01*
X398216Y28633D01*
X398549Y28550D01*
X398882Y28633D01*
X399132Y28842D01*
X399299Y29092D01*
X399424Y29425D01*
X399466Y29800D01*
X399424Y30175D01*
X399299Y30508D01*
X399132Y30758D01*
X398882Y30967D01*
X398549Y31050D01*
G01X400857Y29592D02*
X401149Y29883D01*
X401399Y30050D01*
X401732Y30133D01*
X402024Y30050D01*
X402232Y29883D01*
X402399Y29633D01*
X402441Y29342D01*
X402399Y29092D01*
X402232Y28842D01*
X401982Y28633D01*
X401691Y28550D01*
X401357Y28633D01*
X401066Y28883D01*
X400899Y29258D01*
X400857Y29675D01*
X400941Y30217D01*
X401066Y30508D01*
X401274Y30800D01*
X401566Y31008D01*
X401857Y31050D01*
X402149Y30967D01*
X402357Y30758D01*
G01X381299Y32550D02*
Y28550D01*
X388699D01*
G01X391516Y24050D02*
Y26550D01*
X392557D01*
X392891Y26425D01*
X393099Y26258D01*
X393182Y25925D01*
X393099Y25592D01*
X392849Y25383D01*
X392557Y25258D01*
X391516D01*
G01X392557D02*
X393182Y24050D01*
G01X394532Y24550D02*
X394782Y24258D01*
X395116Y24092D01*
X395491Y24050D01*
X395824Y24092D01*
X396157Y24300D01*
X396366Y24550D01*
X396407Y24800D01*
X396324Y25092D01*
X396032Y25300D01*
X395741Y25383D01*
X395366D01*
G01X395741D02*
X395991Y25508D01*
X396199Y25717D01*
X396282Y25967D01*
X396199Y26217D01*
X395991Y26425D01*
X395616Y26550D01*
X395241Y26508D01*
X394866Y26342D01*
G01X398549Y26550D02*
X398216Y26467D01*
X397966Y26258D01*
X397799Y26008D01*
X397674Y25675D01*
X397632Y25300D01*
X397674Y24925D01*
X397799Y24592D01*
X397966Y24342D01*
X398216Y24133D01*
X398549Y24050D01*
X398882Y24133D01*
X399132Y24342D01*
X399299Y24592D01*
X399424Y24925D01*
X399466Y25300D01*
X399424Y25675D01*
X399299Y26008D01*
X399132Y26258D01*
X398882Y26467D01*
X398549Y26550D01*
G01X401566Y24050D02*
X401649Y24592D01*
X401774Y25050D01*
X401941Y25467D01*
X402149Y25925D01*
X402482Y26550D01*
X400816D01*
G01X381299Y28050D02*
Y24050D01*
X388699D01*
G01X397199Y33350D02*
Y44750D01*
G01X383799Y33350D02*
X397199D01*
G01X383799Y44750D02*
Y33350D01*
G01X397199Y44750D02*
X383799D01*
G01X401999D02*
X397999D01*
Y37350D01*
G01X398799Y53050D02*
Y49050D01*
X406199D01*
G01X397699Y48550D02*
X384299D01*
G01X397699Y58550D02*
Y48550D01*
G01X384299D02*
Y58550D01*
G01X383208Y69767D02*
X383083Y69517D01*
X383000Y69225D01*
Y68892D01*
X383125Y68517D01*
X383333Y68225D01*
X383583Y68017D01*
X384000Y67850D01*
X384375Y67808D01*
X384750Y67892D01*
X385000Y68017D01*
X385250Y68267D01*
X385417Y68558D01*
X385500Y68850D01*
Y69142D01*
X385417Y69433D01*
X385292Y69683D01*
X385125Y69892D01*
G01X385000Y71033D02*
X385292Y71283D01*
X385458Y71617D01*
X385500Y71992D01*
X385458Y72325D01*
X385250Y72658D01*
X385000Y72867D01*
X384750Y72908D01*
X384458Y72825D01*
X384250Y72533D01*
X384167Y72242D01*
Y71867D01*
G01Y72242D02*
X384042Y72492D01*
X383833Y72700D01*
X383583Y72783D01*
X383333Y72700D01*
X383125Y72492D01*
X383000Y72117D01*
X383042Y71742D01*
X383208Y71367D01*
G01X385000Y74133D02*
X385292Y74383D01*
X385458Y74717D01*
X385500Y75092D01*
X385458Y75425D01*
X385250Y75758D01*
X385000Y75967D01*
X384750Y76008D01*
X384458Y75925D01*
X384250Y75633D01*
X384167Y75342D01*
Y74967D01*
G01Y75342D02*
X384042Y75592D01*
X383833Y75800D01*
X383583Y75883D01*
X383333Y75800D01*
X383125Y75592D01*
X383000Y75217D01*
X383042Y74842D01*
X383208Y74467D01*
G01X385208Y77442D02*
X385417Y77733D01*
X385500Y78067D01*
X385417Y78400D01*
X385167Y78692D01*
X384792Y78900D01*
X384417Y78983D01*
X383958D01*
X383583Y78900D01*
X383250Y78692D01*
X383083Y78442D01*
X383000Y78150D01*
X383083Y77817D01*
X383250Y77567D01*
X383500Y77400D01*
X383833Y77317D01*
X384125Y77400D01*
X384417Y77608D01*
X384583Y77858D01*
X384625Y78150D01*
X384542Y78483D01*
X384333Y78733D01*
X383958Y78983D01*
G01X398799Y58050D02*
Y54050D01*
X406199D01*
G01X385983Y64500D02*
Y62708D01*
X386150Y62333D01*
X386483Y62083D01*
X386900Y62000D01*
X387317Y62083D01*
X387650Y62333D01*
X387817Y62708D01*
Y64500D01*
G01X390500Y62000D02*
Y64500D01*
X388958Y62708D01*
X391042D01*
G01X392183Y62375D02*
X392433Y62167D01*
X392725Y62042D01*
X393100Y62000D01*
X393475Y62083D01*
X393767Y62250D01*
X393975Y62542D01*
X394017Y62875D01*
X393933Y63208D01*
X393725Y63417D01*
X393433Y63583D01*
X393142Y63625D01*
X392850Y63583D01*
X392475Y63417D01*
X392600Y64500D01*
X393725D01*
G01X384299Y58550D02*
X397699D01*
G01X400166Y1238050D02*
Y1248050D01*
X404499Y1239717D01*
X408832Y1248050D01*
Y1238050D01*
G01X410932D02*
X415099Y1248050D01*
X419266Y1238050D01*
G01X417766Y1241550D02*
X412432D01*
G01X422032Y1238050D02*
Y1248050D01*
X425366D01*
X426699Y1247550D01*
X427699Y1246883D01*
X428532Y1245883D01*
X429199Y1244716D01*
X429366Y1243050D01*
X429199Y1241383D01*
X428532Y1240217D01*
X427699Y1239216D01*
X426699Y1238550D01*
X425366Y1238050D01*
X422032D01*
G01X439632D02*
X432966D01*
Y1248050D01*
X439632D01*
G01X436966Y1243217D02*
X432966D01*
G01X455499Y1248050D02*
X459499D01*
G01X457499D02*
Y1238050D01*
G01X455499D02*
X459499D01*
G01X464266D02*
Y1248050D01*
X471932Y1238050D01*
Y1248050D01*
G01X489299D02*
Y1238050D01*
G01X485466Y1248050D02*
X493132D01*
G01X495732Y1238050D02*
X499899Y1248050D01*
X504066Y1238050D01*
G01X502566Y1241550D02*
X497232D01*
G01X508499Y1248050D02*
X512499D01*
G01X510499D02*
Y1238050D01*
G01X508499D02*
X512499D01*
G01X516099Y1248050D02*
X518432Y1238050D01*
X521099Y1248050D01*
X523766Y1238050D01*
X526099Y1248050D01*
G01X527532Y1238050D02*
X531699Y1248050D01*
X535866Y1238050D01*
G01X534366Y1241550D02*
X529032D01*
G01X538466Y1238050D02*
Y1248050D01*
X546132Y1238050D01*
Y1248050D01*
G01X405999Y1253050D02*
Y1263050D01*
X399832Y1255883D01*
X408166D01*
G01X414599Y1253050D02*
X415766Y1253217D01*
X417099Y1253717D01*
X417932Y1254550D01*
X418266Y1255717D01*
X417932Y1256883D01*
X416932Y1257883D01*
X415432Y1258383D01*
X413766D01*
X412766Y1258717D01*
X411932Y1259550D01*
X411599Y1260717D01*
X412099Y1261883D01*
X413265Y1262717D01*
X414599Y1263050D01*
X415932Y1262717D01*
X417099Y1261883D01*
X417599Y1260717D01*
X417266Y1259550D01*
X416432Y1258717D01*
X415432Y1258383D01*
X413766D01*
X412266Y1257883D01*
X411266Y1256883D01*
X410932Y1255717D01*
X411266Y1254550D01*
X412099Y1253717D01*
X413432Y1253217D01*
X414599Y1253050D01*
G01X425199Y1252717D02*
X424866Y1252883D01*
Y1253217D01*
X425199Y1253383D01*
X425532Y1253217D01*
Y1252883D01*
X425199Y1252717D01*
G01X432632Y1257216D02*
X433799Y1258383D01*
X434799Y1259050D01*
X436132Y1259383D01*
X437299Y1259050D01*
X438132Y1258383D01*
X438799Y1257383D01*
X438966Y1256217D01*
X438799Y1255217D01*
X438132Y1254216D01*
X437132Y1253383D01*
X435966Y1253050D01*
X434632Y1253383D01*
X433466Y1254383D01*
X432799Y1255883D01*
X432632Y1257550D01*
X432966Y1259716D01*
X433466Y1260883D01*
X434299Y1262050D01*
X435466Y1262883D01*
X436632Y1263050D01*
X437799Y1262717D01*
X438632Y1261883D01*
G01X448399Y1253050D02*
Y1263050D01*
X442232Y1255883D01*
X450566D01*
G01X451999Y1263050D02*
X454332Y1253050D01*
X456999Y1263050D01*
X459666Y1253050D01*
X461999Y1263050D01*
G01X467599D02*
X466265Y1262717D01*
X465266Y1261883D01*
X464599Y1260883D01*
X464099Y1259550D01*
X463932Y1258050D01*
X464099Y1256550D01*
X464599Y1255217D01*
X465266Y1254216D01*
X466265Y1253383D01*
X467599Y1253050D01*
X468932Y1253383D01*
X469932Y1254216D01*
X470599Y1255217D01*
X471099Y1256550D01*
X471266Y1258050D01*
X471099Y1259550D01*
X470599Y1260883D01*
X469932Y1261883D01*
X468932Y1262717D01*
X467599Y1263050D01*
G01X474532Y1255050D02*
X475532Y1253883D01*
X476865Y1253217D01*
X478366Y1253050D01*
X479699Y1253217D01*
X481032Y1254050D01*
X481866Y1255050D01*
X482032Y1256050D01*
X481699Y1257216D01*
X480532Y1258050D01*
X479366Y1258383D01*
X477866D01*
G01X479366D02*
X480366Y1258883D01*
X481199Y1259716D01*
X481532Y1260717D01*
X481199Y1261717D01*
X480366Y1262550D01*
X478866Y1263050D01*
X477366Y1262883D01*
X475866Y1262217D01*
G01X488799Y1252717D02*
X488466Y1252883D01*
Y1253217D01*
X488799Y1253383D01*
X489132Y1253217D01*
Y1252883D01*
X488799Y1252717D01*
G01X499399Y1263050D02*
X498065Y1262717D01*
X497066Y1261883D01*
X496399Y1260883D01*
X495899Y1259550D01*
X495732Y1258050D01*
X495899Y1256550D01*
X496399Y1255217D01*
X497066Y1254216D01*
X498065Y1253383D01*
X499399Y1253050D01*
X500732Y1253383D01*
X501732Y1254216D01*
X502399Y1255217D01*
X502899Y1256550D01*
X503066Y1258050D01*
X502899Y1259550D01*
X502399Y1260883D01*
X501732Y1261883D01*
X500732Y1262717D01*
X499399Y1263050D01*
G01X509999Y1253050D02*
Y1263050D01*
X507999Y1261050D01*
G01Y1253050D02*
X511999D01*
G01X520599D02*
Y1263050D01*
X518599Y1261050D01*
G01Y1253050D02*
X522599D01*
G01X402499Y1268050D02*
Y1278050D01*
X400499Y1276050D01*
G01Y1268050D02*
X404499D01*
G01X409932Y1276383D02*
X410932Y1277383D01*
X412099Y1277883D01*
X413432Y1278050D01*
X415099Y1277717D01*
X416266Y1276883D01*
X416599Y1275883D01*
X416432Y1274883D01*
X415766Y1274050D01*
X412432Y1272383D01*
X410932Y1271217D01*
X409932Y1269550D01*
X409599Y1268050D01*
X416599D01*
G01X425699D02*
Y1278050D01*
X419532Y1270883D01*
X427866D01*
G01X430632Y1270050D02*
X431632Y1268883D01*
X432965Y1268217D01*
X434466Y1268050D01*
X435799Y1268217D01*
X437132Y1269050D01*
X437966Y1270050D01*
X438132Y1271050D01*
X437799Y1272216D01*
X436632Y1273050D01*
X435466Y1273383D01*
X433966D01*
G01X435466D02*
X436466Y1273883D01*
X437299Y1274716D01*
X437632Y1275717D01*
X437299Y1276717D01*
X436466Y1277550D01*
X434966Y1278050D01*
X433466Y1277883D01*
X431966Y1277217D01*
G01X441732Y1276383D02*
X442732Y1277383D01*
X443899Y1277883D01*
X445232Y1278050D01*
X446899Y1277717D01*
X448066Y1276883D01*
X448399Y1275883D01*
X448232Y1274883D01*
X447566Y1274050D01*
X444232Y1272383D01*
X442732Y1271217D01*
X441732Y1269550D01*
X441399Y1268050D01*
X448399D01*
G01X453332Y1271383D02*
X457666D01*
G01X466099Y1268050D02*
Y1278050D01*
X464099Y1276050D01*
G01Y1268050D02*
X468099D01*
G01X400832Y1283050D02*
Y1293050D01*
G01X407166D02*
X400832Y1286883D01*
G01X408166Y1283050D02*
X403666Y1289716D01*
G01X411266Y1283050D02*
Y1293050D01*
X418932Y1283050D01*
Y1293050D01*
G01X425699Y1283050D02*
X424365Y1283217D01*
X423199Y1283883D01*
X422199Y1284883D01*
X421532Y1286050D01*
X421199Y1287383D01*
Y1288717D01*
X421532Y1290050D01*
X422199Y1291217D01*
X423199Y1292217D01*
X424365Y1292883D01*
X425699Y1293050D01*
X427032Y1292883D01*
X428199Y1292217D01*
X429199Y1291217D01*
X429866Y1290050D01*
X430199Y1288717D01*
Y1287383D01*
X429866Y1286050D01*
X429199Y1284883D01*
X428199Y1283883D01*
X427032Y1283217D01*
X425699Y1283050D01*
G01X432799D02*
X439799Y1293050D01*
G01X432799D02*
X439799Y1283050D01*
G01X453832D02*
Y1293050D01*
X457166D01*
X458499Y1292550D01*
X459499Y1291883D01*
X460332Y1290883D01*
X460999Y1289716D01*
X461166Y1288050D01*
X460999Y1286383D01*
X460332Y1285217D01*
X459499Y1284216D01*
X458499Y1283550D01*
X457166Y1283050D01*
X453832D01*
G01X464766D02*
Y1293050D01*
X468932D01*
X470266Y1292550D01*
X471099Y1291883D01*
X471432Y1290550D01*
X471099Y1289217D01*
X470099Y1288383D01*
X468932Y1287883D01*
X464766D01*
G01X468932D02*
X471432Y1283050D01*
G01X476699Y1293050D02*
X480699D01*
G01X478699D02*
Y1283050D01*
G01X476699D02*
X480699D01*
G01X485132Y1293050D02*
X489299Y1283050D01*
X493466Y1293050D01*
G01X503232Y1283050D02*
X496566D01*
Y1293050D01*
X503232D01*
G01X500566Y1288217D02*
X496566D01*
G01X517766Y1283050D02*
Y1293050D01*
X521766D01*
X523099Y1292550D01*
X524099Y1291383D01*
X524432Y1290050D01*
X524099Y1288717D01*
X523266Y1287717D01*
X521766Y1287216D01*
X517766D01*
G01X528366Y1293050D02*
Y1283050D01*
X535032D01*
G01X538132D02*
X542299Y1293050D01*
X546466Y1283050D01*
G01X544966Y1286550D02*
X539632D01*
G01X549066Y1283050D02*
Y1293050D01*
X556732Y1283050D01*
Y1293050D01*
G01X566832Y1283050D02*
X560166D01*
Y1293050D01*
X566832D01*
G01X564166Y1288217D02*
X560166D01*
G01X586032Y1288383D02*
X586699Y1288883D01*
X587199Y1289716D01*
X587532Y1290883D01*
X587199Y1291883D01*
X586532Y1292550D01*
X585366Y1293050D01*
X580866D01*
Y1283050D01*
X586366D01*
X587532Y1283717D01*
X588199Y1284717D01*
X588532Y1285883D01*
X588199Y1287050D01*
X587199Y1288050D01*
X586032Y1288383D01*
X580866D01*
G01X595299Y1283050D02*
X593965Y1283217D01*
X592799Y1283883D01*
X591799Y1284883D01*
X591132Y1286050D01*
X590799Y1287383D01*
Y1288717D01*
X591132Y1290050D01*
X591799Y1291217D01*
X592799Y1292217D01*
X593965Y1292883D01*
X595299Y1293050D01*
X596632Y1292883D01*
X597799Y1292217D01*
X598799Y1291217D01*
X599466Y1290050D01*
X599799Y1288717D01*
Y1287383D01*
X599466Y1286050D01*
X598799Y1284883D01*
X597799Y1283883D01*
X596632Y1283217D01*
X595299Y1283050D01*
G01X601732D02*
X605899Y1293050D01*
X610066Y1283050D01*
G01X608566Y1286550D02*
X603232D01*
G01X613166Y1283050D02*
Y1293050D01*
X617332D01*
X618666Y1292550D01*
X619499Y1291883D01*
X619832Y1290550D01*
X619499Y1289217D01*
X618499Y1288383D01*
X617332Y1287883D01*
X613166D01*
G01X617332D02*
X619832Y1283050D01*
G01X623432D02*
Y1293050D01*
X626766D01*
X628099Y1292550D01*
X629099Y1291883D01*
X629932Y1290883D01*
X630599Y1289716D01*
X630766Y1288050D01*
X630599Y1286383D01*
X629932Y1285217D01*
X629099Y1284216D01*
X628099Y1283550D01*
X626766Y1283050D01*
X623432D01*
G01X410463Y35147D02*
X410421Y34814D01*
X410255Y34522D01*
X410005Y34272D01*
X409713Y34105D01*
X409380Y34022D01*
X409046D01*
X408713Y34105D01*
X408421Y34272D01*
X408171Y34522D01*
X408005Y34814D01*
X407963Y35147D01*
X408005Y35480D01*
X408171Y35772D01*
X408421Y36022D01*
X408713Y36189D01*
X409046Y36272D01*
X409380D01*
X409713Y36189D01*
X410005Y36022D01*
X410255Y35772D01*
X410421Y35480D01*
X410463Y35147D01*
G01X409796Y35480D02*
X410463Y35980D01*
G01X409963Y37330D02*
X410255Y37580D01*
X410421Y37914D01*
X410463Y38289D01*
X410421Y38622D01*
X410213Y38955D01*
X409963Y39164D01*
X409713Y39205D01*
X409421Y39122D01*
X409213Y38830D01*
X409130Y38539D01*
Y38164D01*
G01Y38539D02*
X409005Y38789D01*
X408796Y38997D01*
X408546Y39080D01*
X408296Y38997D01*
X408088Y38789D01*
X407963Y38414D01*
X408005Y38039D01*
X408171Y37664D01*
G01X407963Y41347D02*
X408046Y41014D01*
X408255Y40764D01*
X408505Y40597D01*
X408838Y40472D01*
X409213Y40430D01*
X409588Y40472D01*
X409921Y40597D01*
X410171Y40764D01*
X410380Y41014D01*
X410463Y41347D01*
X410380Y41680D01*
X410171Y41930D01*
X409921Y42097D01*
X409588Y42222D01*
X409213Y42264D01*
X408838Y42222D01*
X408505Y42097D01*
X408255Y41930D01*
X408046Y41680D01*
X407963Y41347D01*
G01X414463Y33764D02*
X411963D01*
Y34805D01*
X412088Y35139D01*
X412255Y35347D01*
X412588Y35430D01*
X412921Y35347D01*
X413130Y35097D01*
X413255Y34805D01*
Y33764D01*
G01Y34805D02*
X414463Y35430D01*
G01X413963Y36780D02*
X414255Y37030D01*
X414421Y37364D01*
X414463Y37739D01*
X414421Y38072D01*
X414213Y38405D01*
X413963Y38614D01*
X413713Y38655D01*
X413421Y38572D01*
X413213Y38280D01*
X413130Y37989D01*
Y37614D01*
G01Y37989D02*
X413005Y38239D01*
X412796Y38447D01*
X412546Y38530D01*
X412296Y38447D01*
X412088Y38239D01*
X411963Y37864D01*
X412005Y37489D01*
X412171Y37114D01*
G01X411963Y40797D02*
X412046Y40464D01*
X412255Y40214D01*
X412505Y40047D01*
X412838Y39922D01*
X413213Y39880D01*
X413588Y39922D01*
X413921Y40047D01*
X414171Y40214D01*
X414380Y40464D01*
X414463Y40797D01*
X414380Y41130D01*
X414171Y41380D01*
X413921Y41547D01*
X413588Y41672D01*
X413213Y41714D01*
X412838Y41672D01*
X412505Y41547D01*
X412255Y41380D01*
X412046Y41130D01*
X411963Y40797D01*
G01X414463Y43897D02*
X414421Y44189D01*
X414296Y44522D01*
X414088Y44730D01*
X413796Y44814D01*
X413505Y44730D01*
X413255Y44480D01*
X413130Y44105D01*
Y43689D01*
X413046Y43439D01*
X412838Y43230D01*
X412546Y43147D01*
X412255Y43272D01*
X412046Y43564D01*
X411963Y43897D01*
X412046Y44230D01*
X412255Y44522D01*
X412546Y44647D01*
X412838Y44564D01*
X413046Y44355D01*
X413130Y44105D01*
Y43689D01*
X413255Y43314D01*
X413505Y43064D01*
X413796Y42980D01*
X414088Y43064D01*
X414296Y43272D01*
X414421Y43605D01*
X414463Y43897D01*
G01X408017Y48500D02*
Y51000D01*
X409058D01*
X409392Y50875D01*
X409600Y50708D01*
X409683Y50375D01*
X409600Y50042D01*
X409350Y49833D01*
X409058Y49708D01*
X408017D01*
G01X409058D02*
X409683Y48500D01*
G01X411033Y49000D02*
X411283Y48708D01*
X411617Y48542D01*
X411992Y48500D01*
X412325Y48542D01*
X412658Y48750D01*
X412867Y49000D01*
X412908Y49250D01*
X412825Y49542D01*
X412533Y49750D01*
X412242Y49833D01*
X411867D01*
G01X412242D02*
X412492Y49958D01*
X412700Y50167D01*
X412783Y50417D01*
X412700Y50667D01*
X412492Y50875D01*
X412117Y51000D01*
X411742Y50958D01*
X411367Y50792D01*
G01X415050Y51000D02*
X414717Y50917D01*
X414467Y50708D01*
X414300Y50458D01*
X414175Y50125D01*
X414133Y49750D01*
X414175Y49375D01*
X414300Y49042D01*
X414467Y48792D01*
X414717Y48583D01*
X415050Y48500D01*
X415383Y48583D01*
X415633Y48792D01*
X415800Y49042D01*
X415925Y49375D01*
X415967Y49750D01*
X415925Y50125D01*
X415800Y50458D01*
X415633Y50708D01*
X415383Y50917D01*
X415050Y51000D01*
G01X417442Y48792D02*
X417733Y48583D01*
X418067Y48500D01*
X418400Y48583D01*
X418692Y48833D01*
X418900Y49208D01*
X418983Y49583D01*
Y50042D01*
X418900Y50417D01*
X418692Y50750D01*
X418442Y50917D01*
X418150Y51000D01*
X417817Y50917D01*
X417567Y50750D01*
X417400Y50500D01*
X417317Y50167D01*
X417400Y49875D01*
X417608Y49583D01*
X417858Y49417D01*
X418150Y49375D01*
X418483Y49458D01*
X418733Y49667D01*
X418983Y50042D01*
G01X400517Y59000D02*
Y61500D01*
X401558D01*
X401892Y61375D01*
X402100Y61208D01*
X402183Y60875D01*
X402100Y60542D01*
X401850Y60333D01*
X401558Y60208D01*
X400517D01*
G01X401558D02*
X402183Y59000D01*
G01X403533Y59500D02*
X403783Y59208D01*
X404117Y59042D01*
X404492Y59000D01*
X404825Y59042D01*
X405158Y59250D01*
X405367Y59500D01*
X405408Y59750D01*
X405325Y60042D01*
X405033Y60250D01*
X404742Y60333D01*
X404367D01*
G01X404742D02*
X404992Y60458D01*
X405200Y60667D01*
X405283Y60917D01*
X405200Y61167D01*
X404992Y61375D01*
X404617Y61500D01*
X404242Y61458D01*
X403867Y61292D01*
G01X407550Y61500D02*
X407217Y61417D01*
X406967Y61208D01*
X406800Y60958D01*
X406675Y60625D01*
X406633Y60250D01*
X406675Y59875D01*
X406800Y59542D01*
X406967Y59292D01*
X407217Y59083D01*
X407550Y59000D01*
X407883Y59083D01*
X408133Y59292D01*
X408300Y59542D01*
X408425Y59875D01*
X408467Y60250D01*
X408425Y60625D01*
X408300Y60958D01*
X408133Y61208D01*
X407883Y61417D01*
X407550Y61500D01*
G01X409733Y59375D02*
X409983Y59167D01*
X410275Y59042D01*
X410650Y59000D01*
X411025Y59083D01*
X411317Y59250D01*
X411525Y59542D01*
X411567Y59875D01*
X411483Y60208D01*
X411275Y60417D01*
X410983Y60583D01*
X410692Y60625D01*
X410400Y60583D01*
X410025Y60417D01*
X410150Y61500D01*
X411275D01*
G01X427585Y1173280D02*
X429835D01*
G01X427585Y1167400D02*
Y1173280D01*
G01X429835Y1167400D02*
X427585D01*
G01X428935Y1170435D02*
X427585D01*
G01X433335Y1169070D02*
Y1173280D01*
G01X433105Y1168185D02*
X433335Y1169070D01*
G01X432655Y1167600D02*
X433105Y1168185D01*
G01X432090Y1167400D02*
X432655Y1167600D01*
G01X431525D02*
X432090Y1167400D01*
G01X431075Y1168185D02*
X431525Y1167600D01*
G01X430850Y1169070D02*
X431075Y1168185D01*
G01X430850Y1173280D02*
Y1169070D01*
G01X439300Y1167495D02*
X438855Y1167400D01*
G01X439700Y1167890D02*
X439300Y1167495D01*
G01X440035Y1168480D02*
X439700Y1167890D01*
G01X440265Y1169165D02*
X440035Y1168480D01*
G01X440375Y1169950D02*
X440265Y1169165D01*
G01X440375Y1170730D02*
Y1169950D01*
G01X440265Y1171515D02*
X440375Y1170730D01*
G01X440035Y1172200D02*
X440265Y1171515D01*
G01X439700Y1172790D02*
X440035Y1172200D01*
G01X439300Y1173185D02*
X439700Y1172790D01*
G01X438855Y1173280D02*
X439300Y1173185D01*
G01X438405D02*
X438855Y1173280D01*
G01X438005Y1172790D02*
X438405Y1173185D01*
G01X437670Y1172200D02*
X438005Y1172790D01*
G01X437440Y1171515D02*
X437670Y1172200D01*
G01X437330Y1170730D02*
X437440Y1171515D01*
G01X437330Y1169950D02*
Y1170730D01*
G01X437440Y1169165D02*
X437330Y1169950D01*
G01X437670Y1168480D02*
X437440Y1169165D01*
G01X438005Y1167890D02*
X437670Y1168480D01*
G01X438405Y1167495D02*
X438005Y1167890D01*
G01X438855Y1167400D02*
X438405Y1167495D01*
G01X441280Y1167400D02*
Y1171320D01*
G01X441835Y1171220D02*
X442290Y1171320D01*
G01X441500Y1170830D02*
X441835Y1171220D01*
G01X441280Y1170340D02*
X441500Y1170830D01*
G01X443190Y1170140D02*
Y1167400D01*
G01X443020Y1170830D02*
X443190Y1170140D01*
G01X442680Y1171220D02*
X443020Y1170830D01*
G01X442290Y1171320D02*
X442680Y1171220D01*
G01X445615Y1167400D02*
Y1173280D01*
G01X449445Y1168085D02*
X450180Y1171320D01*
G01X449105Y1166520D02*
X449445Y1168085D01*
G01X448885Y1166025D02*
X449105Y1166520D01*
G01X448600Y1165635D02*
X448885Y1166025D01*
G01X448150Y1165440D02*
X448600Y1165635D01*
G01X447810D02*
X448150Y1165440D01*
G01X448380Y1171320D02*
X449445Y1168085D01*
G01X492967Y1174100D02*
Y1184100D01*
X497133D01*
X498467Y1183600D01*
X499300Y1182933D01*
X499633Y1181600D01*
X499300Y1180267D01*
X498300Y1179433D01*
X497133Y1178933D01*
X492967D01*
G01X497133D02*
X499633Y1174100D01*
G01X506900D02*
X505566Y1174267D01*
X504400Y1174933D01*
X503400Y1175933D01*
X502733Y1177100D01*
X502400Y1178433D01*
Y1179767D01*
X502733Y1181100D01*
X503400Y1182267D01*
X504400Y1183267D01*
X505566Y1183933D01*
X506900Y1184100D01*
X508233Y1183933D01*
X509400Y1183267D01*
X510400Y1182267D01*
X511067Y1181100D01*
X511400Y1179767D01*
Y1178433D01*
X511067Y1177100D01*
X510400Y1175933D01*
X509400Y1174933D01*
X508233Y1174267D01*
X506900Y1174100D01*
G01X514000D02*
Y1184100D01*
G01X521000D02*
Y1174100D01*
G01Y1179100D02*
X514000D01*
G01X524600Y1175433D02*
X525933Y1174600D01*
X527433Y1174100D01*
X528767D01*
X530100Y1174600D01*
X531100Y1175433D01*
X531600Y1176600D01*
X531267Y1177766D01*
X530433Y1178767D01*
X528933Y1179433D01*
X526933Y1179767D01*
X525767Y1180433D01*
X525267Y1181600D01*
X525600Y1182767D01*
X526433Y1183600D01*
X527600Y1184100D01*
X528767D01*
X529933Y1183767D01*
X530933Y1182933D01*
G01X551967Y1179933D02*
X550800Y1180600D01*
X549800Y1180766D01*
X548467Y1180433D01*
X547467Y1179767D01*
X546800Y1178600D01*
X546633Y1177433D01*
X546800Y1176267D01*
X547467Y1175266D01*
X548467Y1174433D01*
X549800Y1174100D01*
X550967Y1174433D01*
X551967Y1175100D01*
G01X559900Y1174100D02*
X558900Y1174267D01*
X557900Y1174933D01*
X557233Y1176100D01*
X556900Y1177433D01*
X557233Y1178767D01*
X557900Y1179933D01*
X558900Y1180600D01*
X559900Y1180766D01*
X560900Y1180600D01*
X561900Y1179933D01*
X562567Y1178767D01*
X562733Y1177433D01*
X562567Y1176100D01*
X561900Y1174933D01*
X560900Y1174267D01*
X559900Y1174100D01*
G01X565500D02*
Y1180766D01*
G01Y1178933D02*
X566000Y1179767D01*
X566833Y1180433D01*
X568000Y1180766D01*
X569166Y1180433D01*
X570000Y1179767D01*
X570500Y1178933D01*
Y1174100D01*
G01Y1178933D02*
X571000Y1179767D01*
X571833Y1180433D01*
X573000Y1180766D01*
X574167Y1180433D01*
X575000Y1179767D01*
X575500Y1178767D01*
Y1174100D01*
G01X578100Y1170767D02*
Y1180766D01*
G01Y1179267D02*
X578933Y1180100D01*
X579766Y1180600D01*
X581100Y1180766D01*
X582267Y1180600D01*
X583433Y1179767D01*
X583933Y1178600D01*
X584100Y1177433D01*
X583933Y1176267D01*
X583433Y1175100D01*
X582433Y1174433D01*
X581100Y1174100D01*
X579933Y1174267D01*
X578767Y1174767D01*
X578100Y1175433D01*
G01X591700Y1174100D02*
Y1184100D01*
G01X602300Y1180766D02*
Y1174100D01*
G01Y1183433D02*
X601967Y1183600D01*
Y1183933D01*
X602300Y1184100D01*
X602633Y1183933D01*
Y1183600D01*
X602300Y1183433D01*
G01X615900Y1174100D02*
Y1180766D01*
G01Y1179600D02*
X615233Y1180267D01*
X614233Y1180600D01*
X613067Y1180766D01*
X611900Y1180433D01*
X610900Y1179767D01*
X610233Y1178767D01*
X609900Y1177433D01*
X610233Y1176100D01*
X610900Y1175100D01*
X611900Y1174433D01*
X613067Y1174100D01*
X614233Y1174267D01*
X615233Y1174767D01*
X615900Y1175433D01*
G01X620667Y1174100D02*
Y1180766D01*
G01Y1179100D02*
X621333Y1179933D01*
X622333Y1180600D01*
X623667Y1180766D01*
X624833Y1180600D01*
X625833Y1179933D01*
X626333Y1178767D01*
Y1174100D01*
G01X636767Y1179933D02*
X635600Y1180600D01*
X634600Y1180766D01*
X633267Y1180433D01*
X632267Y1179767D01*
X631600Y1178600D01*
X631433Y1177433D01*
X631600Y1176267D01*
X632267Y1175266D01*
X633267Y1174433D01*
X634600Y1174100D01*
X635767Y1174433D01*
X636767Y1175100D01*
G01X642200Y1178600D02*
X647533D01*
X647033Y1179767D01*
X646200Y1180433D01*
X645033Y1180766D01*
X643867Y1180600D01*
X642867Y1180100D01*
X642200Y1178933D01*
X641867Y1177933D01*
Y1176933D01*
X642200Y1175933D01*
X643033Y1174933D01*
X644033Y1174267D01*
X645200Y1174100D01*
X646367Y1174433D01*
X647533Y1175433D01*
G01X627049Y1786151D02*
X624549D01*
Y1787192D01*
X624674Y1787526D01*
X624841Y1787734D01*
X625174Y1787817D01*
X625507Y1787734D01*
X625716Y1787484D01*
X625841Y1787192D01*
Y1786151D01*
G01Y1787192D02*
X627049Y1787817D01*
G01Y1790584D02*
X624549D01*
X626341Y1789042D01*
Y1791126D01*
G01X627049Y1793184D02*
X627007Y1793476D01*
X626882Y1793809D01*
X626674Y1794017D01*
X626382Y1794101D01*
X626091Y1794017D01*
X625841Y1793767D01*
X625716Y1793392D01*
Y1792976D01*
X625632Y1792726D01*
X625424Y1792517D01*
X625132Y1792434D01*
X624841Y1792559D01*
X624632Y1792851D01*
X624549Y1793184D01*
X624632Y1793517D01*
X624841Y1793809D01*
X625132Y1793934D01*
X625424Y1793851D01*
X625632Y1793642D01*
X625716Y1793392D01*
Y1792976D01*
X625841Y1792601D01*
X626091Y1792351D01*
X626382Y1792267D01*
X626674Y1792351D01*
X626882Y1792559D01*
X627007Y1792892D01*
X627049Y1793184D01*
G01X624966Y1795492D02*
X624716Y1795742D01*
X624591Y1796034D01*
X624549Y1796367D01*
X624632Y1796784D01*
X624841Y1797076D01*
X625091Y1797159D01*
X625341Y1797117D01*
X625549Y1796951D01*
X625966Y1796117D01*
X626257Y1795742D01*
X626674Y1795492D01*
X627049Y1795409D01*
Y1797159D01*
G01X631049Y1786151D02*
X628549D01*
Y1787192D01*
X628674Y1787526D01*
X628841Y1787734D01*
X629174Y1787817D01*
X629507Y1787734D01*
X629716Y1787484D01*
X629841Y1787192D01*
Y1786151D01*
G01Y1787192D02*
X631049Y1787817D01*
G01Y1790584D02*
X628549D01*
X630341Y1789042D01*
Y1791126D01*
G01X631049Y1793184D02*
X631007Y1793476D01*
X630882Y1793809D01*
X630674Y1794017D01*
X630382Y1794101D01*
X630091Y1794017D01*
X629841Y1793767D01*
X629716Y1793392D01*
Y1792976D01*
X629632Y1792726D01*
X629424Y1792517D01*
X629132Y1792434D01*
X628841Y1792559D01*
X628632Y1792851D01*
X628549Y1793184D01*
X628632Y1793517D01*
X628841Y1793809D01*
X629132Y1793934D01*
X629424Y1793851D01*
X629632Y1793642D01*
X629716Y1793392D01*
Y1792976D01*
X629841Y1792601D01*
X630091Y1792351D01*
X630382Y1792267D01*
X630674Y1792351D01*
X630882Y1792559D01*
X631007Y1792892D01*
X631049Y1793184D01*
G01X630549Y1795367D02*
X630841Y1795617D01*
X631007Y1795951D01*
X631049Y1796326D01*
X631007Y1796659D01*
X630799Y1796992D01*
X630549Y1797201D01*
X630299Y1797242D01*
X630007Y1797159D01*
X629799Y1796867D01*
X629716Y1796576D01*
Y1796201D01*
G01Y1796576D02*
X629591Y1796826D01*
X629382Y1797034D01*
X629132Y1797117D01*
X628882Y1797034D01*
X628674Y1796826D01*
X628549Y1796451D01*
X628591Y1796076D01*
X628757Y1795701D01*
G01X627049Y1802151D02*
X624549D01*
Y1803192D01*
X624674Y1803526D01*
X624841Y1803734D01*
X625174Y1803817D01*
X625507Y1803734D01*
X625716Y1803484D01*
X625841Y1803192D01*
Y1802151D01*
G01Y1803192D02*
X627049Y1803817D01*
G01X626549Y1805167D02*
X626841Y1805417D01*
X627007Y1805751D01*
X627049Y1806126D01*
X627007Y1806459D01*
X626799Y1806792D01*
X626549Y1807001D01*
X626299Y1807042D01*
X626007Y1806959D01*
X625799Y1806667D01*
X625716Y1806376D01*
Y1806001D01*
G01Y1806376D02*
X625591Y1806626D01*
X625382Y1806834D01*
X625132Y1806917D01*
X624882Y1806834D01*
X624674Y1806626D01*
X624549Y1806251D01*
X624591Y1805876D01*
X624757Y1805501D01*
G01X627049Y1809184D02*
X627007Y1809476D01*
X626882Y1809809D01*
X626674Y1810017D01*
X626382Y1810101D01*
X626091Y1810017D01*
X625841Y1809767D01*
X625716Y1809392D01*
Y1808976D01*
X625632Y1808726D01*
X625424Y1808517D01*
X625132Y1808434D01*
X624841Y1808559D01*
X624632Y1808851D01*
X624549Y1809184D01*
X624632Y1809517D01*
X624841Y1809809D01*
X625132Y1809934D01*
X625424Y1809851D01*
X625632Y1809642D01*
X625716Y1809392D01*
Y1808976D01*
X625841Y1808601D01*
X626091Y1808351D01*
X626382Y1808267D01*
X626674Y1808351D01*
X626882Y1808559D01*
X627007Y1808892D01*
X627049Y1809184D01*
G01Y1812284D02*
X627007Y1812576D01*
X626882Y1812909D01*
X626674Y1813117D01*
X626382Y1813201D01*
X626091Y1813117D01*
X625841Y1812867D01*
X625716Y1812492D01*
Y1812076D01*
X625632Y1811826D01*
X625424Y1811617D01*
X625132Y1811534D01*
X624841Y1811659D01*
X624632Y1811951D01*
X624549Y1812284D01*
X624632Y1812617D01*
X624841Y1812909D01*
X625132Y1813034D01*
X625424Y1812951D01*
X625632Y1812742D01*
X625716Y1812492D01*
Y1812076D01*
X625841Y1811701D01*
X626091Y1811451D01*
X626382Y1811367D01*
X626674Y1811451D01*
X626882Y1811659D01*
X627007Y1811992D01*
X627049Y1812284D01*
G01X631049Y1802151D02*
X628549D01*
Y1803192D01*
X628674Y1803526D01*
X628841Y1803734D01*
X629174Y1803817D01*
X629507Y1803734D01*
X629716Y1803484D01*
X629841Y1803192D01*
Y1802151D01*
G01Y1803192D02*
X631049Y1803817D01*
G01X630549Y1805167D02*
X630841Y1805417D01*
X631007Y1805751D01*
X631049Y1806126D01*
X631007Y1806459D01*
X630799Y1806792D01*
X630549Y1807001D01*
X630299Y1807042D01*
X630007Y1806959D01*
X629799Y1806667D01*
X629716Y1806376D01*
Y1806001D01*
G01Y1806376D02*
X629591Y1806626D01*
X629382Y1806834D01*
X629132Y1806917D01*
X628882Y1806834D01*
X628674Y1806626D01*
X628549Y1806251D01*
X628591Y1805876D01*
X628757Y1805501D01*
G01X630757Y1808476D02*
X630966Y1808767D01*
X631049Y1809101D01*
X630966Y1809434D01*
X630716Y1809726D01*
X630341Y1809934D01*
X629966Y1810017D01*
X629507D01*
X629132Y1809934D01*
X628799Y1809726D01*
X628632Y1809476D01*
X628549Y1809184D01*
X628632Y1808851D01*
X628799Y1808601D01*
X629049Y1808434D01*
X629382Y1808351D01*
X629674Y1808434D01*
X629966Y1808642D01*
X630132Y1808892D01*
X630174Y1809184D01*
X630091Y1809517D01*
X629882Y1809767D01*
X629507Y1810017D01*
G01X628549Y1812284D02*
X628632Y1811951D01*
X628841Y1811701D01*
X629091Y1811534D01*
X629424Y1811409D01*
X629799Y1811367D01*
X630174Y1811409D01*
X630507Y1811534D01*
X630757Y1811701D01*
X630966Y1811951D01*
X631049Y1812284D01*
X630966Y1812617D01*
X630757Y1812867D01*
X630507Y1813034D01*
X630174Y1813159D01*
X629799Y1813201D01*
X629424Y1813159D01*
X629091Y1813034D01*
X628841Y1812867D01*
X628632Y1812617D01*
X628549Y1812284D01*
G01X644566Y1785634D02*
Y1788134D01*
X645607D01*
X645941Y1788009D01*
X646149Y1787842D01*
X646232Y1787509D01*
X646149Y1787176D01*
X645899Y1786967D01*
X645607Y1786842D01*
X644566D01*
G01X645607D02*
X646232Y1785634D01*
G01X647582Y1786134D02*
X647832Y1785842D01*
X648166Y1785676D01*
X648541Y1785634D01*
X648874Y1785676D01*
X649207Y1785884D01*
X649416Y1786134D01*
X649457Y1786384D01*
X649374Y1786676D01*
X649082Y1786884D01*
X648791Y1786967D01*
X648416D01*
G01X648791D02*
X649041Y1787092D01*
X649249Y1787301D01*
X649332Y1787551D01*
X649249Y1787801D01*
X649041Y1788009D01*
X648666Y1788134D01*
X648291Y1788092D01*
X647916Y1787926D01*
G01X651516Y1785634D02*
X651599Y1786176D01*
X651724Y1786634D01*
X651891Y1787051D01*
X652099Y1787509D01*
X652432Y1788134D01*
X650766D01*
G01X653782Y1786134D02*
X654032Y1785842D01*
X654366Y1785676D01*
X654741Y1785634D01*
X655074Y1785676D01*
X655407Y1785884D01*
X655616Y1786134D01*
X655657Y1786384D01*
X655574Y1786676D01*
X655282Y1786884D01*
X654991Y1786967D01*
X654616D01*
G01X654991D02*
X655241Y1787092D01*
X655449Y1787301D01*
X655532Y1787551D01*
X655449Y1787801D01*
X655241Y1788009D01*
X654866Y1788134D01*
X654491Y1788092D01*
X654116Y1787926D01*
G01X644566Y1781634D02*
Y1784134D01*
X645607D01*
X645941Y1784009D01*
X646149Y1783842D01*
X646232Y1783509D01*
X646149Y1783176D01*
X645899Y1782967D01*
X645607Y1782842D01*
X644566D01*
G01X645607D02*
X646232Y1781634D01*
G01X647582Y1782134D02*
X647832Y1781842D01*
X648166Y1781676D01*
X648541Y1781634D01*
X648874Y1781676D01*
X649207Y1781884D01*
X649416Y1782134D01*
X649457Y1782384D01*
X649374Y1782676D01*
X649082Y1782884D01*
X648791Y1782967D01*
X648416D01*
G01X648791D02*
X649041Y1783092D01*
X649249Y1783301D01*
X649332Y1783551D01*
X649249Y1783801D01*
X649041Y1784009D01*
X648666Y1784134D01*
X648291Y1784092D01*
X647916Y1783926D01*
G01X651599Y1781634D02*
X651891Y1781676D01*
X652224Y1781801D01*
X652432Y1782009D01*
X652516Y1782301D01*
X652432Y1782592D01*
X652182Y1782842D01*
X651807Y1782967D01*
X651391D01*
X651141Y1783051D01*
X650932Y1783259D01*
X650849Y1783551D01*
X650974Y1783842D01*
X651266Y1784051D01*
X651599Y1784134D01*
X651932Y1784051D01*
X652224Y1783842D01*
X652349Y1783551D01*
X652266Y1783259D01*
X652057Y1783051D01*
X651807Y1782967D01*
X651391D01*
X651016Y1782842D01*
X650766Y1782592D01*
X650682Y1782301D01*
X650766Y1782009D01*
X650974Y1781801D01*
X651307Y1781676D01*
X651599Y1781634D01*
G01X654699Y1784134D02*
X654366Y1784051D01*
X654116Y1783842D01*
X653949Y1783592D01*
X653824Y1783259D01*
X653782Y1782884D01*
X653824Y1782509D01*
X653949Y1782176D01*
X654116Y1781926D01*
X654366Y1781717D01*
X654699Y1781634D01*
X655032Y1781717D01*
X655282Y1781926D01*
X655449Y1782176D01*
X655574Y1782509D01*
X655616Y1782884D01*
X655574Y1783259D01*
X655449Y1783592D01*
X655282Y1783842D01*
X655032Y1784051D01*
X654699Y1784134D01*
G01X646349Y1805634D02*
Y1801634D01*
X653749D01*
G01X646349Y1798134D02*
Y1794134D01*
X653749D01*
G01X642049Y1809334D02*
X638049D01*
Y1801934D01*
G01X642049D02*
X646049D01*
Y1809334D01*
G01X642049Y1798334D02*
X638049D01*
Y1790934D01*
G01X642049D02*
X646049D01*
Y1798334D01*
G01X643049Y1811151D02*
X640549D01*
Y1812192D01*
X640674Y1812526D01*
X640841Y1812734D01*
X641174Y1812817D01*
X641507Y1812734D01*
X641716Y1812484D01*
X641841Y1812192D01*
Y1811151D01*
G01Y1812192D02*
X643049Y1812817D01*
G01X642549Y1814167D02*
X642841Y1814417D01*
X643007Y1814751D01*
X643049Y1815126D01*
X643007Y1815459D01*
X642799Y1815792D01*
X642549Y1816001D01*
X642299Y1816042D01*
X642007Y1815959D01*
X641799Y1815667D01*
X641716Y1815376D01*
Y1815001D01*
G01Y1815376D02*
X641591Y1815626D01*
X641382Y1815834D01*
X641132Y1815917D01*
X640882Y1815834D01*
X640674Y1815626D01*
X640549Y1815251D01*
X640591Y1814876D01*
X640757Y1814501D01*
G01X642007Y1817392D02*
X641716Y1817684D01*
X641549Y1817934D01*
X641466Y1818267D01*
X641549Y1818559D01*
X641716Y1818767D01*
X641966Y1818934D01*
X642257Y1818976D01*
X642507Y1818934D01*
X642757Y1818767D01*
X642966Y1818517D01*
X643049Y1818226D01*
X642966Y1817892D01*
X642716Y1817601D01*
X642341Y1817434D01*
X641924Y1817392D01*
X641382Y1817476D01*
X641091Y1817601D01*
X640799Y1817809D01*
X640591Y1818101D01*
X640549Y1818392D01*
X640632Y1818684D01*
X640841Y1818892D01*
G01X640966Y1820492D02*
X640716Y1820742D01*
X640591Y1821034D01*
X640549Y1821367D01*
X640632Y1821784D01*
X640841Y1822076D01*
X641091Y1822159D01*
X641341Y1822117D01*
X641549Y1821951D01*
X641966Y1821117D01*
X642257Y1820742D01*
X642674Y1820492D01*
X643049Y1820409D01*
Y1822159D01*
G01X651049Y1816334D02*
X647049D01*
Y1808934D01*
G01X650049Y1822651D02*
X647549D01*
Y1823692D01*
X647674Y1824026D01*
X647841Y1824234D01*
X648174Y1824317D01*
X648507Y1824234D01*
X648716Y1823984D01*
X648841Y1823692D01*
Y1822651D01*
G01Y1823692D02*
X650049Y1824317D01*
G01X649549Y1825667D02*
X649841Y1825917D01*
X650007Y1826251D01*
X650049Y1826626D01*
X650007Y1826959D01*
X649799Y1827292D01*
X649549Y1827501D01*
X649299Y1827542D01*
X649007Y1827459D01*
X648799Y1827167D01*
X648716Y1826876D01*
Y1826501D01*
G01Y1826876D02*
X648591Y1827126D01*
X648382Y1827334D01*
X648132Y1827417D01*
X647882Y1827334D01*
X647674Y1827126D01*
X647549Y1826751D01*
X647591Y1826376D01*
X647757Y1826001D01*
G01X649007Y1828892D02*
X648716Y1829184D01*
X648549Y1829434D01*
X648466Y1829767D01*
X648549Y1830059D01*
X648716Y1830267D01*
X648966Y1830434D01*
X649257Y1830476D01*
X649507Y1830434D01*
X649757Y1830267D01*
X649966Y1830017D01*
X650049Y1829726D01*
X649966Y1829392D01*
X649716Y1829101D01*
X649341Y1828934D01*
X648924Y1828892D01*
X648382Y1828976D01*
X648091Y1829101D01*
X647799Y1829309D01*
X647591Y1829601D01*
X647549Y1829892D01*
X647632Y1830184D01*
X647841Y1830392D01*
G01X650049Y1833284D02*
X647549D01*
X649341Y1831742D01*
Y1833826D01*
G01X645849Y1820634D02*
Y1816634D01*
X653249D01*
G01X659208Y1776767D02*
X659083Y1776517D01*
X659000Y1776225D01*
Y1775892D01*
X659125Y1775517D01*
X659333Y1775225D01*
X659583Y1775017D01*
X660000Y1774850D01*
X660375Y1774808D01*
X660750Y1774892D01*
X661000Y1775017D01*
X661250Y1775267D01*
X661417Y1775558D01*
X661500Y1775850D01*
Y1776142D01*
X661417Y1776433D01*
X661292Y1776683D01*
X661125Y1776892D01*
G01X661000Y1778033D02*
X661292Y1778283D01*
X661458Y1778617D01*
X661500Y1778992D01*
X661458Y1779325D01*
X661250Y1779658D01*
X661000Y1779867D01*
X660750Y1779908D01*
X660458Y1779825D01*
X660250Y1779533D01*
X660167Y1779242D01*
Y1778867D01*
G01Y1779242D02*
X660042Y1779492D01*
X659833Y1779700D01*
X659583Y1779783D01*
X659333Y1779700D01*
X659125Y1779492D01*
X659000Y1779117D01*
X659042Y1778742D01*
X659208Y1778367D01*
G01X661125Y1781133D02*
X661333Y1781383D01*
X661458Y1781675D01*
X661500Y1782050D01*
X661417Y1782425D01*
X661250Y1782717D01*
X660958Y1782925D01*
X660625Y1782967D01*
X660292Y1782883D01*
X660083Y1782675D01*
X659917Y1782383D01*
X659875Y1782092D01*
X659917Y1781800D01*
X660083Y1781425D01*
X659000Y1781550D01*
Y1782675D01*
G01X661500Y1785650D02*
X659000D01*
X660792Y1784108D01*
Y1786192D01*
G01X659257Y1790401D02*
X659132Y1790151D01*
X659049Y1789859D01*
Y1789526D01*
X659174Y1789151D01*
X659382Y1788859D01*
X659632Y1788651D01*
X660049Y1788484D01*
X660424Y1788442D01*
X660799Y1788526D01*
X661049Y1788651D01*
X661299Y1788901D01*
X661466Y1789192D01*
X661549Y1789484D01*
Y1789776D01*
X661466Y1790067D01*
X661341Y1790317D01*
X661174Y1790526D01*
G01X661049Y1791667D02*
X661341Y1791917D01*
X661507Y1792251D01*
X661549Y1792626D01*
X661507Y1792959D01*
X661299Y1793292D01*
X661049Y1793501D01*
X660799Y1793542D01*
X660507Y1793459D01*
X660299Y1793167D01*
X660216Y1792876D01*
Y1792501D01*
G01Y1792876D02*
X660091Y1793126D01*
X659882Y1793334D01*
X659632Y1793417D01*
X659382Y1793334D01*
X659174Y1793126D01*
X659049Y1792751D01*
X659091Y1792376D01*
X659257Y1792001D01*
G01X661174Y1794767D02*
X661382Y1795017D01*
X661507Y1795309D01*
X661549Y1795684D01*
X661466Y1796059D01*
X661299Y1796351D01*
X661007Y1796559D01*
X660674Y1796601D01*
X660341Y1796517D01*
X660132Y1796309D01*
X659966Y1796017D01*
X659924Y1795726D01*
X659966Y1795434D01*
X660132Y1795059D01*
X659049Y1795184D01*
Y1796309D01*
G01X661049Y1797867D02*
X661341Y1798117D01*
X661507Y1798451D01*
X661549Y1798826D01*
X661507Y1799159D01*
X661299Y1799492D01*
X661049Y1799701D01*
X660799Y1799742D01*
X660507Y1799659D01*
X660299Y1799367D01*
X660216Y1799076D01*
Y1798701D01*
G01Y1799076D02*
X660091Y1799326D01*
X659882Y1799534D01*
X659632Y1799617D01*
X659382Y1799534D01*
X659174Y1799326D01*
X659049Y1798951D01*
X659091Y1798576D01*
X659257Y1798201D01*
G01X670549Y1818534D02*
X678549D01*
Y1806134D01*
X670549D01*
Y1818534D01*
G01X656549Y1822651D02*
X654049D01*
Y1823692D01*
X654174Y1824026D01*
X654341Y1824234D01*
X654674Y1824317D01*
X655007Y1824234D01*
X655216Y1823984D01*
X655341Y1823692D01*
Y1822651D01*
G01Y1823692D02*
X656549Y1824317D01*
G01X656049Y1825667D02*
X656341Y1825917D01*
X656507Y1826251D01*
X656549Y1826626D01*
X656507Y1826959D01*
X656299Y1827292D01*
X656049Y1827501D01*
X655799Y1827542D01*
X655507Y1827459D01*
X655299Y1827167D01*
X655216Y1826876D01*
Y1826501D01*
G01Y1826876D02*
X655091Y1827126D01*
X654882Y1827334D01*
X654632Y1827417D01*
X654382Y1827334D01*
X654174Y1827126D01*
X654049Y1826751D01*
X654091Y1826376D01*
X654257Y1826001D01*
G01X656549Y1829684D02*
X656507Y1829976D01*
X656382Y1830309D01*
X656174Y1830517D01*
X655882Y1830601D01*
X655591Y1830517D01*
X655341Y1830267D01*
X655216Y1829892D01*
Y1829476D01*
X655132Y1829226D01*
X654924Y1829017D01*
X654632Y1828934D01*
X654341Y1829059D01*
X654132Y1829351D01*
X654049Y1829684D01*
X654132Y1830017D01*
X654341Y1830309D01*
X654632Y1830434D01*
X654924Y1830351D01*
X655132Y1830142D01*
X655216Y1829892D01*
Y1829476D01*
X655341Y1829101D01*
X655591Y1828851D01*
X655882Y1828767D01*
X656174Y1828851D01*
X656382Y1829059D01*
X656507Y1829392D01*
X656549Y1829684D01*
G01Y1832784D02*
X654049D01*
X654549Y1832284D01*
G01X656549D02*
Y1833284D01*
G01X657549Y1820834D02*
X653549D01*
Y1813434D01*
G01X659199Y1826250D02*
X661699D01*
G01X659199Y1825292D02*
Y1827208D01*
G01X661699Y1828517D02*
X659199D01*
Y1829517D01*
X659324Y1829850D01*
X659616Y1830100D01*
X659949Y1830183D01*
X660282Y1830100D01*
X660532Y1829892D01*
X660657Y1829517D01*
Y1828517D01*
G01X661699Y1832450D02*
X659199D01*
X659699Y1831950D01*
G01X661699D02*
Y1832950D01*
G01X661324Y1834633D02*
X661532Y1834883D01*
X661657Y1835175D01*
X661699Y1835550D01*
X661616Y1835925D01*
X661449Y1836217D01*
X661157Y1836425D01*
X660824Y1836467D01*
X660491Y1836383D01*
X660282Y1836175D01*
X660116Y1835883D01*
X660074Y1835592D01*
X660116Y1835300D01*
X660282Y1834925D01*
X659199Y1835050D01*
Y1836175D01*
G01Y1838650D02*
X659282Y1838317D01*
X659491Y1838067D01*
X659741Y1837900D01*
X660074Y1837775D01*
X660449Y1837733D01*
X660824Y1837775D01*
X661157Y1837900D01*
X661407Y1838067D01*
X661616Y1838317D01*
X661699Y1838650D01*
X661616Y1838983D01*
X661407Y1839233D01*
X661157Y1839400D01*
X660824Y1839525D01*
X660449Y1839567D01*
X660074Y1839525D01*
X659741Y1839400D01*
X659491Y1839233D01*
X659282Y1838983D01*
X659199Y1838650D01*
G01X671032Y1823634D02*
Y1821842D01*
X671199Y1821467D01*
X671532Y1821217D01*
X671949Y1821134D01*
X672366Y1821217D01*
X672699Y1821467D01*
X672866Y1821842D01*
Y1823634D01*
G01X674132Y1821509D02*
X674382Y1821301D01*
X674674Y1821176D01*
X675049Y1821134D01*
X675424Y1821217D01*
X675716Y1821384D01*
X675924Y1821676D01*
X675966Y1822009D01*
X675882Y1822342D01*
X675674Y1822551D01*
X675382Y1822717D01*
X675091Y1822759D01*
X674799Y1822717D01*
X674424Y1822551D01*
X674549Y1823634D01*
X675674D01*
G01X677232Y1821634D02*
X677482Y1821342D01*
X677816Y1821176D01*
X678191Y1821134D01*
X678524Y1821176D01*
X678857Y1821384D01*
X679066Y1821634D01*
X679107Y1821884D01*
X679024Y1822176D01*
X678732Y1822384D01*
X678441Y1822467D01*
X678066D01*
G01X678441D02*
X678691Y1822592D01*
X678899Y1822801D01*
X678982Y1823051D01*
X678899Y1823301D01*
X678691Y1823509D01*
X678316Y1823634D01*
X677941Y1823592D01*
X677566Y1823426D01*
G01X674549Y1816834D02*
X676049Y1818334D01*
G01X674549Y1816834D02*
X673049Y1818334D01*
G01X686499Y198050D02*
Y188050D01*
G01X682666Y198050D02*
X690332D01*
G01X700432Y188050D02*
X693766D01*
Y198050D01*
X700432D01*
G01X697766Y193217D02*
X693766D01*
G01X703366Y188050D02*
Y198050D01*
X707699Y189717D01*
X712032Y198050D01*
Y188050D01*
G01X714966D02*
Y198050D01*
X718966D01*
X720299Y197550D01*
X721299Y196383D01*
X721632Y195050D01*
X721299Y193717D01*
X720466Y192717D01*
X718966Y192216D01*
X714966D01*
G01X723899Y184717D02*
X733899D01*
G01X735999Y189383D02*
X737332Y188550D01*
X738832Y188050D01*
X740166D01*
X741499Y188550D01*
X742499Y189383D01*
X742999Y190550D01*
X742666Y191716D01*
X741832Y192717D01*
X740332Y193383D01*
X738332Y193717D01*
X737166Y194383D01*
X736666Y195550D01*
X736999Y196717D01*
X737832Y197550D01*
X738999Y198050D01*
X740166D01*
X741332Y197717D01*
X742332Y196883D01*
G01X753432Y188050D02*
X746766D01*
Y198050D01*
X753432D01*
G01X750766Y193217D02*
X746766D01*
G01X756866Y188050D02*
Y198050D01*
X764532Y188050D01*
Y198050D01*
G01X767799Y189383D02*
X769132Y188550D01*
X770632Y188050D01*
X771966D01*
X773299Y188550D01*
X774299Y189383D01*
X774799Y190550D01*
X774466Y191716D01*
X773632Y192717D01*
X772132Y193383D01*
X770132Y193717D01*
X768966Y194383D01*
X768466Y195550D01*
X768799Y196717D01*
X769632Y197550D01*
X770799Y198050D01*
X771966D01*
X773132Y197717D01*
X774132Y196883D01*
G01X781899Y188050D02*
X780565Y188217D01*
X779399Y188883D01*
X778399Y189883D01*
X777732Y191050D01*
X777399Y192383D01*
Y193717D01*
X777732Y195050D01*
X778399Y196217D01*
X779399Y197217D01*
X780565Y197883D01*
X781899Y198050D01*
X783232Y197883D01*
X784399Y197217D01*
X785399Y196217D01*
X786066Y195050D01*
X786399Y193717D01*
Y192383D01*
X786066Y191050D01*
X785399Y189883D01*
X784399Y188883D01*
X783232Y188217D01*
X781899Y188050D01*
G01X789166D02*
Y198050D01*
X793332D01*
X794666Y197550D01*
X795499Y196883D01*
X795832Y195550D01*
X795499Y194217D01*
X794499Y193383D01*
X793332Y192883D01*
X789166D01*
G01X793332D02*
X795832Y188050D01*
G01X805099D02*
Y198050D01*
X798932Y190883D01*
X807266D01*
G01X692208Y1771767D02*
X692083Y1771517D01*
X692000Y1771225D01*
Y1770892D01*
X692125Y1770517D01*
X692333Y1770225D01*
X692583Y1770017D01*
X693000Y1769850D01*
X693375Y1769808D01*
X693750Y1769892D01*
X694000Y1770017D01*
X694250Y1770267D01*
X694417Y1770558D01*
X694500Y1770850D01*
Y1771142D01*
X694417Y1771433D01*
X694292Y1771683D01*
X694125Y1771892D01*
G01X694000Y1773033D02*
X694292Y1773283D01*
X694458Y1773617D01*
X694500Y1773992D01*
X694458Y1774325D01*
X694250Y1774658D01*
X694000Y1774867D01*
X693750Y1774908D01*
X693458Y1774825D01*
X693250Y1774533D01*
X693167Y1774242D01*
Y1773867D01*
G01Y1774242D02*
X693042Y1774492D01*
X692833Y1774700D01*
X692583Y1774783D01*
X692333Y1774700D01*
X692125Y1774492D01*
X692000Y1774117D01*
X692042Y1773742D01*
X692208Y1773367D01*
G01X693458Y1776258D02*
X693167Y1776550D01*
X693000Y1776800D01*
X692917Y1777133D01*
X693000Y1777425D01*
X693167Y1777633D01*
X693417Y1777800D01*
X693708Y1777842D01*
X693958Y1777800D01*
X694208Y1777633D01*
X694417Y1777383D01*
X694500Y1777092D01*
X694417Y1776758D01*
X694167Y1776467D01*
X693792Y1776300D01*
X693375Y1776258D01*
X692833Y1776342D01*
X692542Y1776467D01*
X692250Y1776675D01*
X692042Y1776967D01*
X692000Y1777258D01*
X692083Y1777550D01*
X692292Y1777758D01*
G01X694500Y1780150D02*
X692000D01*
X692500Y1779650D01*
G01X694500D02*
Y1780650D01*
G01X692208Y1784767D02*
X692083Y1784517D01*
X692000Y1784225D01*
Y1783892D01*
X692125Y1783517D01*
X692333Y1783225D01*
X692583Y1783017D01*
X693000Y1782850D01*
X693375Y1782808D01*
X693750Y1782892D01*
X694000Y1783017D01*
X694250Y1783267D01*
X694417Y1783558D01*
X694500Y1783850D01*
Y1784142D01*
X694417Y1784433D01*
X694292Y1784683D01*
X694125Y1784892D01*
G01X694000Y1786033D02*
X694292Y1786283D01*
X694458Y1786617D01*
X694500Y1786992D01*
X694458Y1787325D01*
X694250Y1787658D01*
X694000Y1787867D01*
X693750Y1787908D01*
X693458Y1787825D01*
X693250Y1787533D01*
X693167Y1787242D01*
Y1786867D01*
G01Y1787242D02*
X693042Y1787492D01*
X692833Y1787700D01*
X692583Y1787783D01*
X692333Y1787700D01*
X692125Y1787492D01*
X692000Y1787117D01*
X692042Y1786742D01*
X692208Y1786367D01*
G01X693458Y1789258D02*
X693167Y1789550D01*
X693000Y1789800D01*
X692917Y1790133D01*
X693000Y1790425D01*
X693167Y1790633D01*
X693417Y1790800D01*
X693708Y1790842D01*
X693958Y1790800D01*
X694208Y1790633D01*
X694417Y1790383D01*
X694500Y1790092D01*
X694417Y1789758D01*
X694167Y1789467D01*
X693792Y1789300D01*
X693375Y1789258D01*
X692833Y1789342D01*
X692542Y1789467D01*
X692250Y1789675D01*
X692042Y1789967D01*
X692000Y1790258D01*
X692083Y1790550D01*
X692292Y1790758D01*
G01X692417Y1792358D02*
X692167Y1792608D01*
X692042Y1792900D01*
X692000Y1793233D01*
X692083Y1793650D01*
X692292Y1793942D01*
X692542Y1794025D01*
X692792Y1793983D01*
X693000Y1793817D01*
X693417Y1792983D01*
X693708Y1792608D01*
X694125Y1792358D01*
X694500Y1792275D01*
Y1794025D01*
G01X702749Y1799634D02*
Y1803634D01*
X695349D01*
G01X687707Y1827817D02*
X687582Y1827567D01*
X687499Y1827275D01*
Y1826942D01*
X687624Y1826567D01*
X687832Y1826275D01*
X688082Y1826067D01*
X688499Y1825900D01*
X688874Y1825858D01*
X689249Y1825942D01*
X689499Y1826067D01*
X689749Y1826317D01*
X689916Y1826608D01*
X689999Y1826900D01*
Y1827192D01*
X689916Y1827483D01*
X689791Y1827733D01*
X689624Y1827942D01*
G01X689499Y1829083D02*
X689791Y1829333D01*
X689957Y1829667D01*
X689999Y1830042D01*
X689957Y1830375D01*
X689749Y1830708D01*
X689499Y1830917D01*
X689249Y1830958D01*
X688957Y1830875D01*
X688749Y1830583D01*
X688666Y1830292D01*
Y1829917D01*
G01Y1830292D02*
X688541Y1830542D01*
X688332Y1830750D01*
X688082Y1830833D01*
X687832Y1830750D01*
X687624Y1830542D01*
X687499Y1830167D01*
X687541Y1829792D01*
X687707Y1829417D01*
G01X689624Y1832183D02*
X689832Y1832433D01*
X689957Y1832725D01*
X689999Y1833100D01*
X689916Y1833475D01*
X689749Y1833767D01*
X689457Y1833975D01*
X689124Y1834017D01*
X688791Y1833933D01*
X688582Y1833725D01*
X688416Y1833433D01*
X688374Y1833142D01*
X688416Y1832850D01*
X688582Y1832475D01*
X687499Y1832600D01*
Y1833725D01*
G01X687916Y1835408D02*
X687666Y1835658D01*
X687541Y1835950D01*
X687499Y1836283D01*
X687582Y1836700D01*
X687791Y1836992D01*
X688041Y1837075D01*
X688291Y1837033D01*
X688499Y1836867D01*
X688916Y1836033D01*
X689207Y1835658D01*
X689624Y1835408D01*
X689999Y1835325D01*
Y1837075D01*
G01X691849Y1823634D02*
Y1819634D01*
X699249D01*
G01X691849Y1827634D02*
Y1823634D01*
X699249D01*
G01X702749Y1806634D02*
Y1810634D01*
X695349D01*
G01X714622Y323186D02*
Y325686D01*
X715663D01*
X715997Y325561D01*
X716205Y325394D01*
X716288Y325061D01*
X716205Y324728D01*
X715955Y324519D01*
X715663Y324394D01*
X714622D01*
G01X715663D02*
X716288Y323186D01*
G01X718555D02*
Y325686D01*
X718055Y325186D01*
G01Y323186D02*
X719055D01*
G01X720863Y324228D02*
X721155Y324519D01*
X721405Y324686D01*
X721738Y324769D01*
X722030Y324686D01*
X722238Y324519D01*
X722405Y324269D01*
X722447Y323978D01*
X722405Y323728D01*
X722238Y323478D01*
X721988Y323269D01*
X721697Y323186D01*
X721363Y323269D01*
X721072Y323519D01*
X720905Y323894D01*
X720863Y324311D01*
X720947Y324853D01*
X721072Y325144D01*
X721280Y325436D01*
X721572Y325644D01*
X721863Y325686D01*
X722155Y325603D01*
X722363Y325394D01*
G01X725255Y323186D02*
Y325686D01*
X723713Y323894D01*
X725797D01*
G01X714643Y327312D02*
Y329812D01*
X715684D01*
X716018Y329687D01*
X716226Y329520D01*
X716309Y329187D01*
X716226Y328854D01*
X715976Y328645D01*
X715684Y328520D01*
X714643D01*
G01X715684D02*
X716309Y327312D01*
G01X718576D02*
Y329812D01*
X718076Y329312D01*
G01Y327312D02*
X719076D01*
G01X720884Y328354D02*
X721176Y328645D01*
X721426Y328812D01*
X721759Y328895D01*
X722051Y328812D01*
X722259Y328645D01*
X722426Y328395D01*
X722468Y328104D01*
X722426Y327854D01*
X722259Y327604D01*
X722009Y327395D01*
X721718Y327312D01*
X721384Y327395D01*
X721093Y327645D01*
X720926Y328020D01*
X720884Y328437D01*
X720968Y328979D01*
X721093Y329270D01*
X721301Y329562D01*
X721593Y329770D01*
X721884Y329812D01*
X722176Y329729D01*
X722384Y329520D01*
G01X724068Y327604D02*
X724359Y327395D01*
X724693Y327312D01*
X725026Y327395D01*
X725318Y327645D01*
X725526Y328020D01*
X725609Y328395D01*
Y328854D01*
X725526Y329229D01*
X725318Y329562D01*
X725068Y329729D01*
X724776Y329812D01*
X724443Y329729D01*
X724193Y329562D01*
X724026Y329312D01*
X723943Y328979D01*
X724026Y328687D01*
X724234Y328395D01*
X724484Y328229D01*
X724776Y328187D01*
X725109Y328270D01*
X725359Y328479D01*
X725609Y328854D01*
G01X713372Y1124234D02*
Y1126734D01*
X714413D01*
X714747Y1126609D01*
X714955Y1126442D01*
X715038Y1126109D01*
X714955Y1125776D01*
X714705Y1125567D01*
X714413Y1125442D01*
X713372D01*
G01X714413D02*
X715038Y1124234D01*
G01X717305D02*
Y1126734D01*
X716805Y1126234D01*
G01Y1124234D02*
X717805D01*
G01X719488Y1124734D02*
X719738Y1124442D01*
X720072Y1124276D01*
X720447Y1124234D01*
X720780Y1124276D01*
X721113Y1124484D01*
X721322Y1124734D01*
X721363Y1124984D01*
X721280Y1125276D01*
X720988Y1125484D01*
X720697Y1125567D01*
X720322D01*
G01X720697D02*
X720947Y1125692D01*
X721155Y1125901D01*
X721238Y1126151D01*
X721155Y1126401D01*
X720947Y1126609D01*
X720572Y1126734D01*
X720197Y1126692D01*
X719822Y1126526D01*
G01X722588Y1124609D02*
X722838Y1124401D01*
X723130Y1124276D01*
X723505Y1124234D01*
X723880Y1124317D01*
X724172Y1124484D01*
X724380Y1124776D01*
X724422Y1125109D01*
X724338Y1125442D01*
X724130Y1125651D01*
X723838Y1125817D01*
X723547Y1125859D01*
X723255Y1125817D01*
X722880Y1125651D01*
X723005Y1126734D01*
X724130D01*
G01X713538Y1128392D02*
Y1130892D01*
X714579D01*
X714913Y1130767D01*
X715121Y1130600D01*
X715204Y1130267D01*
X715121Y1129934D01*
X714871Y1129725D01*
X714579Y1129600D01*
X713538D01*
G01X714579D02*
X715204Y1128392D01*
G01X717471D02*
Y1130892D01*
X716971Y1130392D01*
G01Y1128392D02*
X717971D01*
G01X721071D02*
Y1130892D01*
X719529Y1129100D01*
X721613D01*
G01X723671Y1128392D02*
Y1130892D01*
X723171Y1130392D01*
G01Y1128392D02*
X724171D01*
G01X710000Y1753000D02*
Y1743000D01*
G01X706167Y1753000D02*
X713833D01*
G01X723933Y1743000D02*
X717267D01*
Y1753000D01*
X723933D01*
G01X721267Y1748167D02*
X717267D01*
G01X726867Y1743000D02*
Y1753000D01*
X731200Y1744667D01*
X735533Y1753000D01*
Y1743000D01*
G01X738467D02*
Y1753000D01*
X742467D01*
X743800Y1752500D01*
X744800Y1751333D01*
X745133Y1750000D01*
X744800Y1748667D01*
X743967Y1747667D01*
X742467Y1747166D01*
X738467D01*
G01X747400Y1739667D02*
X757400D01*
G01X759500Y1744333D02*
X760833Y1743500D01*
X762333Y1743000D01*
X763667D01*
X765000Y1743500D01*
X766000Y1744333D01*
X766500Y1745500D01*
X766167Y1746666D01*
X765333Y1747667D01*
X763833Y1748333D01*
X761833Y1748667D01*
X760667Y1749333D01*
X760167Y1750500D01*
X760500Y1751667D01*
X761333Y1752500D01*
X762500Y1753000D01*
X763667D01*
X764833Y1752667D01*
X765833Y1751833D01*
G01X776933Y1743000D02*
X770267D01*
Y1753000D01*
X776933D01*
G01X774267Y1748167D02*
X770267D01*
G01X780367Y1743000D02*
Y1753000D01*
X788033Y1743000D01*
Y1753000D01*
G01X791300Y1744333D02*
X792633Y1743500D01*
X794133Y1743000D01*
X795467D01*
X796800Y1743500D01*
X797800Y1744333D01*
X798300Y1745500D01*
X797967Y1746666D01*
X797133Y1747667D01*
X795633Y1748333D01*
X793633Y1748667D01*
X792467Y1749333D01*
X791967Y1750500D01*
X792300Y1751667D01*
X793133Y1752500D01*
X794300Y1753000D01*
X795467D01*
X796633Y1752667D01*
X797633Y1751833D01*
G01X805400Y1743000D02*
X804066Y1743167D01*
X802900Y1743833D01*
X801900Y1744833D01*
X801233Y1746000D01*
X800900Y1747333D01*
Y1748667D01*
X801233Y1750000D01*
X801900Y1751167D01*
X802900Y1752167D01*
X804066Y1752833D01*
X805400Y1753000D01*
X806733Y1752833D01*
X807900Y1752167D01*
X808900Y1751167D01*
X809567Y1750000D01*
X809900Y1748667D01*
Y1747333D01*
X809567Y1746000D01*
X808900Y1744833D01*
X807900Y1743833D01*
X806733Y1743167D01*
X805400Y1743000D01*
G01X812667D02*
Y1753000D01*
X816833D01*
X818167Y1752500D01*
X819000Y1751833D01*
X819333Y1750500D01*
X819000Y1749167D01*
X818000Y1748333D01*
X816833Y1747833D01*
X812667D01*
G01X816833D02*
X819333Y1743000D01*
G01X822933Y1745000D02*
X823933Y1743833D01*
X825266Y1743167D01*
X826767Y1743000D01*
X828100Y1743167D01*
X829433Y1744000D01*
X830267Y1745000D01*
X830433Y1746000D01*
X830100Y1747166D01*
X828933Y1748000D01*
X827767Y1748333D01*
X826267D01*
G01X827767D02*
X828767Y1748833D01*
X829600Y1749666D01*
X829933Y1750667D01*
X829600Y1751667D01*
X828767Y1752500D01*
X827267Y1753000D01*
X825767Y1752833D01*
X824267Y1752167D01*
G01X698066Y1783134D02*
Y1785634D01*
X699107D01*
X699441Y1785509D01*
X699649Y1785342D01*
X699732Y1785009D01*
X699649Y1784676D01*
X699399Y1784467D01*
X699107Y1784342D01*
X698066D01*
G01X699107D02*
X699732Y1783134D01*
G01X701082Y1783634D02*
X701332Y1783342D01*
X701666Y1783176D01*
X702041Y1783134D01*
X702374Y1783176D01*
X702707Y1783384D01*
X702916Y1783634D01*
X702957Y1783884D01*
X702874Y1784176D01*
X702582Y1784384D01*
X702291Y1784467D01*
X701916D01*
G01X702291D02*
X702541Y1784592D01*
X702749Y1784801D01*
X702832Y1785051D01*
X702749Y1785301D01*
X702541Y1785509D01*
X702166Y1785634D01*
X701791Y1785592D01*
X701416Y1785426D01*
G01X704307Y1784176D02*
X704599Y1784467D01*
X704849Y1784634D01*
X705182Y1784717D01*
X705474Y1784634D01*
X705682Y1784467D01*
X705849Y1784217D01*
X705891Y1783926D01*
X705849Y1783676D01*
X705682Y1783426D01*
X705432Y1783217D01*
X705141Y1783134D01*
X704807Y1783217D01*
X704516Y1783467D01*
X704349Y1783842D01*
X704307Y1784259D01*
X704391Y1784801D01*
X704516Y1785092D01*
X704724Y1785384D01*
X705016Y1785592D01*
X705307Y1785634D01*
X705599Y1785551D01*
X705807Y1785342D01*
G01X708199Y1783134D02*
Y1785634D01*
X707699Y1785134D01*
G01Y1783134D02*
X708699D01*
G01X698066Y1787134D02*
Y1789634D01*
X699107D01*
X699441Y1789509D01*
X699649Y1789342D01*
X699732Y1789009D01*
X699649Y1788676D01*
X699399Y1788467D01*
X699107Y1788342D01*
X698066D01*
G01X699107D02*
X699732Y1787134D01*
G01X701082Y1787634D02*
X701332Y1787342D01*
X701666Y1787176D01*
X702041Y1787134D01*
X702374Y1787176D01*
X702707Y1787384D01*
X702916Y1787634D01*
X702957Y1787884D01*
X702874Y1788176D01*
X702582Y1788384D01*
X702291Y1788467D01*
X701916D01*
G01X702291D02*
X702541Y1788592D01*
X702749Y1788801D01*
X702832Y1789051D01*
X702749Y1789301D01*
X702541Y1789509D01*
X702166Y1789634D01*
X701791Y1789592D01*
X701416Y1789426D01*
G01X705099Y1787134D02*
X705391Y1787176D01*
X705724Y1787301D01*
X705932Y1787509D01*
X706016Y1787801D01*
X705932Y1788092D01*
X705682Y1788342D01*
X705307Y1788467D01*
X704891D01*
X704641Y1788551D01*
X704432Y1788759D01*
X704349Y1789051D01*
X704474Y1789342D01*
X704766Y1789551D01*
X705099Y1789634D01*
X705432Y1789551D01*
X705724Y1789342D01*
X705849Y1789051D01*
X705766Y1788759D01*
X705557Y1788551D01*
X705307Y1788467D01*
X704891D01*
X704516Y1788342D01*
X704266Y1788092D01*
X704182Y1787801D01*
X704266Y1787509D01*
X704474Y1787301D01*
X704807Y1787176D01*
X705099Y1787134D01*
G01X707407Y1788176D02*
X707699Y1788467D01*
X707949Y1788634D01*
X708282Y1788717D01*
X708574Y1788634D01*
X708782Y1788467D01*
X708949Y1788217D01*
X708991Y1787926D01*
X708949Y1787676D01*
X708782Y1787426D01*
X708532Y1787217D01*
X708241Y1787134D01*
X707907Y1787217D01*
X707616Y1787467D01*
X707449Y1787842D01*
X707407Y1788259D01*
X707491Y1788801D01*
X707616Y1789092D01*
X707824Y1789384D01*
X708116Y1789592D01*
X708407Y1789634D01*
X708699Y1789551D01*
X708907Y1789342D01*
G01X699816Y1793426D02*
X699566Y1793551D01*
X699274Y1793634D01*
X698941D01*
X698566Y1793509D01*
X698274Y1793301D01*
X698066Y1793051D01*
X697899Y1792634D01*
X697857Y1792259D01*
X697941Y1791884D01*
X698066Y1791634D01*
X698316Y1791384D01*
X698607Y1791217D01*
X698899Y1791134D01*
X699191D01*
X699482Y1791217D01*
X699732Y1791342D01*
X699941Y1791509D01*
G01X701082Y1791634D02*
X701332Y1791342D01*
X701666Y1791176D01*
X702041Y1791134D01*
X702374Y1791176D01*
X702707Y1791384D01*
X702916Y1791634D01*
X702957Y1791884D01*
X702874Y1792176D01*
X702582Y1792384D01*
X702291Y1792467D01*
X701916D01*
G01X702291D02*
X702541Y1792592D01*
X702749Y1792801D01*
X702832Y1793051D01*
X702749Y1793301D01*
X702541Y1793509D01*
X702166Y1793634D01*
X701791Y1793592D01*
X701416Y1793426D01*
G01X704307Y1792176D02*
X704599Y1792467D01*
X704849Y1792634D01*
X705182Y1792717D01*
X705474Y1792634D01*
X705682Y1792467D01*
X705849Y1792217D01*
X705891Y1791926D01*
X705849Y1791676D01*
X705682Y1791426D01*
X705432Y1791217D01*
X705141Y1791134D01*
X704807Y1791217D01*
X704516Y1791467D01*
X704349Y1791842D01*
X704307Y1792259D01*
X704391Y1792801D01*
X704516Y1793092D01*
X704724Y1793384D01*
X705016Y1793592D01*
X705307Y1793634D01*
X705599Y1793551D01*
X705807Y1793342D01*
G01X707282Y1791634D02*
X707532Y1791342D01*
X707866Y1791176D01*
X708241Y1791134D01*
X708574Y1791176D01*
X708907Y1791384D01*
X709116Y1791634D01*
X709157Y1791884D01*
X709074Y1792176D01*
X708782Y1792384D01*
X708491Y1792467D01*
X708116D01*
G01X708491D02*
X708741Y1792592D01*
X708949Y1792801D01*
X709032Y1793051D01*
X708949Y1793301D01*
X708741Y1793509D01*
X708366Y1793634D01*
X707991Y1793592D01*
X707616Y1793426D01*
G01X714549Y1814034D02*
X710549D01*
Y1806634D01*
G01X706549D02*
X710549D01*
Y1814034D01*
G01X708549Y1803334D02*
X704549D01*
Y1795934D01*
G01X708549D02*
X712549D01*
Y1803334D01*
G01X701066Y1820634D02*
Y1823134D01*
X702107D01*
X702441Y1823009D01*
X702649Y1822842D01*
X702732Y1822509D01*
X702649Y1822176D01*
X702399Y1821967D01*
X702107Y1821842D01*
X701066D01*
G01X702107D02*
X702732Y1820634D01*
G01X704082Y1821134D02*
X704332Y1820842D01*
X704666Y1820676D01*
X705041Y1820634D01*
X705374Y1820676D01*
X705707Y1820884D01*
X705916Y1821134D01*
X705957Y1821384D01*
X705874Y1821676D01*
X705582Y1821884D01*
X705291Y1821967D01*
X704916D01*
G01X705291D02*
X705541Y1822092D01*
X705749Y1822301D01*
X705832Y1822551D01*
X705749Y1822801D01*
X705541Y1823009D01*
X705166Y1823134D01*
X704791Y1823092D01*
X704416Y1822926D01*
G01X708016Y1820634D02*
X708099Y1821176D01*
X708224Y1821634D01*
X708391Y1822051D01*
X708599Y1822509D01*
X708932Y1823134D01*
X707266D01*
G01X710491Y1820926D02*
X710782Y1820717D01*
X711116Y1820634D01*
X711449Y1820717D01*
X711741Y1820967D01*
X711949Y1821342D01*
X712032Y1821717D01*
Y1822176D01*
X711949Y1822551D01*
X711741Y1822884D01*
X711491Y1823051D01*
X711199Y1823134D01*
X710866Y1823051D01*
X710616Y1822884D01*
X710449Y1822634D01*
X710366Y1822301D01*
X710449Y1822009D01*
X710657Y1821717D01*
X710907Y1821551D01*
X711199Y1821509D01*
X711532Y1821592D01*
X711782Y1821801D01*
X712032Y1822176D01*
G01X701066Y1824634D02*
Y1827134D01*
X702107D01*
X702441Y1827009D01*
X702649Y1826842D01*
X702732Y1826509D01*
X702649Y1826176D01*
X702399Y1825967D01*
X702107Y1825842D01*
X701066D01*
G01X702107D02*
X702732Y1824634D01*
G01X704082Y1825134D02*
X704332Y1824842D01*
X704666Y1824676D01*
X705041Y1824634D01*
X705374Y1824676D01*
X705707Y1824884D01*
X705916Y1825134D01*
X705957Y1825384D01*
X705874Y1825676D01*
X705582Y1825884D01*
X705291Y1825967D01*
X704916D01*
G01X705291D02*
X705541Y1826092D01*
X705749Y1826301D01*
X705832Y1826551D01*
X705749Y1826801D01*
X705541Y1827009D01*
X705166Y1827134D01*
X704791Y1827092D01*
X704416Y1826926D01*
G01X708099Y1824634D02*
X708391Y1824676D01*
X708724Y1824801D01*
X708932Y1825009D01*
X709016Y1825301D01*
X708932Y1825592D01*
X708682Y1825842D01*
X708307Y1825967D01*
X707891D01*
X707641Y1826051D01*
X707432Y1826259D01*
X707349Y1826551D01*
X707474Y1826842D01*
X707766Y1827051D01*
X708099Y1827134D01*
X708432Y1827051D01*
X708724Y1826842D01*
X708849Y1826551D01*
X708766Y1826259D01*
X708557Y1826051D01*
X708307Y1825967D01*
X707891D01*
X707516Y1825842D01*
X707266Y1825592D01*
X707182Y1825301D01*
X707266Y1825009D01*
X707474Y1824801D01*
X707807Y1824676D01*
X708099Y1824634D01*
G01X710407Y1826717D02*
X710657Y1826967D01*
X710949Y1827092D01*
X711282Y1827134D01*
X711699Y1827051D01*
X711991Y1826842D01*
X712074Y1826592D01*
X712032Y1826342D01*
X711866Y1826134D01*
X711032Y1825717D01*
X710657Y1825426D01*
X710407Y1825009D01*
X710324Y1824634D01*
X712074D01*
G01X719049Y1812851D02*
X716549D01*
Y1813892D01*
X716674Y1814226D01*
X716841Y1814434D01*
X717174Y1814517D01*
X717507Y1814434D01*
X717716Y1814184D01*
X717841Y1813892D01*
Y1812851D01*
G01Y1813892D02*
X719049Y1814517D01*
G01X718549Y1815867D02*
X718841Y1816117D01*
X719007Y1816451D01*
X719049Y1816826D01*
X719007Y1817159D01*
X718799Y1817492D01*
X718549Y1817701D01*
X718299Y1817742D01*
X718007Y1817659D01*
X717799Y1817367D01*
X717716Y1817076D01*
Y1816701D01*
G01Y1817076D02*
X717591Y1817326D01*
X717382Y1817534D01*
X717132Y1817617D01*
X716882Y1817534D01*
X716674Y1817326D01*
X716549Y1816951D01*
X716591Y1816576D01*
X716757Y1816201D01*
G01X719049Y1819884D02*
X719007Y1820176D01*
X718882Y1820509D01*
X718674Y1820717D01*
X718382Y1820801D01*
X718091Y1820717D01*
X717841Y1820467D01*
X717716Y1820092D01*
Y1819676D01*
X717632Y1819426D01*
X717424Y1819217D01*
X717132Y1819134D01*
X716841Y1819259D01*
X716632Y1819551D01*
X716549Y1819884D01*
X716632Y1820217D01*
X716841Y1820509D01*
X717132Y1820634D01*
X717424Y1820551D01*
X717632Y1820342D01*
X717716Y1820092D01*
Y1819676D01*
X717841Y1819301D01*
X718091Y1819051D01*
X718382Y1818967D01*
X718674Y1819051D01*
X718882Y1819259D01*
X719007Y1819592D01*
X719049Y1819884D01*
G01X718757Y1822276D02*
X718966Y1822567D01*
X719049Y1822901D01*
X718966Y1823234D01*
X718716Y1823526D01*
X718341Y1823734D01*
X717966Y1823817D01*
X717507D01*
X717132Y1823734D01*
X716799Y1823526D01*
X716632Y1823276D01*
X716549Y1822984D01*
X716632Y1822651D01*
X716799Y1822401D01*
X717049Y1822234D01*
X717382Y1822151D01*
X717674Y1822234D01*
X717966Y1822442D01*
X718132Y1822692D01*
X718174Y1822984D01*
X718091Y1823317D01*
X717882Y1823567D01*
X717507Y1823817D01*
G01X733143Y327312D02*
Y329812D01*
X734184D01*
X734518Y329687D01*
X734726Y329520D01*
X734809Y329187D01*
X734726Y328854D01*
X734476Y328645D01*
X734184Y328520D01*
X733143D01*
G01X734184D02*
X734809Y327312D01*
G01X737576D02*
Y329812D01*
X736034Y328020D01*
X738118D01*
G01X740676Y327312D02*
Y329812D01*
X739134Y328020D01*
X741218D01*
G01X743276Y329812D02*
X742943Y329729D01*
X742693Y329520D01*
X742526Y329270D01*
X742401Y328937D01*
X742359Y328562D01*
X742401Y328187D01*
X742526Y327854D01*
X742693Y327604D01*
X742943Y327395D01*
X743276Y327312D01*
X743609Y327395D01*
X743859Y327604D01*
X744026Y327854D01*
X744151Y328187D01*
X744193Y328562D01*
X744151Y328937D01*
X744026Y329270D01*
X743859Y329520D01*
X743609Y329729D01*
X743276Y329812D01*
G01X733143Y323312D02*
Y325812D01*
X734184D01*
X734518Y325687D01*
X734726Y325520D01*
X734809Y325187D01*
X734726Y324854D01*
X734476Y324645D01*
X734184Y324520D01*
X733143D01*
G01X734184D02*
X734809Y323312D01*
G01X737576D02*
Y325812D01*
X736034Y324020D01*
X738118D01*
G01X740676Y323312D02*
Y325812D01*
X739134Y324020D01*
X741218D01*
G01X743276Y323312D02*
Y325812D01*
X742776Y325312D01*
G01Y323312D02*
X743776D01*
G01X728626Y323295D02*
X730418D01*
X730793Y323462D01*
X731043Y323795D01*
X731126Y324212D01*
X731043Y324629D01*
X730793Y324962D01*
X730418Y325129D01*
X728626D01*
G01X731126Y327312D02*
X728626D01*
X729126Y326812D01*
G01X731126D02*
Y327812D01*
G01X730751Y329495D02*
X730959Y329745D01*
X731084Y330037D01*
X731126Y330412D01*
X731043Y330787D01*
X730876Y331079D01*
X730584Y331287D01*
X730251Y331329D01*
X729918Y331245D01*
X729709Y331037D01*
X729543Y330745D01*
X729501Y330454D01*
X729543Y330162D01*
X729709Y329787D01*
X728626Y329912D01*
Y331037D01*
G01X730894Y723566D02*
Y726066D01*
X731935D01*
X732269Y725941D01*
X732477Y725774D01*
X732560Y725441D01*
X732477Y725108D01*
X732227Y724899D01*
X731935Y724774D01*
X730894D01*
G01X731935D02*
X732560Y723566D01*
G01X734827D02*
Y726066D01*
X734327Y725566D01*
G01Y723566D02*
X735327D01*
G01X738427D02*
Y726066D01*
X736885Y724274D01*
X738969D01*
G01X740944Y723566D02*
X741027Y724108D01*
X741152Y724566D01*
X741319Y724983D01*
X741527Y725441D01*
X741860Y726066D01*
X740194D01*
G01X730894Y728566D02*
Y731066D01*
X731935D01*
X732269Y730941D01*
X732477Y730774D01*
X732560Y730441D01*
X732477Y730108D01*
X732227Y729899D01*
X731935Y729774D01*
X730894D01*
G01X731935D02*
X732560Y728566D01*
G01X734827D02*
Y731066D01*
X734327Y730566D01*
G01Y728566D02*
X735327D01*
G01X737010Y728941D02*
X737260Y728733D01*
X737552Y728608D01*
X737927Y728566D01*
X738302Y728649D01*
X738594Y728816D01*
X738802Y729108D01*
X738844Y729441D01*
X738760Y729774D01*
X738552Y729983D01*
X738260Y730149D01*
X737969Y730191D01*
X737677Y730149D01*
X737302Y729983D01*
X737427Y731066D01*
X738552D01*
G01X740110Y728941D02*
X740360Y728733D01*
X740652Y728608D01*
X741027Y728566D01*
X741402Y728649D01*
X741694Y728816D01*
X741902Y729108D01*
X741944Y729441D01*
X741860Y729774D01*
X741652Y729983D01*
X741360Y730149D01*
X741069Y730191D01*
X740777Y730149D01*
X740402Y729983D01*
X740527Y731066D01*
X741652D01*
G01X731038Y1128392D02*
Y1130892D01*
X732079D01*
X732413Y1130767D01*
X732621Y1130600D01*
X732704Y1130267D01*
X732621Y1129934D01*
X732371Y1129725D01*
X732079Y1129600D01*
X731038D01*
G01X732079D02*
X732704Y1128392D01*
G01X735471D02*
Y1130892D01*
X733929Y1129100D01*
X736013D01*
G01X737154Y1128892D02*
X737404Y1128600D01*
X737738Y1128434D01*
X738113Y1128392D01*
X738446Y1128434D01*
X738779Y1128642D01*
X738988Y1128892D01*
X739029Y1129142D01*
X738946Y1129434D01*
X738654Y1129642D01*
X738363Y1129725D01*
X737988D01*
G01X738363D02*
X738613Y1129850D01*
X738821Y1130059D01*
X738904Y1130309D01*
X738821Y1130559D01*
X738613Y1130767D01*
X738238Y1130892D01*
X737863Y1130850D01*
X737488Y1130684D01*
G01X740379Y1130475D02*
X740629Y1130725D01*
X740921Y1130850D01*
X741254Y1130892D01*
X741671Y1130809D01*
X741963Y1130600D01*
X742046Y1130350D01*
X742004Y1130100D01*
X741838Y1129892D01*
X741004Y1129475D01*
X740629Y1129184D01*
X740379Y1128767D01*
X740296Y1128392D01*
X742046D01*
G01X731038Y1124392D02*
Y1126892D01*
X732079D01*
X732413Y1126767D01*
X732621Y1126600D01*
X732704Y1126267D01*
X732621Y1125934D01*
X732371Y1125725D01*
X732079Y1125600D01*
X731038D01*
G01X732079D02*
X732704Y1124392D01*
G01X735471D02*
Y1126892D01*
X733929Y1125100D01*
X736013D01*
G01X737154Y1124892D02*
X737404Y1124600D01*
X737738Y1124434D01*
X738113Y1124392D01*
X738446Y1124434D01*
X738779Y1124642D01*
X738988Y1124892D01*
X739029Y1125142D01*
X738946Y1125434D01*
X738654Y1125642D01*
X738363Y1125725D01*
X737988D01*
G01X738363D02*
X738613Y1125850D01*
X738821Y1126059D01*
X738904Y1126309D01*
X738821Y1126559D01*
X738613Y1126767D01*
X738238Y1126892D01*
X737863Y1126850D01*
X737488Y1126684D01*
G01X740254Y1124892D02*
X740504Y1124600D01*
X740838Y1124434D01*
X741213Y1124392D01*
X741546Y1124434D01*
X741879Y1124642D01*
X742088Y1124892D01*
X742129Y1125142D01*
X742046Y1125434D01*
X741754Y1125642D01*
X741463Y1125725D01*
X741088D01*
G01X741463D02*
X741713Y1125850D01*
X741921Y1126059D01*
X742004Y1126309D01*
X741921Y1126559D01*
X741713Y1126767D01*
X741338Y1126892D01*
X740963Y1126850D01*
X740588Y1126684D01*
G01X726521Y1124425D02*
X728313D01*
X728688Y1124592D01*
X728938Y1124925D01*
X729021Y1125342D01*
X728938Y1125759D01*
X728688Y1126092D01*
X728313Y1126259D01*
X726521D01*
G01X728729Y1127734D02*
X728938Y1128025D01*
X729021Y1128359D01*
X728938Y1128692D01*
X728688Y1128984D01*
X728313Y1129192D01*
X727938Y1129275D01*
X727479D01*
X727104Y1129192D01*
X726771Y1128984D01*
X726604Y1128734D01*
X726521Y1128442D01*
X726604Y1128109D01*
X726771Y1127859D01*
X727021Y1127692D01*
X727354Y1127609D01*
X727646Y1127692D01*
X727938Y1127900D01*
X728104Y1128150D01*
X728146Y1128442D01*
X728063Y1128775D01*
X727854Y1129025D01*
X727479Y1129275D01*
G01X718630Y1534191D02*
Y1536691D01*
X719671D01*
X720005Y1536566D01*
X720213Y1536399D01*
X720296Y1536066D01*
X720213Y1535733D01*
X719963Y1535524D01*
X719671Y1535399D01*
X718630D01*
G01X719671D02*
X720296Y1534191D01*
G01X722563D02*
Y1536691D01*
X722063Y1536191D01*
G01Y1534191D02*
X723063D01*
G01X725663D02*
Y1536691D01*
X725163Y1536191D01*
G01Y1534191D02*
X726163D01*
G01X728055Y1534483D02*
X728346Y1534274D01*
X728680Y1534191D01*
X729013Y1534274D01*
X729305Y1534524D01*
X729513Y1534899D01*
X729596Y1535274D01*
Y1535733D01*
X729513Y1536108D01*
X729305Y1536441D01*
X729055Y1536608D01*
X728763Y1536691D01*
X728430Y1536608D01*
X728180Y1536441D01*
X728013Y1536191D01*
X727930Y1535858D01*
X728013Y1535566D01*
X728221Y1535274D01*
X728471Y1535108D01*
X728763Y1535066D01*
X729096Y1535149D01*
X729346Y1535358D01*
X729596Y1535733D01*
G01X718630Y1539191D02*
Y1541691D01*
X719671D01*
X720005Y1541566D01*
X720213Y1541399D01*
X720296Y1541066D01*
X720213Y1540733D01*
X719963Y1540524D01*
X719671Y1540399D01*
X718630D01*
G01X719671D02*
X720296Y1539191D01*
G01X722563D02*
Y1541691D01*
X722063Y1541191D01*
G01Y1539191D02*
X723063D01*
G01X724871Y1541274D02*
X725121Y1541524D01*
X725413Y1541649D01*
X725746Y1541691D01*
X726163Y1541608D01*
X726455Y1541399D01*
X726538Y1541149D01*
X726496Y1540899D01*
X726330Y1540691D01*
X725496Y1540274D01*
X725121Y1539983D01*
X724871Y1539566D01*
X724788Y1539191D01*
X726538D01*
G01X728680D02*
X728763Y1539733D01*
X728888Y1540191D01*
X729055Y1540608D01*
X729263Y1541066D01*
X729596Y1541691D01*
X727930D01*
G01X735484Y1534288D02*
Y1536788D01*
X736525D01*
X736859Y1536663D01*
X737067Y1536496D01*
X737150Y1536163D01*
X737067Y1535830D01*
X736817Y1535621D01*
X736525Y1535496D01*
X735484D01*
G01X736525D02*
X737150Y1534288D01*
G01X739917D02*
Y1536788D01*
X738375Y1534996D01*
X740459D01*
G01X741725Y1536371D02*
X741975Y1536621D01*
X742267Y1536746D01*
X742600Y1536788D01*
X743017Y1536705D01*
X743309Y1536496D01*
X743392Y1536246D01*
X743350Y1535996D01*
X743184Y1535788D01*
X742350Y1535371D01*
X741975Y1535080D01*
X741725Y1534663D01*
X741642Y1534288D01*
X743392D01*
G01X745617D02*
X745909Y1534330D01*
X746242Y1534455D01*
X746450Y1534663D01*
X746534Y1534955D01*
X746450Y1535246D01*
X746200Y1535496D01*
X745825Y1535621D01*
X745409D01*
X745159Y1535705D01*
X744950Y1535913D01*
X744867Y1536205D01*
X744992Y1536496D01*
X745284Y1536705D01*
X745617Y1536788D01*
X745950Y1536705D01*
X746242Y1536496D01*
X746367Y1536205D01*
X746284Y1535913D01*
X746075Y1535705D01*
X745825Y1535621D01*
X745409D01*
X745034Y1535496D01*
X744784Y1535246D01*
X744700Y1534955D01*
X744784Y1534663D01*
X744992Y1534455D01*
X745325Y1534330D01*
X745617Y1534288D01*
G01X735484Y1538288D02*
Y1540788D01*
X736525D01*
X736859Y1540663D01*
X737067Y1540496D01*
X737150Y1540163D01*
X737067Y1539830D01*
X736817Y1539621D01*
X736525Y1539496D01*
X735484D01*
G01X736525D02*
X737150Y1538288D01*
G01X739917D02*
Y1540788D01*
X738375Y1538996D01*
X740459D01*
G01X741725Y1540371D02*
X741975Y1540621D01*
X742267Y1540746D01*
X742600Y1540788D01*
X743017Y1540705D01*
X743309Y1540496D01*
X743392Y1540246D01*
X743350Y1539996D01*
X743184Y1539788D01*
X742350Y1539371D01*
X741975Y1539080D01*
X741725Y1538663D01*
X741642Y1538288D01*
X743392D01*
G01X744909Y1538580D02*
X745200Y1538371D01*
X745534Y1538288D01*
X745867Y1538371D01*
X746159Y1538621D01*
X746367Y1538996D01*
X746450Y1539371D01*
Y1539830D01*
X746367Y1540205D01*
X746159Y1540538D01*
X745909Y1540705D01*
X745617Y1540788D01*
X745284Y1540705D01*
X745034Y1540538D01*
X744867Y1540288D01*
X744784Y1539955D01*
X744867Y1539663D01*
X745075Y1539371D01*
X745325Y1539205D01*
X745617Y1539163D01*
X745950Y1539246D01*
X746200Y1539455D01*
X746450Y1539830D01*
G01X731285Y1534478D02*
X733077D01*
X733452Y1534645D01*
X733702Y1534978D01*
X733785Y1535395D01*
X733702Y1535812D01*
X733452Y1536145D01*
X733077Y1536312D01*
X731285D01*
G01X732743Y1537703D02*
X732452Y1537995D01*
X732285Y1538245D01*
X732202Y1538578D01*
X732285Y1538870D01*
X732452Y1539078D01*
X732702Y1539245D01*
X732993Y1539287D01*
X733243Y1539245D01*
X733493Y1539078D01*
X733702Y1538828D01*
X733785Y1538537D01*
X733702Y1538203D01*
X733452Y1537912D01*
X733077Y1537745D01*
X732660Y1537703D01*
X732118Y1537787D01*
X731827Y1537912D01*
X731535Y1538120D01*
X731327Y1538412D01*
X731285Y1538703D01*
X731368Y1538995D01*
X731577Y1539203D01*
G01X727566Y1783634D02*
Y1786134D01*
X728607D01*
X728941Y1786009D01*
X729149Y1785842D01*
X729232Y1785509D01*
X729149Y1785176D01*
X728899Y1784967D01*
X728607Y1784842D01*
X727566D01*
G01X728607D02*
X729232Y1783634D01*
G01X730582Y1784134D02*
X730832Y1783842D01*
X731166Y1783676D01*
X731541Y1783634D01*
X731874Y1783676D01*
X732207Y1783884D01*
X732416Y1784134D01*
X732457Y1784384D01*
X732374Y1784676D01*
X732082Y1784884D01*
X731791Y1784967D01*
X731416D01*
G01X731791D02*
X732041Y1785092D01*
X732249Y1785301D01*
X732332Y1785551D01*
X732249Y1785801D01*
X732041Y1786009D01*
X731666Y1786134D01*
X731291Y1786092D01*
X730916Y1785926D01*
G01X735099Y1783634D02*
Y1786134D01*
X733557Y1784342D01*
X735641D01*
G01X736907Y1784676D02*
X737199Y1784967D01*
X737449Y1785134D01*
X737782Y1785217D01*
X738074Y1785134D01*
X738282Y1784967D01*
X738449Y1784717D01*
X738491Y1784426D01*
X738449Y1784176D01*
X738282Y1783926D01*
X738032Y1783717D01*
X737741Y1783634D01*
X737407Y1783717D01*
X737116Y1783967D01*
X736949Y1784342D01*
X736907Y1784759D01*
X736991Y1785301D01*
X737116Y1785592D01*
X737324Y1785884D01*
X737616Y1786092D01*
X737907Y1786134D01*
X738199Y1786051D01*
X738407Y1785842D01*
G01X727566Y1779634D02*
Y1782134D01*
X728607D01*
X728941Y1782009D01*
X729149Y1781842D01*
X729232Y1781509D01*
X729149Y1781176D01*
X728899Y1780967D01*
X728607Y1780842D01*
X727566D01*
G01X728607D02*
X729232Y1779634D01*
G01X730582Y1780134D02*
X730832Y1779842D01*
X731166Y1779676D01*
X731541Y1779634D01*
X731874Y1779676D01*
X732207Y1779884D01*
X732416Y1780134D01*
X732457Y1780384D01*
X732374Y1780676D01*
X732082Y1780884D01*
X731791Y1780967D01*
X731416D01*
G01X731791D02*
X732041Y1781092D01*
X732249Y1781301D01*
X732332Y1781551D01*
X732249Y1781801D01*
X732041Y1782009D01*
X731666Y1782134D01*
X731291Y1782092D01*
X730916Y1781926D01*
G01X735099Y1779634D02*
Y1782134D01*
X733557Y1780342D01*
X735641D01*
G01X737616Y1779634D02*
X737699Y1780176D01*
X737824Y1780634D01*
X737991Y1781051D01*
X738199Y1781509D01*
X738532Y1782134D01*
X736866D01*
G01X727566Y1787634D02*
Y1790134D01*
X728607D01*
X728941Y1790009D01*
X729149Y1789842D01*
X729232Y1789509D01*
X729149Y1789176D01*
X728899Y1788967D01*
X728607Y1788842D01*
X727566D01*
G01X728607D02*
X729232Y1787634D01*
G01X730582Y1788134D02*
X730832Y1787842D01*
X731166Y1787676D01*
X731541Y1787634D01*
X731874Y1787676D01*
X732207Y1787884D01*
X732416Y1788134D01*
X732457Y1788384D01*
X732374Y1788676D01*
X732082Y1788884D01*
X731791Y1788967D01*
X731416D01*
G01X731791D02*
X732041Y1789092D01*
X732249Y1789301D01*
X732332Y1789551D01*
X732249Y1789801D01*
X732041Y1790009D01*
X731666Y1790134D01*
X731291Y1790092D01*
X730916Y1789926D01*
G01X735099Y1787634D02*
Y1790134D01*
X733557Y1788342D01*
X735641D01*
G01X736782Y1788009D02*
X737032Y1787801D01*
X737324Y1787676D01*
X737699Y1787634D01*
X738074Y1787717D01*
X738366Y1787884D01*
X738574Y1788176D01*
X738616Y1788509D01*
X738532Y1788842D01*
X738324Y1789051D01*
X738032Y1789217D01*
X737741Y1789259D01*
X737449Y1789217D01*
X737074Y1789051D01*
X737199Y1790134D01*
X738324D01*
G01X734349Y1808634D02*
Y1804634D01*
X741749D01*
G01X734349Y1800634D02*
Y1796634D01*
X741749D01*
G01X723433Y1793567D02*
X720933D01*
Y1794608D01*
X721058Y1794942D01*
X721225Y1795150D01*
X721558Y1795233D01*
X721891Y1795150D01*
X722100Y1794900D01*
X722225Y1794608D01*
Y1793567D01*
G01Y1794608D02*
X723433Y1795233D01*
G01Y1798000D02*
X720933D01*
X722725Y1796458D01*
Y1798542D01*
G01X723433Y1800600D02*
X723391Y1800892D01*
X723266Y1801225D01*
X723058Y1801433D01*
X722766Y1801517D01*
X722475Y1801433D01*
X722225Y1801183D01*
X722100Y1800808D01*
Y1800392D01*
X722016Y1800142D01*
X721808Y1799933D01*
X721516Y1799850D01*
X721225Y1799975D01*
X721016Y1800267D01*
X720933Y1800600D01*
X721016Y1800933D01*
X721225Y1801225D01*
X721516Y1801350D01*
X721808Y1801267D01*
X722016Y1801058D01*
X722100Y1800808D01*
Y1800392D01*
X722225Y1800017D01*
X722475Y1799767D01*
X722766Y1799683D01*
X723058Y1799767D01*
X723266Y1799975D01*
X723391Y1800308D01*
X723433Y1800600D01*
G01Y1804200D02*
X720933D01*
X722725Y1802658D01*
Y1804742D01*
G01X728249Y1793651D02*
X725749D01*
Y1794692D01*
X725874Y1795026D01*
X726041Y1795234D01*
X726374Y1795317D01*
X726707Y1795234D01*
X726916Y1794984D01*
X727041Y1794692D01*
Y1793651D01*
G01Y1794692D02*
X728249Y1795317D01*
G01Y1798084D02*
X725749D01*
X727541Y1796542D01*
Y1798626D01*
G01X728249Y1800684D02*
X728207Y1800976D01*
X728082Y1801309D01*
X727874Y1801517D01*
X727582Y1801601D01*
X727291Y1801517D01*
X727041Y1801267D01*
X726916Y1800892D01*
Y1800476D01*
X726832Y1800226D01*
X726624Y1800017D01*
X726332Y1799934D01*
X726041Y1800059D01*
X725832Y1800351D01*
X725749Y1800684D01*
X725832Y1801017D01*
X726041Y1801309D01*
X726332Y1801434D01*
X726624Y1801351D01*
X726832Y1801142D01*
X726916Y1800892D01*
Y1800476D01*
X727041Y1800101D01*
X727291Y1799851D01*
X727582Y1799767D01*
X727874Y1799851D01*
X728082Y1800059D01*
X728207Y1800392D01*
X728249Y1800684D01*
G01X727874Y1802867D02*
X728082Y1803117D01*
X728207Y1803409D01*
X728249Y1803784D01*
X728166Y1804159D01*
X727999Y1804451D01*
X727707Y1804659D01*
X727374Y1804701D01*
X727041Y1804617D01*
X726832Y1804409D01*
X726666Y1804117D01*
X726624Y1803826D01*
X726666Y1803534D01*
X726832Y1803159D01*
X725749Y1803284D01*
Y1804409D01*
G01X734349Y1816134D02*
Y1812134D01*
X741749D01*
G01X723049Y1812851D02*
X720549D01*
Y1813892D01*
X720674Y1814226D01*
X720841Y1814434D01*
X721174Y1814517D01*
X721507Y1814434D01*
X721716Y1814184D01*
X721841Y1813892D01*
Y1812851D01*
G01Y1813892D02*
X723049Y1814517D01*
G01X722549Y1815867D02*
X722841Y1816117D01*
X723007Y1816451D01*
X723049Y1816826D01*
X723007Y1817159D01*
X722799Y1817492D01*
X722549Y1817701D01*
X722299Y1817742D01*
X722007Y1817659D01*
X721799Y1817367D01*
X721716Y1817076D01*
Y1816701D01*
G01Y1817076D02*
X721591Y1817326D01*
X721382Y1817534D01*
X721132Y1817617D01*
X720882Y1817534D01*
X720674Y1817326D01*
X720549Y1816951D01*
X720591Y1816576D01*
X720757Y1816201D01*
G01X723049Y1819884D02*
X723007Y1820176D01*
X722882Y1820509D01*
X722674Y1820717D01*
X722382Y1820801D01*
X722091Y1820717D01*
X721841Y1820467D01*
X721716Y1820092D01*
Y1819676D01*
X721632Y1819426D01*
X721424Y1819217D01*
X721132Y1819134D01*
X720841Y1819259D01*
X720632Y1819551D01*
X720549Y1819884D01*
X720632Y1820217D01*
X720841Y1820509D01*
X721132Y1820634D01*
X721424Y1820551D01*
X721632Y1820342D01*
X721716Y1820092D01*
Y1819676D01*
X721841Y1819301D01*
X722091Y1819051D01*
X722382Y1818967D01*
X722674Y1819051D01*
X722882Y1819259D01*
X723007Y1819592D01*
X723049Y1819884D01*
G01Y1822901D02*
X722507Y1822984D01*
X722049Y1823109D01*
X721632Y1823276D01*
X721174Y1823484D01*
X720549Y1823817D01*
Y1822151D01*
G01X735831Y1936713D02*
Y1939213D01*
X736872D01*
X737206Y1939088D01*
X737414Y1938921D01*
X737497Y1938588D01*
X737414Y1938255D01*
X737164Y1938046D01*
X736872Y1937921D01*
X735831D01*
G01X736872D02*
X737497Y1936713D01*
G01X739764D02*
Y1939213D01*
X739264Y1938713D01*
G01Y1936713D02*
X740264D01*
G01X742864Y1939213D02*
X742531Y1939130D01*
X742281Y1938921D01*
X742114Y1938671D01*
X741989Y1938338D01*
X741947Y1937963D01*
X741989Y1937588D01*
X742114Y1937255D01*
X742281Y1937005D01*
X742531Y1936796D01*
X742864Y1936713D01*
X743197Y1936796D01*
X743447Y1937005D01*
X743614Y1937255D01*
X743739Y1937588D01*
X743781Y1937963D01*
X743739Y1938338D01*
X743614Y1938671D01*
X743447Y1938921D01*
X743197Y1939130D01*
X742864Y1939213D01*
G01X745881Y1936713D02*
X745964Y1937255D01*
X746089Y1937713D01*
X746256Y1938130D01*
X746464Y1938588D01*
X746797Y1939213D01*
X745131D01*
G01X735831Y1941213D02*
Y1943713D01*
X736872D01*
X737206Y1943588D01*
X737414Y1943421D01*
X737497Y1943088D01*
X737414Y1942755D01*
X737164Y1942546D01*
X736872Y1942421D01*
X735831D01*
G01X736872D02*
X737497Y1941213D01*
G01X739764D02*
Y1943713D01*
X739264Y1943213D01*
G01Y1941213D02*
X740264D01*
G01X742864D02*
Y1943713D01*
X742364Y1943213D01*
G01Y1941213D02*
X743364D01*
G01X745047Y1941713D02*
X745297Y1941421D01*
X745631Y1941255D01*
X746006Y1941213D01*
X746339Y1941255D01*
X746672Y1941463D01*
X746881Y1941713D01*
X746922Y1941963D01*
X746839Y1942255D01*
X746547Y1942463D01*
X746256Y1942546D01*
X745881D01*
G01X746256D02*
X746506Y1942671D01*
X746714Y1942880D01*
X746797Y1943130D01*
X746714Y1943380D01*
X746506Y1943588D01*
X746131Y1943713D01*
X745756Y1943671D01*
X745381Y1943505D01*
G01X727416Y1980550D02*
Y1985550D01*
X730582D01*
G01X729416Y1983133D02*
X727416D01*
G01X733016Y1984717D02*
X733516Y1985217D01*
X734099Y1985467D01*
X734766Y1985550D01*
X735599Y1985383D01*
X736182Y1984967D01*
X736349Y1984467D01*
X736266Y1983967D01*
X735932Y1983550D01*
X734266Y1982717D01*
X733516Y1982133D01*
X733016Y1981300D01*
X732849Y1980550D01*
X736349D01*
G01X740199Y1980383D02*
X740032Y1980467D01*
Y1980633D01*
X740199Y1980717D01*
X740366Y1980633D01*
Y1980467D01*
X740199Y1980383D01*
G01Y1982633D02*
X740032Y1982717D01*
Y1982883D01*
X740199Y1982967D01*
X740366Y1982883D01*
Y1982717D01*
X740199Y1982633D01*
G01X743966Y1981550D02*
X744466Y1980967D01*
X745132Y1980633D01*
X745882Y1980550D01*
X746549Y1980633D01*
X747216Y1981050D01*
X747632Y1981550D01*
X747716Y1982050D01*
X747549Y1982633D01*
X746966Y1983050D01*
X746382Y1983217D01*
X745632D01*
G01X746382D02*
X746882Y1983467D01*
X747299Y1983883D01*
X747466Y1984383D01*
X747299Y1984883D01*
X746882Y1985300D01*
X746132Y1985550D01*
X745382Y1985467D01*
X744632Y1985133D01*
G01X749316Y1980550D02*
X751399Y1985550D01*
X753482Y1980550D01*
G01X752732Y1982300D02*
X750066D01*
G01X755499Y1980383D02*
X758499Y1985550D01*
G01X762599Y1980550D02*
Y1985550D01*
X761599Y1984550D01*
G01Y1980550D02*
X763599D01*
G01X766366Y1981300D02*
X766866Y1980883D01*
X767449Y1980633D01*
X768199Y1980550D01*
X768949Y1980717D01*
X769532Y1981050D01*
X769949Y1981633D01*
X770032Y1982300D01*
X769866Y1982967D01*
X769449Y1983383D01*
X768866Y1983717D01*
X768282Y1983800D01*
X767699Y1983717D01*
X766949Y1983383D01*
X767199Y1985550D01*
X769449D01*
G01X771716D02*
X773799Y1980550D01*
X775882Y1985550D01*
G01X758208Y302767D02*
X758083Y302517D01*
X758000Y302225D01*
Y301892D01*
X758125Y301517D01*
X758333Y301225D01*
X758583Y301017D01*
X759000Y300850D01*
X759375Y300808D01*
X759750Y300892D01*
X760000Y301017D01*
X760250Y301267D01*
X760417Y301558D01*
X760500Y301850D01*
Y302142D01*
X760417Y302433D01*
X760292Y302683D01*
X760125Y302892D01*
G01X760500Y304950D02*
X758000D01*
X758500Y304450D01*
G01X760500D02*
Y305450D01*
G01Y307967D02*
X759958Y308050D01*
X759500Y308175D01*
X759083Y308342D01*
X758625Y308550D01*
X758000Y308883D01*
Y307217D01*
G01X760500Y311150D02*
X758000D01*
X758500Y310650D01*
G01X760500D02*
Y311650D01*
G01X756678Y321924D02*
Y325924D01*
X749278D01*
G01X756678Y326924D02*
Y330924D01*
X749278D01*
G01X757778Y321424D02*
Y331424D01*
G01X771178Y321424D02*
X757778D01*
G01X747996Y336057D02*
X747954Y335724D01*
X747788Y335432D01*
X747538Y335182D01*
X747246Y335015D01*
X746913Y334932D01*
X746579D01*
X746246Y335015D01*
X745954Y335182D01*
X745704Y335432D01*
X745538Y335724D01*
X745496Y336057D01*
X745538Y336390D01*
X745704Y336682D01*
X745954Y336932D01*
X746246Y337099D01*
X746579Y337182D01*
X746913D01*
X747246Y337099D01*
X747538Y336932D01*
X747788Y336682D01*
X747954Y336390D01*
X747996Y336057D01*
G01X747329Y336390D02*
X747996Y336890D01*
G01Y339157D02*
X745496D01*
X745996Y338657D01*
G01X747996D02*
Y339657D01*
G01X745496Y342257D02*
X745579Y341924D01*
X745788Y341674D01*
X746038Y341507D01*
X746371Y341382D01*
X746746Y341340D01*
X747121Y341382D01*
X747454Y341507D01*
X747704Y341674D01*
X747913Y341924D01*
X747996Y342257D01*
X747913Y342590D01*
X747704Y342840D01*
X747454Y343007D01*
X747121Y343132D01*
X746746Y343174D01*
X746371Y343132D01*
X746038Y343007D01*
X745788Y342840D01*
X745579Y342590D01*
X745496Y342257D01*
G01X757778Y345124D02*
Y333724D01*
G01X771178Y345124D02*
X757778D01*
G01Y333724D02*
X771178D01*
G01X748995Y347424D02*
Y349924D01*
X750036D01*
X750370Y349799D01*
X750578Y349632D01*
X750661Y349299D01*
X750578Y348966D01*
X750328Y348757D01*
X750036Y348632D01*
X748995D01*
G01X750036D02*
X750661Y347424D01*
G01X752928D02*
Y349924D01*
X752428Y349424D01*
G01Y347424D02*
X753428D01*
G01X755236Y348466D02*
X755528Y348757D01*
X755778Y348924D01*
X756111Y349007D01*
X756403Y348924D01*
X756611Y348757D01*
X756778Y348507D01*
X756820Y348216D01*
X756778Y347966D01*
X756611Y347716D01*
X756361Y347507D01*
X756070Y347424D01*
X755736Y347507D01*
X755445Y347757D01*
X755278Y348132D01*
X755236Y348549D01*
X755320Y349091D01*
X755445Y349382D01*
X755653Y349674D01*
X755945Y349882D01*
X756236Y349924D01*
X756528Y349841D01*
X756736Y349632D01*
G01X758211Y347799D02*
X758461Y347591D01*
X758753Y347466D01*
X759128Y347424D01*
X759503Y347507D01*
X759795Y347674D01*
X760003Y347966D01*
X760045Y348299D01*
X759961Y348632D01*
X759753Y348841D01*
X759461Y349007D01*
X759170Y349049D01*
X758878Y349007D01*
X758503Y348841D01*
X758628Y349924D01*
X759753D01*
G01X743996Y335174D02*
X741496D01*
Y336215D01*
X741621Y336549D01*
X741788Y336757D01*
X742121Y336840D01*
X742454Y336757D01*
X742663Y336507D01*
X742788Y336215D01*
Y335174D01*
G01Y336215D02*
X743996Y336840D01*
G01Y339107D02*
X741496D01*
X741996Y338607D01*
G01X743996D02*
Y339607D01*
G01X742954Y341415D02*
X742663Y341707D01*
X742496Y341957D01*
X742413Y342290D01*
X742496Y342582D01*
X742663Y342790D01*
X742913Y342957D01*
X743204Y342999D01*
X743454Y342957D01*
X743704Y342790D01*
X743913Y342540D01*
X743996Y342249D01*
X743913Y341915D01*
X743663Y341624D01*
X743288Y341457D01*
X742871Y341415D01*
X742329Y341499D01*
X742038Y341624D01*
X741746Y341832D01*
X741538Y342124D01*
X741496Y342415D01*
X741579Y342707D01*
X741788Y342915D01*
G01X743996Y345307D02*
X743954Y345599D01*
X743829Y345932D01*
X743621Y346140D01*
X743329Y346224D01*
X743038Y346140D01*
X742788Y345890D01*
X742663Y345515D01*
Y345099D01*
X742579Y344849D01*
X742371Y344640D01*
X742079Y344557D01*
X741788Y344682D01*
X741579Y344974D01*
X741496Y345307D01*
X741579Y345640D01*
X741788Y345932D01*
X742079Y346057D01*
X742371Y345974D01*
X742579Y345765D01*
X742663Y345515D01*
Y345099D01*
X742788Y344724D01*
X743038Y344474D01*
X743329Y344390D01*
X743621Y344474D01*
X743829Y344682D01*
X743954Y345015D01*
X743996Y345307D01*
G01X752978Y333724D02*
X756978D01*
Y341124D01*
G01X757778Y331424D02*
X771178D01*
G01X748995Y351924D02*
Y354424D01*
X750036D01*
X750370Y354299D01*
X750578Y354132D01*
X750661Y353799D01*
X750578Y353466D01*
X750328Y353257D01*
X750036Y353132D01*
X748995D01*
G01X750036D02*
X750661Y351924D01*
G01X752928D02*
Y354424D01*
X752428Y353924D01*
G01Y351924D02*
X753428D01*
G01X755236Y352966D02*
X755528Y353257D01*
X755778Y353424D01*
X756111Y353507D01*
X756403Y353424D01*
X756611Y353257D01*
X756778Y353007D01*
X756820Y352716D01*
X756778Y352466D01*
X756611Y352216D01*
X756361Y352007D01*
X756070Y351924D01*
X755736Y352007D01*
X755445Y352257D01*
X755278Y352632D01*
X755236Y353049D01*
X755320Y353591D01*
X755445Y353882D01*
X755653Y354174D01*
X755945Y354382D01*
X756236Y354424D01*
X756528Y354341D01*
X756736Y354132D01*
G01X758336Y352966D02*
X758628Y353257D01*
X758878Y353424D01*
X759211Y353507D01*
X759503Y353424D01*
X759711Y353257D01*
X759878Y353007D01*
X759920Y352716D01*
X759878Y352466D01*
X759711Y352216D01*
X759461Y352007D01*
X759170Y351924D01*
X758836Y352007D01*
X758545Y352257D01*
X758378Y352632D01*
X758336Y353049D01*
X758420Y353591D01*
X758545Y353882D01*
X758753Y354174D01*
X759045Y354382D01*
X759336Y354424D01*
X759628Y354341D01*
X759836Y354132D01*
G01X753417Y673000D02*
Y678000D01*
X756583D01*
G01X755417Y675583D02*
X753417D01*
G01X760433Y673000D02*
X760600Y674083D01*
X760850Y675000D01*
X761183Y675833D01*
X761600Y676750D01*
X762267Y678000D01*
X758933D01*
G01X766200Y672833D02*
X766033Y672917D01*
Y673083D01*
X766200Y673167D01*
X766367Y673083D01*
Y672917D01*
X766200Y672833D01*
G01Y675083D02*
X766033Y675167D01*
Y675333D01*
X766200Y675417D01*
X766367Y675333D01*
Y675167D01*
X766200Y675083D01*
G01X770217Y677167D02*
X770717Y677667D01*
X771300Y677917D01*
X771967Y678000D01*
X772800Y677833D01*
X773383Y677417D01*
X773550Y676917D01*
X773467Y676417D01*
X773133Y676000D01*
X771467Y675167D01*
X770717Y674583D01*
X770217Y673750D01*
X770050Y673000D01*
X773550D01*
G01X775317D02*
X777400Y678000D01*
X779483Y673000D01*
G01X778733Y674750D02*
X776067D01*
G01X781500Y672833D02*
X784500Y678000D01*
G01X787017Y675083D02*
X787600Y675667D01*
X788100Y676000D01*
X788767Y676167D01*
X789350Y676000D01*
X789767Y675667D01*
X790100Y675167D01*
X790183Y674583D01*
X790100Y674083D01*
X789767Y673583D01*
X789267Y673167D01*
X788683Y673000D01*
X788017Y673167D01*
X787433Y673667D01*
X787100Y674417D01*
X787017Y675250D01*
X787183Y676333D01*
X787433Y676917D01*
X787850Y677500D01*
X788433Y677917D01*
X789017Y678000D01*
X789600Y677833D01*
X790017Y677417D01*
G01X792117Y678000D02*
X794200Y673000D01*
X796283Y678000D01*
G01X749708Y703267D02*
X749583Y703017D01*
X749500Y702725D01*
Y702392D01*
X749625Y702017D01*
X749833Y701725D01*
X750083Y701517D01*
X750500Y701350D01*
X750875Y701308D01*
X751250Y701392D01*
X751500Y701517D01*
X751750Y701767D01*
X751917Y702058D01*
X752000Y702350D01*
Y702642D01*
X751917Y702933D01*
X751792Y703183D01*
X751625Y703392D01*
G01X752000Y705450D02*
X749500D01*
X750000Y704950D01*
G01X752000D02*
Y705950D01*
G01X751625Y707633D02*
X751833Y707883D01*
X751958Y708175D01*
X752000Y708550D01*
X751917Y708925D01*
X751750Y709217D01*
X751458Y709425D01*
X751125Y709467D01*
X750792Y709383D01*
X750583Y709175D01*
X750417Y708883D01*
X750375Y708592D01*
X750417Y708300D01*
X750583Y707925D01*
X749500Y708050D01*
Y709175D01*
G01X752000Y711650D02*
X751958Y711942D01*
X751833Y712275D01*
X751625Y712483D01*
X751333Y712567D01*
X751042Y712483D01*
X750792Y712233D01*
X750667Y711858D01*
Y711442D01*
X750583Y711192D01*
X750375Y710983D01*
X750083Y710900D01*
X749792Y711025D01*
X749583Y711317D01*
X749500Y711650D01*
X749583Y711983D01*
X749792Y712275D01*
X750083Y712400D01*
X750375Y712317D01*
X750583Y712108D01*
X750667Y711858D01*
Y711442D01*
X750792Y711067D01*
X751042Y710817D01*
X751333Y710733D01*
X751625Y710817D01*
X751833Y711025D01*
X751958Y711358D01*
X752000Y711650D01*
G01X755396Y722882D02*
Y726882D01*
X747996D01*
G01X755396Y727882D02*
Y731882D01*
X747996D01*
G01X753983Y720000D02*
Y718208D01*
X754150Y717833D01*
X754483Y717583D01*
X754900Y717500D01*
X755317Y717583D01*
X755650Y717833D01*
X755817Y718208D01*
Y720000D01*
G01X758000Y717500D02*
Y720000D01*
X757500Y719500D01*
G01Y717500D02*
X758500D01*
G01X760308Y719583D02*
X760558Y719833D01*
X760850Y719958D01*
X761183Y720000D01*
X761600Y719917D01*
X761892Y719708D01*
X761975Y719458D01*
X761933Y719208D01*
X761767Y719000D01*
X760933Y718583D01*
X760558Y718292D01*
X760308Y717875D01*
X760225Y717500D01*
X761975D01*
G01X756996Y722382D02*
Y732382D01*
G01X770396Y722382D02*
X756996D01*
G01X750337Y744224D02*
X750004Y744266D01*
X749712Y744432D01*
X749462Y744682D01*
X749295Y744974D01*
X749212Y745307D01*
Y745641D01*
X749295Y745974D01*
X749462Y746266D01*
X749712Y746516D01*
X750004Y746682D01*
X750337Y746724D01*
X750670Y746682D01*
X750962Y746516D01*
X751212Y746266D01*
X751379Y745974D01*
X751462Y745641D01*
Y745307D01*
X751379Y744974D01*
X751212Y744682D01*
X750962Y744432D01*
X750670Y744266D01*
X750337Y744224D01*
G01X750670Y744891D02*
X751170Y744224D01*
G01X753437D02*
X753729Y744266D01*
X754062Y744391D01*
X754270Y744599D01*
X754354Y744891D01*
X754270Y745182D01*
X754020Y745432D01*
X753645Y745557D01*
X753229D01*
X752979Y745641D01*
X752770Y745849D01*
X752687Y746141D01*
X752812Y746432D01*
X753104Y746641D01*
X753437Y746724D01*
X753770Y746641D01*
X754062Y746432D01*
X754187Y746141D01*
X754104Y745849D01*
X753895Y745641D01*
X753645Y745557D01*
X753229D01*
X752854Y745432D01*
X752604Y745182D01*
X752520Y744891D01*
X752604Y744599D01*
X752812Y744391D01*
X753145Y744266D01*
X753437Y744224D01*
G01X755996Y745582D02*
Y734182D01*
G01X769396Y745582D02*
X755996D01*
G01Y734182D02*
X769396D01*
G01X751213Y748382D02*
Y750882D01*
X752254D01*
X752588Y750757D01*
X752796Y750590D01*
X752879Y750257D01*
X752796Y749924D01*
X752546Y749715D01*
X752254Y749590D01*
X751213D01*
G01X752254D02*
X752879Y748382D01*
G01X755146D02*
Y750882D01*
X754646Y750382D01*
G01Y748382D02*
X755646D01*
G01X758746D02*
Y750882D01*
X757204Y749090D01*
X759288D01*
G01X761346Y748382D02*
X761638Y748424D01*
X761971Y748549D01*
X762179Y748757D01*
X762263Y749049D01*
X762179Y749340D01*
X761929Y749590D01*
X761554Y749715D01*
X761138D01*
X760888Y749799D01*
X760679Y750007D01*
X760596Y750299D01*
X760721Y750590D01*
X761013Y750799D01*
X761346Y750882D01*
X761679Y750799D01*
X761971Y750590D01*
X762096Y750299D01*
X762013Y750007D01*
X761804Y749799D01*
X761554Y749715D01*
X761138D01*
X760763Y749590D01*
X760513Y749340D01*
X760429Y749049D01*
X760513Y748757D01*
X760721Y748549D01*
X761054Y748424D01*
X761346Y748382D01*
G01X743043Y733848D02*
X740543D01*
Y734889D01*
X740668Y735223D01*
X740835Y735431D01*
X741168Y735514D01*
X741501Y735431D01*
X741710Y735181D01*
X741835Y734889D01*
Y733848D01*
G01Y734889D02*
X743043Y735514D01*
G01Y737781D02*
X740543D01*
X741043Y737281D01*
G01X743043D02*
Y738281D01*
G01X742668Y739964D02*
X742876Y740214D01*
X743001Y740506D01*
X743043Y740881D01*
X742960Y741256D01*
X742793Y741548D01*
X742501Y741756D01*
X742168Y741798D01*
X741835Y741714D01*
X741626Y741506D01*
X741460Y741214D01*
X741418Y740923D01*
X741460Y740631D01*
X741626Y740256D01*
X740543Y740381D01*
Y741506D01*
G01X742543Y743064D02*
X742835Y743314D01*
X743001Y743648D01*
X743043Y744023D01*
X743001Y744356D01*
X742793Y744689D01*
X742543Y744898D01*
X742293Y744939D01*
X742001Y744856D01*
X741793Y744564D01*
X741710Y744273D01*
Y743898D01*
G01Y744273D02*
X741585Y744523D01*
X741376Y744731D01*
X741126Y744814D01*
X740876Y744731D01*
X740668Y744523D01*
X740543Y744148D01*
X740585Y743773D01*
X740751Y743398D01*
G01X751196Y733182D02*
X755196D01*
Y740582D01*
G01X756996Y732382D02*
X770396D01*
G01X751213Y752882D02*
Y755382D01*
X752254D01*
X752588Y755257D01*
X752796Y755090D01*
X752879Y754757D01*
X752796Y754424D01*
X752546Y754215D01*
X752254Y754090D01*
X751213D01*
G01X752254D02*
X752879Y752882D01*
G01X755146D02*
Y755382D01*
X754646Y754882D01*
G01Y752882D02*
X755646D01*
G01X758746D02*
Y755382D01*
X757204Y753590D01*
X759288D01*
G01X760638Y753174D02*
X760929Y752965D01*
X761263Y752882D01*
X761596Y752965D01*
X761888Y753215D01*
X762096Y753590D01*
X762179Y753965D01*
Y754424D01*
X762096Y754799D01*
X761888Y755132D01*
X761638Y755299D01*
X761346Y755382D01*
X761013Y755299D01*
X760763Y755132D01*
X760596Y754882D01*
X760513Y754549D01*
X760596Y754257D01*
X760804Y753965D01*
X761054Y753799D01*
X761346Y753757D01*
X761679Y753840D01*
X761929Y754049D01*
X762179Y754424D01*
G01X754708Y1104767D02*
X754583Y1104517D01*
X754500Y1104225D01*
Y1103892D01*
X754625Y1103517D01*
X754833Y1103225D01*
X755083Y1103017D01*
X755500Y1102850D01*
X755875Y1102808D01*
X756250Y1102892D01*
X756500Y1103017D01*
X756750Y1103267D01*
X756917Y1103558D01*
X757000Y1103850D01*
Y1104142D01*
X756917Y1104433D01*
X756792Y1104683D01*
X756625Y1104892D01*
G01X757000Y1106950D02*
X754500D01*
X755000Y1106450D01*
G01X757000D02*
Y1107450D01*
G01Y1110550D02*
X754500D01*
X756292Y1109008D01*
Y1111092D01*
G01X757000Y1113150D02*
X754500D01*
X755000Y1112650D01*
G01X757000D02*
Y1113650D01*
G01X756033Y1124392D02*
Y1128392D01*
X748633D01*
G01X756033Y1129392D02*
Y1133392D01*
X748633D01*
G01X757133Y1123892D02*
Y1133892D01*
G01X770533Y1123892D02*
X757133D01*
G01X745255Y1140290D02*
X745213Y1139957D01*
X745047Y1139665D01*
X744797Y1139415D01*
X744505Y1139248D01*
X744172Y1139165D01*
X743838D01*
X743505Y1139248D01*
X743213Y1139415D01*
X742963Y1139665D01*
X742797Y1139957D01*
X742755Y1140290D01*
X742797Y1140623D01*
X742963Y1140915D01*
X743213Y1141165D01*
X743505Y1141332D01*
X743838Y1141415D01*
X744172D01*
X744505Y1141332D01*
X744797Y1141165D01*
X745047Y1140915D01*
X745213Y1140623D01*
X745255Y1140290D01*
G01X744588Y1140623D02*
X745255Y1141123D01*
G01X744213Y1142598D02*
X743922Y1142890D01*
X743755Y1143140D01*
X743672Y1143473D01*
X743755Y1143765D01*
X743922Y1143973D01*
X744172Y1144140D01*
X744463Y1144182D01*
X744713Y1144140D01*
X744963Y1143973D01*
X745172Y1143723D01*
X745255Y1143432D01*
X745172Y1143098D01*
X744922Y1142807D01*
X744547Y1142640D01*
X744130Y1142598D01*
X743588Y1142682D01*
X743297Y1142807D01*
X743005Y1143015D01*
X742797Y1143307D01*
X742755Y1143598D01*
X742838Y1143890D01*
X743047Y1144098D01*
G01X757799Y1149750D02*
Y1138350D01*
G01X771199Y1149750D02*
X757799D01*
G01Y1138350D02*
X771199D01*
G01X748350Y1151392D02*
Y1153892D01*
X749391D01*
X749725Y1153767D01*
X749933Y1153600D01*
X750016Y1153267D01*
X749933Y1152934D01*
X749683Y1152725D01*
X749391Y1152600D01*
X748350D01*
G01X749391D02*
X750016Y1151392D01*
G01X752283D02*
Y1153892D01*
X751783Y1153392D01*
G01Y1151392D02*
X752783D01*
G01X754466Y1151892D02*
X754716Y1151600D01*
X755050Y1151434D01*
X755425Y1151392D01*
X755758Y1151434D01*
X756091Y1151642D01*
X756300Y1151892D01*
X756341Y1152142D01*
X756258Y1152434D01*
X755966Y1152642D01*
X755675Y1152725D01*
X755300D01*
G01X755675D02*
X755925Y1152850D01*
X756133Y1153059D01*
X756216Y1153309D01*
X756133Y1153559D01*
X755925Y1153767D01*
X755550Y1153892D01*
X755175Y1153850D01*
X754800Y1153684D01*
G01X757691Y1152434D02*
X757983Y1152725D01*
X758233Y1152892D01*
X758566Y1152975D01*
X758858Y1152892D01*
X759066Y1152725D01*
X759233Y1152475D01*
X759275Y1152184D01*
X759233Y1151934D01*
X759066Y1151684D01*
X758816Y1151475D01*
X758525Y1151392D01*
X758191Y1151475D01*
X757900Y1151725D01*
X757733Y1152100D01*
X757691Y1152517D01*
X757775Y1153059D01*
X757900Y1153350D01*
X758108Y1153642D01*
X758400Y1153850D01*
X758691Y1153892D01*
X758983Y1153809D01*
X759191Y1153600D01*
G01X741255Y1139357D02*
X738755D01*
Y1140398D01*
X738880Y1140732D01*
X739047Y1140940D01*
X739380Y1141023D01*
X739713Y1140940D01*
X739922Y1140690D01*
X740047Y1140398D01*
Y1139357D01*
G01Y1140398D02*
X741255Y1141023D01*
G01Y1143290D02*
X738755D01*
X739255Y1142790D01*
G01X741255D02*
Y1143790D01*
G01Y1146890D02*
X738755D01*
X740547Y1145348D01*
Y1147432D01*
G01X738755Y1149490D02*
X738838Y1149157D01*
X739047Y1148907D01*
X739297Y1148740D01*
X739630Y1148615D01*
X740005Y1148573D01*
X740380Y1148615D01*
X740713Y1148740D01*
X740963Y1148907D01*
X741172Y1149157D01*
X741255Y1149490D01*
X741172Y1149823D01*
X740963Y1150073D01*
X740713Y1150240D01*
X740380Y1150365D01*
X740005Y1150407D01*
X739630Y1150365D01*
X739297Y1150240D01*
X739047Y1150073D01*
X738838Y1149823D01*
X738755Y1149490D01*
G01X753499Y1138350D02*
X757499D01*
Y1145750D01*
G01X757133Y1133892D02*
X770533D01*
G01X748350Y1155892D02*
Y1158392D01*
X749391D01*
X749725Y1158267D01*
X749933Y1158100D01*
X750016Y1157767D01*
X749933Y1157434D01*
X749683Y1157225D01*
X749391Y1157100D01*
X748350D01*
G01X749391D02*
X750016Y1155892D01*
G01X752283D02*
Y1158392D01*
X751783Y1157892D01*
G01Y1155892D02*
X752783D01*
G01X754466Y1156392D02*
X754716Y1156100D01*
X755050Y1155934D01*
X755425Y1155892D01*
X755758Y1155934D01*
X756091Y1156142D01*
X756300Y1156392D01*
X756341Y1156642D01*
X756258Y1156934D01*
X755966Y1157142D01*
X755675Y1157225D01*
X755300D01*
G01X755675D02*
X755925Y1157350D01*
X756133Y1157559D01*
X756216Y1157809D01*
X756133Y1158059D01*
X755925Y1158267D01*
X755550Y1158392D01*
X755175Y1158350D01*
X754800Y1158184D01*
G01X758400Y1155892D02*
X758483Y1156434D01*
X758608Y1156892D01*
X758775Y1157309D01*
X758983Y1157767D01*
X759316Y1158392D01*
X757650D01*
G01X756208Y1510767D02*
X756083Y1510517D01*
X756000Y1510225D01*
Y1509892D01*
X756125Y1509517D01*
X756333Y1509225D01*
X756583Y1509017D01*
X757000Y1508850D01*
X757375Y1508808D01*
X757750Y1508892D01*
X758000Y1509017D01*
X758250Y1509267D01*
X758417Y1509558D01*
X758500Y1509850D01*
Y1510142D01*
X758417Y1510433D01*
X758292Y1510683D01*
X758125Y1510892D01*
G01X758500Y1512950D02*
X756000D01*
X756500Y1512450D01*
G01X758500D02*
Y1513450D01*
G01Y1516050D02*
X756000D01*
X756500Y1515550D01*
G01X758500D02*
Y1516550D01*
G01Y1519067D02*
X757958Y1519150D01*
X757500Y1519275D01*
X757083Y1519442D01*
X756625Y1519650D01*
X756000Y1519983D01*
Y1518317D01*
G01X759027Y1529296D02*
Y1533296D01*
X751627D01*
G01X758449Y1553550D02*
X758116Y1553592D01*
X757824Y1553758D01*
X757574Y1554008D01*
X757407Y1554300D01*
X757324Y1554633D01*
Y1554967D01*
X757407Y1555300D01*
X757574Y1555592D01*
X757824Y1555842D01*
X758116Y1556008D01*
X758449Y1556050D01*
X758782Y1556008D01*
X759074Y1555842D01*
X759324Y1555592D01*
X759491Y1555300D01*
X759574Y1554967D01*
Y1554633D01*
X759491Y1554300D01*
X759324Y1554008D01*
X759074Y1553758D01*
X758782Y1553592D01*
X758449Y1553550D01*
G01X758782Y1554217D02*
X759282Y1553550D01*
G01X762049D02*
Y1556050D01*
X760507Y1554258D01*
X762591D01*
G01X758627Y1551996D02*
Y1540596D01*
G01X772027Y1551996D02*
X758627D01*
G01Y1540596D02*
X772027D01*
G01X749911Y1542782D02*
X747411D01*
Y1543823D01*
X747536Y1544157D01*
X747703Y1544365D01*
X748036Y1544448D01*
X748369Y1544365D01*
X748578Y1544115D01*
X748703Y1543823D01*
Y1542782D01*
G01Y1543823D02*
X749911Y1544448D01*
G01Y1546715D02*
X747411D01*
X747911Y1546215D01*
G01X749911D02*
Y1547215D01*
G01X747828Y1549023D02*
X747578Y1549273D01*
X747453Y1549565D01*
X747411Y1549898D01*
X747494Y1550315D01*
X747703Y1550607D01*
X747953Y1550690D01*
X748203Y1550648D01*
X748411Y1550482D01*
X748828Y1549648D01*
X749119Y1549273D01*
X749536Y1549023D01*
X749911Y1548940D01*
Y1550690D01*
G01X748869Y1552123D02*
X748578Y1552415D01*
X748411Y1552665D01*
X748328Y1552998D01*
X748411Y1553290D01*
X748578Y1553498D01*
X748828Y1553665D01*
X749119Y1553707D01*
X749369Y1553665D01*
X749619Y1553498D01*
X749828Y1553248D01*
X749911Y1552957D01*
X749828Y1552623D01*
X749578Y1552332D01*
X749203Y1552165D01*
X748786Y1552123D01*
X748244Y1552207D01*
X747953Y1552332D01*
X747661Y1552540D01*
X747453Y1552832D01*
X747411Y1553123D01*
X747494Y1553415D01*
X747703Y1553623D01*
G01X754327Y1541096D02*
X758327D01*
Y1548496D01*
G01X759027Y1534296D02*
Y1538296D01*
X751627D01*
G01X749549Y1783651D02*
X747049D01*
Y1784692D01*
X747174Y1785026D01*
X747341Y1785234D01*
X747674Y1785317D01*
X748007Y1785234D01*
X748216Y1784984D01*
X748341Y1784692D01*
Y1783651D01*
G01Y1784692D02*
X749549Y1785317D01*
G01X749049Y1786667D02*
X749341Y1786917D01*
X749507Y1787251D01*
X749549Y1787626D01*
X749507Y1787959D01*
X749299Y1788292D01*
X749049Y1788501D01*
X748799Y1788542D01*
X748507Y1788459D01*
X748299Y1788167D01*
X748216Y1787876D01*
Y1787501D01*
G01Y1787876D02*
X748091Y1788126D01*
X747882Y1788334D01*
X747632Y1788417D01*
X747382Y1788334D01*
X747174Y1788126D01*
X747049Y1787751D01*
X747091Y1787376D01*
X747257Y1787001D01*
G01X749174Y1789767D02*
X749382Y1790017D01*
X749507Y1790309D01*
X749549Y1790684D01*
X749466Y1791059D01*
X749299Y1791351D01*
X749007Y1791559D01*
X748674Y1791601D01*
X748341Y1791517D01*
X748132Y1791309D01*
X747966Y1791017D01*
X747924Y1790726D01*
X747966Y1790434D01*
X748132Y1790059D01*
X747049Y1790184D01*
Y1791309D01*
G01Y1793784D02*
X747132Y1793451D01*
X747341Y1793201D01*
X747591Y1793034D01*
X747924Y1792909D01*
X748299Y1792867D01*
X748674Y1792909D01*
X749007Y1793034D01*
X749257Y1793201D01*
X749466Y1793451D01*
X749549Y1793784D01*
X749466Y1794117D01*
X749257Y1794367D01*
X749007Y1794534D01*
X748674Y1794659D01*
X748299Y1794701D01*
X747924Y1794659D01*
X747591Y1794534D01*
X747341Y1794367D01*
X747132Y1794117D01*
X747049Y1793784D01*
G01X749549Y1797651D02*
X747049D01*
Y1798692D01*
X747174Y1799026D01*
X747341Y1799234D01*
X747674Y1799317D01*
X748007Y1799234D01*
X748216Y1798984D01*
X748341Y1798692D01*
Y1797651D01*
G01Y1798692D02*
X749549Y1799317D01*
G01X749049Y1800667D02*
X749341Y1800917D01*
X749507Y1801251D01*
X749549Y1801626D01*
X749507Y1801959D01*
X749299Y1802292D01*
X749049Y1802501D01*
X748799Y1802542D01*
X748507Y1802459D01*
X748299Y1802167D01*
X748216Y1801876D01*
Y1801501D01*
G01Y1801876D02*
X748091Y1802126D01*
X747882Y1802334D01*
X747632Y1802417D01*
X747382Y1802334D01*
X747174Y1802126D01*
X747049Y1801751D01*
X747091Y1801376D01*
X747257Y1801001D01*
G01X749549Y1805184D02*
X747049D01*
X748841Y1803642D01*
Y1805726D01*
G01X749257Y1807076D02*
X749466Y1807367D01*
X749549Y1807701D01*
X749466Y1808034D01*
X749216Y1808326D01*
X748841Y1808534D01*
X748466Y1808617D01*
X748007D01*
X747632Y1808534D01*
X747299Y1808326D01*
X747132Y1808076D01*
X747049Y1807784D01*
X747132Y1807451D01*
X747299Y1807201D01*
X747549Y1807034D01*
X747882Y1806951D01*
X748174Y1807034D01*
X748466Y1807242D01*
X748632Y1807492D01*
X748674Y1807784D01*
X748591Y1808117D01*
X748382Y1808367D01*
X748007Y1808617D01*
G01X746049Y1808334D02*
X742049D01*
Y1800934D01*
G01X746049Y1800834D02*
X742049D01*
Y1793434D01*
G01X747549Y1818151D02*
X745049D01*
Y1819192D01*
X745174Y1819526D01*
X745341Y1819734D01*
X745674Y1819817D01*
X746007Y1819734D01*
X746216Y1819484D01*
X746341Y1819192D01*
Y1818151D01*
G01Y1819192D02*
X747549Y1819817D01*
G01X747049Y1821167D02*
X747341Y1821417D01*
X747507Y1821751D01*
X747549Y1822126D01*
X747507Y1822459D01*
X747299Y1822792D01*
X747049Y1823001D01*
X746799Y1823042D01*
X746507Y1822959D01*
X746299Y1822667D01*
X746216Y1822376D01*
Y1822001D01*
G01Y1822376D02*
X746091Y1822626D01*
X745882Y1822834D01*
X745632Y1822917D01*
X745382Y1822834D01*
X745174Y1822626D01*
X745049Y1822251D01*
X745091Y1821876D01*
X745257Y1821501D01*
G01X747549Y1825684D02*
X745049D01*
X746841Y1824142D01*
Y1826226D01*
G01X747549Y1828284D02*
X747507Y1828576D01*
X747382Y1828909D01*
X747174Y1829117D01*
X746882Y1829201D01*
X746591Y1829117D01*
X746341Y1828867D01*
X746216Y1828492D01*
Y1828076D01*
X746132Y1827826D01*
X745924Y1827617D01*
X745632Y1827534D01*
X745341Y1827659D01*
X745132Y1827951D01*
X745049Y1828284D01*
X745132Y1828617D01*
X745341Y1828909D01*
X745632Y1829034D01*
X745924Y1828951D01*
X746132Y1828742D01*
X746216Y1828492D01*
Y1828076D01*
X746341Y1827701D01*
X746591Y1827451D01*
X746882Y1827367D01*
X747174Y1827451D01*
X747382Y1827659D01*
X747507Y1827992D01*
X747549Y1828284D01*
G01X746049Y1815834D02*
X742049D01*
Y1808434D01*
G01X752532Y1818134D02*
Y1816342D01*
X752699Y1815967D01*
X753032Y1815717D01*
X753449Y1815634D01*
X753866Y1815717D01*
X754199Y1815967D01*
X754366Y1816342D01*
Y1818134D01*
G01X755632Y1816009D02*
X755882Y1815801D01*
X756174Y1815676D01*
X756549Y1815634D01*
X756924Y1815717D01*
X757216Y1815884D01*
X757424Y1816176D01*
X757466Y1816509D01*
X757382Y1816842D01*
X757174Y1817051D01*
X756882Y1817217D01*
X756591Y1817259D01*
X756299Y1817217D01*
X755924Y1817051D01*
X756049Y1818134D01*
X757174D01*
G01X759649D02*
X759316Y1818051D01*
X759066Y1817842D01*
X758899Y1817592D01*
X758774Y1817259D01*
X758732Y1816884D01*
X758774Y1816509D01*
X758899Y1816176D01*
X759066Y1815926D01*
X759316Y1815717D01*
X759649Y1815634D01*
X759982Y1815717D01*
X760232Y1815926D01*
X760399Y1816176D01*
X760524Y1816509D01*
X760566Y1816884D01*
X760524Y1817259D01*
X760399Y1817592D01*
X760232Y1817842D01*
X759982Y1818051D01*
X759649Y1818134D01*
G01X756614Y1934713D02*
Y1944713D01*
G01X770014Y1934713D02*
X756614D01*
G01X748499Y1950000D02*
X748457Y1949667D01*
X748291Y1949375D01*
X748041Y1949125D01*
X747749Y1948958D01*
X747416Y1948875D01*
X747082D01*
X746749Y1948958D01*
X746457Y1949125D01*
X746207Y1949375D01*
X746041Y1949667D01*
X745999Y1950000D01*
X746041Y1950333D01*
X746207Y1950625D01*
X746457Y1950875D01*
X746749Y1951042D01*
X747082Y1951125D01*
X747416D01*
X747749Y1951042D01*
X748041Y1950875D01*
X748291Y1950625D01*
X748457Y1950333D01*
X748499Y1950000D01*
G01X747832Y1950333D02*
X748499Y1950833D01*
G01Y1953100D02*
X745999D01*
X746499Y1952600D01*
G01X748499D02*
Y1953600D01*
G01X756114Y1957913D02*
Y1946513D01*
G01D02*
X769514D01*
G01X755514Y1935713D02*
Y1939713D01*
X748114D01*
G01X744499Y1949067D02*
X741999D01*
Y1950108D01*
X742124Y1950442D01*
X742291Y1950650D01*
X742624Y1950733D01*
X742957Y1950650D01*
X743166Y1950400D01*
X743291Y1950108D01*
Y1949067D01*
G01Y1950108D02*
X744499Y1950733D01*
G01Y1953000D02*
X741999D01*
X742499Y1952500D01*
G01X744499D02*
Y1953500D01*
G01Y1956100D02*
X741999D01*
X742499Y1955600D01*
G01X744499D02*
Y1956600D01*
G01X742416Y1958408D02*
X742166Y1958658D01*
X742041Y1958950D01*
X741999Y1959283D01*
X742082Y1959700D01*
X742291Y1959992D01*
X742541Y1960075D01*
X742791Y1960033D01*
X742999Y1959867D01*
X743416Y1959033D01*
X743707Y1958658D01*
X744124Y1958408D01*
X744499Y1958325D01*
Y1960075D01*
G01X751314Y1946513D02*
X755314D01*
Y1953913D01*
G01X755514Y1940213D02*
Y1944213D01*
X748114D01*
G01X756614Y1944713D02*
X770014D01*
G01X769514Y1957913D02*
X756114D01*
G01X747331Y1962913D02*
Y1965413D01*
X748372D01*
X748706Y1965288D01*
X748914Y1965121D01*
X748997Y1964788D01*
X748914Y1964455D01*
X748664Y1964246D01*
X748372Y1964121D01*
X747331D01*
G01X748372D02*
X748997Y1962913D01*
G01X751264D02*
Y1965413D01*
X750764Y1964913D01*
G01Y1962913D02*
X751764D01*
G01X754364Y1965413D02*
X754031Y1965330D01*
X753781Y1965121D01*
X753614Y1964871D01*
X753489Y1964538D01*
X753447Y1964163D01*
X753489Y1963788D01*
X753614Y1963455D01*
X753781Y1963205D01*
X754031Y1962996D01*
X754364Y1962913D01*
X754697Y1962996D01*
X754947Y1963205D01*
X755114Y1963455D01*
X755239Y1963788D01*
X755281Y1964163D01*
X755239Y1964538D01*
X755114Y1964871D01*
X754947Y1965121D01*
X754697Y1965330D01*
X754364Y1965413D01*
G01X757464Y1962913D02*
X757756Y1962955D01*
X758089Y1963080D01*
X758297Y1963288D01*
X758381Y1963580D01*
X758297Y1963871D01*
X758047Y1964121D01*
X757672Y1964246D01*
X757256D01*
X757006Y1964330D01*
X756797Y1964538D01*
X756714Y1964830D01*
X756839Y1965121D01*
X757131Y1965330D01*
X757464Y1965413D01*
X757797Y1965330D01*
X758089Y1965121D01*
X758214Y1964830D01*
X758131Y1964538D01*
X757922Y1964330D01*
X757672Y1964246D01*
X757256D01*
X756881Y1964121D01*
X756631Y1963871D01*
X756547Y1963580D01*
X756631Y1963288D01*
X756839Y1963080D01*
X757172Y1962955D01*
X757464Y1962913D01*
G01X747331Y1967413D02*
Y1969913D01*
X748372D01*
X748706Y1969788D01*
X748914Y1969621D01*
X748997Y1969288D01*
X748914Y1968955D01*
X748664Y1968746D01*
X748372Y1968621D01*
X747331D01*
G01X748372D02*
X748997Y1967413D01*
G01X751264D02*
Y1969913D01*
X750764Y1969413D01*
G01Y1967413D02*
X751764D01*
G01X754364Y1969913D02*
X754031Y1969830D01*
X753781Y1969621D01*
X753614Y1969371D01*
X753489Y1969038D01*
X753447Y1968663D01*
X753489Y1968288D01*
X753614Y1967955D01*
X753781Y1967705D01*
X754031Y1967496D01*
X754364Y1967413D01*
X754697Y1967496D01*
X754947Y1967705D01*
X755114Y1967955D01*
X755239Y1968288D01*
X755281Y1968663D01*
X755239Y1969038D01*
X755114Y1969371D01*
X754947Y1969621D01*
X754697Y1969830D01*
X754364Y1969913D01*
G01X756756Y1967705D02*
X757047Y1967496D01*
X757381Y1967413D01*
X757714Y1967496D01*
X758006Y1967746D01*
X758214Y1968121D01*
X758297Y1968496D01*
Y1968955D01*
X758214Y1969330D01*
X758006Y1969663D01*
X757756Y1969830D01*
X757464Y1969913D01*
X757131Y1969830D01*
X756881Y1969663D01*
X756714Y1969413D01*
X756631Y1969080D01*
X756714Y1968788D01*
X756922Y1968496D01*
X757172Y1968330D01*
X757464Y1968288D01*
X757797Y1968371D01*
X758047Y1968580D01*
X758297Y1968955D01*
G01X767417Y250500D02*
Y255500D01*
X770583D01*
G01X769417Y253083D02*
X767417D01*
G01X773183Y251083D02*
X773767Y250667D01*
X774433Y250500D01*
X775100Y250667D01*
X775683Y251167D01*
X776100Y251917D01*
X776267Y252667D01*
Y253583D01*
X776100Y254333D01*
X775683Y255000D01*
X775183Y255333D01*
X774600Y255500D01*
X773933Y255333D01*
X773433Y255000D01*
X773100Y254500D01*
X772933Y253833D01*
X773100Y253250D01*
X773517Y252667D01*
X774017Y252333D01*
X774600Y252250D01*
X775267Y252417D01*
X775767Y252833D01*
X776267Y253583D01*
G01X780200Y250333D02*
X780033Y250417D01*
Y250583D01*
X780200Y250667D01*
X780367Y250583D01*
Y250417D01*
X780200Y250333D01*
G01Y252583D02*
X780033Y252667D01*
Y252833D01*
X780200Y252917D01*
X780367Y252833D01*
Y252667D01*
X780200Y252583D01*
G01X784217Y254667D02*
X784717Y255167D01*
X785300Y255417D01*
X785967Y255500D01*
X786800Y255333D01*
X787383Y254917D01*
X787550Y254417D01*
X787467Y253917D01*
X787133Y253500D01*
X785467Y252667D01*
X784717Y252083D01*
X784217Y251250D01*
X784050Y250500D01*
X787550D01*
G01X789317D02*
X791400Y255500D01*
X793483Y250500D01*
G01X792733Y252250D02*
X790067D01*
G01X795500Y250333D02*
X798500Y255500D01*
G01X801017Y252583D02*
X801600Y253167D01*
X802100Y253500D01*
X802767Y253667D01*
X803350Y253500D01*
X803767Y253167D01*
X804100Y252667D01*
X804183Y252083D01*
X804100Y251583D01*
X803767Y251083D01*
X803267Y250667D01*
X802683Y250500D01*
X802017Y250667D01*
X801433Y251167D01*
X801100Y251917D01*
X801017Y252750D01*
X801183Y253833D01*
X801433Y254417D01*
X801850Y255000D01*
X802433Y255417D01*
X803017Y255500D01*
X803600Y255333D01*
X804017Y254917D01*
G01X806117Y255500D02*
X808200Y250500D01*
X810283Y255500D01*
G01X774708Y302267D02*
X774583Y302017D01*
X774500Y301725D01*
Y301392D01*
X774625Y301017D01*
X774833Y300725D01*
X775083Y300517D01*
X775500Y300350D01*
X775875Y300308D01*
X776250Y300392D01*
X776500Y300517D01*
X776750Y300767D01*
X776917Y301058D01*
X777000Y301350D01*
Y301642D01*
X776917Y301933D01*
X776792Y302183D01*
X776625Y302392D01*
G01X777000Y304450D02*
X774500D01*
X775000Y303950D01*
G01X777000D02*
Y304950D01*
G01X775958Y306758D02*
X775667Y307050D01*
X775500Y307300D01*
X775417Y307633D01*
X775500Y307925D01*
X775667Y308133D01*
X775917Y308300D01*
X776208Y308342D01*
X776458Y308300D01*
X776708Y308133D01*
X776917Y307883D01*
X777000Y307592D01*
X776917Y307258D01*
X776667Y306967D01*
X776292Y306800D01*
X775875Y306758D01*
X775333Y306842D01*
X775042Y306967D01*
X774750Y307175D01*
X774542Y307467D01*
X774500Y307758D01*
X774583Y308050D01*
X774792Y308258D01*
G01X776625Y309733D02*
X776833Y309983D01*
X776958Y310275D01*
X777000Y310650D01*
X776917Y311025D01*
X776750Y311317D01*
X776458Y311525D01*
X776125Y311567D01*
X775792Y311483D01*
X775583Y311275D01*
X775417Y310983D01*
X775375Y310692D01*
X775417Y310400D01*
X775583Y310025D01*
X774500Y310150D01*
Y311275D01*
G01X781699Y320550D02*
Y324550D01*
X774299D01*
G01X771178Y331424D02*
Y321424D01*
G01Y333724D02*
Y345124D01*
G01X773678Y345924D02*
Y349924D01*
X766278D01*
G01X781699Y324550D02*
Y328550D01*
X774299D01*
G01X773700Y338200D02*
Y334200D01*
X781100D01*
G01X773678Y350424D02*
Y354424D01*
X766278D01*
G01X771208Y701267D02*
X771083Y701017D01*
X771000Y700725D01*
Y700392D01*
X771125Y700017D01*
X771333Y699725D01*
X771583Y699517D01*
X772000Y699350D01*
X772375Y699308D01*
X772750Y699392D01*
X773000Y699517D01*
X773250Y699767D01*
X773417Y700058D01*
X773500Y700350D01*
Y700642D01*
X773417Y700933D01*
X773292Y701183D01*
X773125Y701392D01*
G01X773500Y703450D02*
X771000D01*
X771500Y702950D01*
G01X773500D02*
Y703950D01*
G01Y707050D02*
X771000D01*
X772792Y705508D01*
Y707592D01*
G01X773208Y708942D02*
X773417Y709233D01*
X773500Y709567D01*
X773417Y709900D01*
X773167Y710192D01*
X772792Y710400D01*
X772417Y710483D01*
X771958D01*
X771583Y710400D01*
X771250Y710192D01*
X771083Y709942D01*
X771000Y709650D01*
X771083Y709317D01*
X771250Y709067D01*
X771500Y708900D01*
X771833Y708817D01*
X772125Y708900D01*
X772417Y709108D01*
X772583Y709358D01*
X772625Y709650D01*
X772542Y709983D01*
X772333Y710233D01*
X771958Y710483D01*
G01X768017Y713000D02*
Y715500D01*
X769058D01*
X769392Y715375D01*
X769600Y715208D01*
X769683Y714875D01*
X769600Y714542D01*
X769350Y714333D01*
X769058Y714208D01*
X768017D01*
G01X769058D02*
X769683Y713000D01*
G01X772450D02*
Y715500D01*
X770908Y713708D01*
X772992D01*
G01X774133Y713500D02*
X774383Y713208D01*
X774717Y713042D01*
X775092Y713000D01*
X775425Y713042D01*
X775758Y713250D01*
X775967Y713500D01*
X776008Y713750D01*
X775925Y714042D01*
X775633Y714250D01*
X775342Y714333D01*
X774967D01*
G01X775342D02*
X775592Y714458D01*
X775800Y714667D01*
X775883Y714917D01*
X775800Y715167D01*
X775592Y715375D01*
X775217Y715500D01*
X774842Y715458D01*
X774467Y715292D01*
G01X778067Y713000D02*
X778150Y713542D01*
X778275Y714000D01*
X778442Y714417D01*
X778650Y714875D01*
X778983Y715500D01*
X777317D01*
G01X779699Y722050D02*
Y726050D01*
X772299D01*
G01X768017Y717000D02*
Y719500D01*
X769058D01*
X769392Y719375D01*
X769600Y719208D01*
X769683Y718875D01*
X769600Y718542D01*
X769350Y718333D01*
X769058Y718208D01*
X768017D01*
G01X769058D02*
X769683Y717000D01*
G01X772450D02*
Y719500D01*
X770908Y717708D01*
X772992D01*
G01X774133Y717500D02*
X774383Y717208D01*
X774717Y717042D01*
X775092Y717000D01*
X775425Y717042D01*
X775758Y717250D01*
X775967Y717500D01*
X776008Y717750D01*
X775925Y718042D01*
X775633Y718250D01*
X775342Y718333D01*
X774967D01*
G01X775342D02*
X775592Y718458D01*
X775800Y718667D01*
X775883Y718917D01*
X775800Y719167D01*
X775592Y719375D01*
X775217Y719500D01*
X774842Y719458D01*
X774467Y719292D01*
G01X777358Y718042D02*
X777650Y718333D01*
X777900Y718500D01*
X778233Y718583D01*
X778525Y718500D01*
X778733Y718333D01*
X778900Y718083D01*
X778942Y717792D01*
X778900Y717542D01*
X778733Y717292D01*
X778483Y717083D01*
X778192Y717000D01*
X777858Y717083D01*
X777567Y717333D01*
X777400Y717708D01*
X777358Y718125D01*
X777442Y718667D01*
X777567Y718958D01*
X777775Y719250D01*
X778067Y719458D01*
X778358Y719500D01*
X778650Y719417D01*
X778858Y719208D01*
G01X779699Y726550D02*
Y730550D01*
X772299D01*
G01X770396Y732382D02*
Y722382D01*
G01X769396Y734182D02*
Y745582D01*
G01X771896Y746382D02*
Y750382D01*
X764496D01*
G01X772400Y738700D02*
Y734700D01*
X779800D01*
G01X771896Y750882D02*
Y754882D01*
X764496D01*
G01X769417Y1045500D02*
Y1050500D01*
X772583D01*
G01X771417Y1048083D02*
X769417D01*
G01X774767Y1046250D02*
X775267Y1045833D01*
X775850Y1045583D01*
X776600Y1045500D01*
X777350Y1045667D01*
X777933Y1046000D01*
X778350Y1046583D01*
X778433Y1047250D01*
X778267Y1047917D01*
X777850Y1048333D01*
X777267Y1048667D01*
X776683Y1048750D01*
X776100Y1048667D01*
X775350Y1048333D01*
X775600Y1050500D01*
X777850D01*
G01X782200Y1045333D02*
X782033Y1045417D01*
Y1045583D01*
X782200Y1045667D01*
X782367Y1045583D01*
Y1045417D01*
X782200Y1045333D01*
G01Y1047583D02*
X782033Y1047667D01*
Y1047833D01*
X782200Y1047917D01*
X782367Y1047833D01*
Y1047667D01*
X782200Y1047583D01*
G01X786217Y1049667D02*
X786717Y1050167D01*
X787300Y1050417D01*
X787967Y1050500D01*
X788800Y1050333D01*
X789383Y1049917D01*
X789550Y1049417D01*
X789467Y1048917D01*
X789133Y1048500D01*
X787467Y1047667D01*
X786717Y1047083D01*
X786217Y1046250D01*
X786050Y1045500D01*
X789550D01*
G01X791317D02*
X793400Y1050500D01*
X795483Y1045500D01*
G01X794733Y1047250D02*
X792067D01*
G01X797500Y1045333D02*
X800500Y1050500D01*
G01X803017Y1047583D02*
X803600Y1048167D01*
X804100Y1048500D01*
X804767Y1048667D01*
X805350Y1048500D01*
X805767Y1048167D01*
X806100Y1047667D01*
X806183Y1047083D01*
X806100Y1046583D01*
X805767Y1046083D01*
X805267Y1045667D01*
X804683Y1045500D01*
X804017Y1045667D01*
X803433Y1046167D01*
X803100Y1046917D01*
X803017Y1047750D01*
X803183Y1048833D01*
X803433Y1049417D01*
X803850Y1050000D01*
X804433Y1050417D01*
X805017Y1050500D01*
X805600Y1050333D01*
X806017Y1049917D01*
G01X808117Y1050500D02*
X810200Y1045500D01*
X812283Y1050500D01*
G01X773208Y1104767D02*
X773083Y1104517D01*
X773000Y1104225D01*
Y1103892D01*
X773125Y1103517D01*
X773333Y1103225D01*
X773583Y1103017D01*
X774000Y1102850D01*
X774375Y1102808D01*
X774750Y1102892D01*
X775000Y1103017D01*
X775250Y1103267D01*
X775417Y1103558D01*
X775500Y1103850D01*
Y1104142D01*
X775417Y1104433D01*
X775292Y1104683D01*
X775125Y1104892D01*
G01X775500Y1106950D02*
X773000D01*
X773500Y1106450D01*
G01X775500D02*
Y1107450D01*
G01X775000Y1109133D02*
X775292Y1109383D01*
X775458Y1109717D01*
X775500Y1110092D01*
X775458Y1110425D01*
X775250Y1110758D01*
X775000Y1110967D01*
X774750Y1111008D01*
X774458Y1110925D01*
X774250Y1110633D01*
X774167Y1110342D01*
Y1109967D01*
G01Y1110342D02*
X774042Y1110592D01*
X773833Y1110800D01*
X773583Y1110883D01*
X773333Y1110800D01*
X773125Y1110592D01*
X773000Y1110217D01*
X773042Y1109842D01*
X773208Y1109467D01*
G01X775000Y1112233D02*
X775292Y1112483D01*
X775458Y1112817D01*
X775500Y1113192D01*
X775458Y1113525D01*
X775250Y1113858D01*
X775000Y1114067D01*
X774750Y1114108D01*
X774458Y1114025D01*
X774250Y1113733D01*
X774167Y1113442D01*
Y1113067D01*
G01Y1113442D02*
X774042Y1113692D01*
X773833Y1113900D01*
X773583Y1113983D01*
X773333Y1113900D01*
X773125Y1113692D01*
X773000Y1113317D01*
X773042Y1112942D01*
X773208Y1112567D01*
G01X780699Y1125550D02*
Y1129550D01*
X773299D01*
G01X780699Y1121550D02*
Y1125550D01*
X773299D01*
G01X770533Y1133892D02*
Y1123892D01*
G01X771199Y1138350D02*
Y1149750D01*
G01X772033Y1150392D02*
Y1154392D01*
X764633D01*
G01X772500Y1140200D02*
Y1136200D01*
X779900D01*
G01X772033Y1154892D02*
Y1158892D01*
X764633D01*
G01X762917Y1457500D02*
Y1462500D01*
X766083D01*
G01X764917Y1460083D02*
X762917D01*
G01X768267Y1458500D02*
X768767Y1457917D01*
X769433Y1457583D01*
X770183Y1457500D01*
X770850Y1457583D01*
X771517Y1458000D01*
X771933Y1458500D01*
X772017Y1459000D01*
X771850Y1459583D01*
X771267Y1460000D01*
X770683Y1460167D01*
X769933D01*
G01X770683D02*
X771183Y1460417D01*
X771600Y1460833D01*
X771767Y1461333D01*
X771600Y1461833D01*
X771183Y1462250D01*
X770433Y1462500D01*
X769683Y1462417D01*
X768933Y1462083D01*
G01X775700Y1457333D02*
X775533Y1457417D01*
Y1457583D01*
X775700Y1457667D01*
X775867Y1457583D01*
Y1457417D01*
X775700Y1457333D01*
G01Y1459583D02*
X775533Y1459667D01*
Y1459833D01*
X775700Y1459917D01*
X775867Y1459833D01*
Y1459667D01*
X775700Y1459583D01*
G01X779717Y1461667D02*
X780217Y1462167D01*
X780800Y1462417D01*
X781467Y1462500D01*
X782300Y1462333D01*
X782883Y1461917D01*
X783050Y1461417D01*
X782967Y1460917D01*
X782633Y1460500D01*
X780967Y1459667D01*
X780217Y1459083D01*
X779717Y1458250D01*
X779550Y1457500D01*
X783050D01*
G01X784817D02*
X786900Y1462500D01*
X788983Y1457500D01*
G01X788233Y1459250D02*
X785567D01*
G01X791000Y1457333D02*
X794000Y1462500D01*
G01X796517Y1459583D02*
X797100Y1460167D01*
X797600Y1460500D01*
X798267Y1460667D01*
X798850Y1460500D01*
X799267Y1460167D01*
X799600Y1459667D01*
X799683Y1459083D01*
X799600Y1458583D01*
X799267Y1458083D01*
X798767Y1457667D01*
X798183Y1457500D01*
X797517Y1457667D01*
X796933Y1458167D01*
X796600Y1458917D01*
X796517Y1459750D01*
X796683Y1460833D01*
X796933Y1461417D01*
X797350Y1462000D01*
X797933Y1462417D01*
X798517Y1462500D01*
X799100Y1462333D01*
X799517Y1461917D01*
G01X801617Y1462500D02*
X803700Y1457500D01*
X805783Y1462500D01*
G01X777708Y1510767D02*
X777583Y1510517D01*
X777500Y1510225D01*
Y1509892D01*
X777625Y1509517D01*
X777833Y1509225D01*
X778083Y1509017D01*
X778500Y1508850D01*
X778875Y1508808D01*
X779250Y1508892D01*
X779500Y1509017D01*
X779750Y1509267D01*
X779917Y1509558D01*
X780000Y1509850D01*
Y1510142D01*
X779917Y1510433D01*
X779792Y1510683D01*
X779625Y1510892D01*
G01X780000Y1512950D02*
X777500D01*
X778000Y1512450D01*
G01X780000D02*
Y1513450D01*
G01X777917Y1515258D02*
X777667Y1515508D01*
X777542Y1515800D01*
X777500Y1516133D01*
X777583Y1516550D01*
X777792Y1516842D01*
X778042Y1516925D01*
X778292Y1516883D01*
X778500Y1516717D01*
X778917Y1515883D01*
X779208Y1515508D01*
X779625Y1515258D01*
X780000Y1515175D01*
Y1516925D01*
G01X779625Y1518233D02*
X779833Y1518483D01*
X779958Y1518775D01*
X780000Y1519150D01*
X779917Y1519525D01*
X779750Y1519817D01*
X779458Y1520025D01*
X779125Y1520067D01*
X778792Y1519983D01*
X778583Y1519775D01*
X778417Y1519483D01*
X778375Y1519192D01*
X778417Y1518900D01*
X778583Y1518525D01*
X777500Y1518650D01*
Y1519775D01*
G01X782881Y1525893D02*
Y1529893D01*
X775481D01*
G01X760127Y1528796D02*
Y1538796D01*
G01X773527Y1528796D02*
X760127D01*
G01X773527Y1538796D02*
Y1528796D01*
G01X772027Y1540596D02*
Y1551996D01*
G01X774527Y1552796D02*
Y1556796D01*
X767127D01*
G01X782881Y1529893D02*
Y1533893D01*
X775481D01*
G01X775100Y1545100D02*
Y1541100D01*
X782500D01*
G01X760127Y1538796D02*
X773527D01*
G01X760844Y1562296D02*
Y1564796D01*
X761885D01*
X762219Y1564671D01*
X762427Y1564504D01*
X762510Y1564171D01*
X762427Y1563838D01*
X762177Y1563629D01*
X761885Y1563504D01*
X760844D01*
G01X761885D02*
X762510Y1562296D01*
G01X764777D02*
Y1564796D01*
X764277Y1564296D01*
G01Y1562296D02*
X765277D01*
G01X767085Y1564379D02*
X767335Y1564629D01*
X767627Y1564754D01*
X767960Y1564796D01*
X768377Y1564713D01*
X768669Y1564504D01*
X768752Y1564254D01*
X768710Y1564004D01*
X768544Y1563796D01*
X767710Y1563379D01*
X767335Y1563088D01*
X767085Y1562671D01*
X767002Y1562296D01*
X768752D01*
G01X770977Y1564796D02*
X770644Y1564713D01*
X770394Y1564504D01*
X770227Y1564254D01*
X770102Y1563921D01*
X770060Y1563546D01*
X770102Y1563171D01*
X770227Y1562838D01*
X770394Y1562588D01*
X770644Y1562379D01*
X770977Y1562296D01*
X771310Y1562379D01*
X771560Y1562588D01*
X771727Y1562838D01*
X771852Y1563171D01*
X771894Y1563546D01*
X771852Y1563921D01*
X771727Y1564254D01*
X771560Y1564504D01*
X771310Y1564713D01*
X770977Y1564796D01*
G01X760844Y1566796D02*
Y1569296D01*
X761885D01*
X762219Y1569171D01*
X762427Y1569004D01*
X762510Y1568671D01*
X762427Y1568338D01*
X762177Y1568129D01*
X761885Y1568004D01*
X760844D01*
G01X761885D02*
X762510Y1566796D01*
G01X764777D02*
Y1569296D01*
X764277Y1568796D01*
G01Y1566796D02*
X765277D01*
G01X767085Y1568879D02*
X767335Y1569129D01*
X767627Y1569254D01*
X767960Y1569296D01*
X768377Y1569213D01*
X768669Y1569004D01*
X768752Y1568754D01*
X768710Y1568504D01*
X768544Y1568296D01*
X767710Y1567879D01*
X767335Y1567588D01*
X767085Y1567171D01*
X767002Y1566796D01*
X768752D01*
G01X770185Y1568879D02*
X770435Y1569129D01*
X770727Y1569254D01*
X771060Y1569296D01*
X771477Y1569213D01*
X771769Y1569004D01*
X771852Y1568754D01*
X771810Y1568504D01*
X771644Y1568296D01*
X770810Y1567879D01*
X770435Y1567588D01*
X770185Y1567171D01*
X770102Y1566796D01*
X771852D01*
G01X774527Y1557296D02*
Y1561296D01*
X767127D01*
G01X776017Y1569000D02*
Y1571500D01*
X777058D01*
X777392Y1571375D01*
X777600Y1571208D01*
X777683Y1570875D01*
X777600Y1570542D01*
X777350Y1570333D01*
X777058Y1570208D01*
X776017D01*
G01X777058D02*
X777683Y1569000D01*
G01X780450D02*
Y1571500D01*
X778908Y1569708D01*
X780992D01*
G01X783050Y1571500D02*
X782717Y1571417D01*
X782467Y1571208D01*
X782300Y1570958D01*
X782175Y1570625D01*
X782133Y1570250D01*
X782175Y1569875D01*
X782300Y1569542D01*
X782467Y1569292D01*
X782717Y1569083D01*
X783050Y1569000D01*
X783383Y1569083D01*
X783633Y1569292D01*
X783800Y1569542D01*
X783925Y1569875D01*
X783967Y1570250D01*
X783925Y1570625D01*
X783800Y1570958D01*
X783633Y1571208D01*
X783383Y1571417D01*
X783050Y1571500D01*
G01X785442Y1569292D02*
X785733Y1569083D01*
X786067Y1569000D01*
X786400Y1569083D01*
X786692Y1569333D01*
X786900Y1569708D01*
X786983Y1570083D01*
Y1570542D01*
X786900Y1570917D01*
X786692Y1571250D01*
X786442Y1571417D01*
X786150Y1571500D01*
X785817Y1571417D01*
X785567Y1571250D01*
X785400Y1571000D01*
X785317Y1570667D01*
X785400Y1570375D01*
X785608Y1570083D01*
X785858Y1569917D01*
X786150Y1569875D01*
X786483Y1569958D01*
X786733Y1570167D01*
X786983Y1570542D01*
G01X768066Y1822634D02*
Y1825134D01*
X769107D01*
X769441Y1825009D01*
X769649Y1824842D01*
X769732Y1824509D01*
X769649Y1824176D01*
X769399Y1823967D01*
X769107Y1823842D01*
X768066D01*
G01X769107D02*
X769732Y1822634D01*
G01X771082Y1823134D02*
X771332Y1822842D01*
X771666Y1822676D01*
X772041Y1822634D01*
X772374Y1822676D01*
X772707Y1822884D01*
X772916Y1823134D01*
X772957Y1823384D01*
X772874Y1823676D01*
X772582Y1823884D01*
X772291Y1823967D01*
X771916D01*
G01X772291D02*
X772541Y1824092D01*
X772749Y1824301D01*
X772832Y1824551D01*
X772749Y1824801D01*
X772541Y1825009D01*
X772166Y1825134D01*
X771791Y1825092D01*
X771416Y1824926D01*
G01X774182Y1823009D02*
X774432Y1822801D01*
X774724Y1822676D01*
X775099Y1822634D01*
X775474Y1822717D01*
X775766Y1822884D01*
X775974Y1823176D01*
X776016Y1823509D01*
X775932Y1823842D01*
X775724Y1824051D01*
X775432Y1824217D01*
X775141Y1824259D01*
X774849Y1824217D01*
X774474Y1824051D01*
X774599Y1825134D01*
X775724D01*
G01X778199Y1822634D02*
Y1825134D01*
X777699Y1824634D01*
G01Y1822634D02*
X778699D01*
G01X772349Y1819634D02*
Y1815634D01*
X779749D01*
G01X775917Y1868500D02*
Y1873500D01*
X779083D01*
G01X777917Y1871083D02*
X775917D01*
G01X783100Y1868500D02*
Y1873500D01*
X782100Y1872500D01*
G01Y1868500D02*
X784100D01*
G01X788700Y1868333D02*
X788533Y1868417D01*
Y1868583D01*
X788700Y1868667D01*
X788867Y1868583D01*
Y1868417D01*
X788700Y1868333D01*
G01Y1870583D02*
X788533Y1870667D01*
Y1870833D01*
X788700Y1870917D01*
X788867Y1870833D01*
Y1870667D01*
X788700Y1870583D01*
G01X792717Y1872667D02*
X793217Y1873167D01*
X793800Y1873417D01*
X794467Y1873500D01*
X795300Y1873333D01*
X795883Y1872917D01*
X796050Y1872417D01*
X795967Y1871917D01*
X795633Y1871500D01*
X793967Y1870667D01*
X793217Y1870083D01*
X792717Y1869250D01*
X792550Y1868500D01*
X796050D01*
G01X797817D02*
X799900Y1873500D01*
X801983Y1868500D01*
G01X801233Y1870250D02*
X798567D01*
G01X804000Y1868333D02*
X807000Y1873500D01*
G01X809517Y1870583D02*
X810100Y1871167D01*
X810600Y1871500D01*
X811267Y1871667D01*
X811850Y1871500D01*
X812267Y1871167D01*
X812600Y1870667D01*
X812683Y1870083D01*
X812600Y1869583D01*
X812267Y1869083D01*
X811767Y1868667D01*
X811183Y1868500D01*
X810517Y1868667D01*
X809933Y1869167D01*
X809600Y1869917D01*
X809517Y1870750D01*
X809683Y1871833D01*
X809933Y1872417D01*
X810350Y1873000D01*
X810933Y1873417D01*
X811517Y1873500D01*
X812100Y1873333D01*
X812517Y1872917D01*
G01X814617Y1873500D02*
X816700Y1868500D01*
X818783Y1873500D01*
G01X762708Y1916267D02*
X762583Y1916017D01*
X762500Y1915725D01*
Y1915392D01*
X762625Y1915017D01*
X762833Y1914725D01*
X763083Y1914517D01*
X763500Y1914350D01*
X763875Y1914308D01*
X764250Y1914392D01*
X764500Y1914517D01*
X764750Y1914767D01*
X764917Y1915058D01*
X765000Y1915350D01*
Y1915642D01*
X764917Y1915933D01*
X764792Y1916183D01*
X764625Y1916392D01*
G01X765000Y1918450D02*
X762500D01*
X763000Y1917950D01*
G01X765000D02*
Y1918950D01*
G01Y1921550D02*
X762500D01*
X763000Y1921050D01*
G01X765000D02*
Y1922050D01*
G01X762500Y1924650D02*
X762583Y1924317D01*
X762792Y1924067D01*
X763042Y1923900D01*
X763375Y1923775D01*
X763750Y1923733D01*
X764125Y1923775D01*
X764458Y1923900D01*
X764708Y1924067D01*
X764917Y1924317D01*
X765000Y1924650D01*
X764917Y1924983D01*
X764708Y1925233D01*
X764458Y1925400D01*
X764125Y1925525D01*
X763750Y1925567D01*
X763375Y1925525D01*
X763042Y1925400D01*
X762792Y1925233D01*
X762583Y1924983D01*
X762500Y1924650D01*
G01X769517Y1920500D02*
Y1923000D01*
X770558D01*
X770892Y1922875D01*
X771100Y1922708D01*
X771183Y1922375D01*
X771100Y1922042D01*
X770850Y1921833D01*
X770558Y1921708D01*
X769517D01*
G01X770558D02*
X771183Y1920500D01*
G01X773950D02*
Y1923000D01*
X772408Y1921208D01*
X774492D01*
G01X775758Y1922583D02*
X776008Y1922833D01*
X776300Y1922958D01*
X776633Y1923000D01*
X777050Y1922917D01*
X777342Y1922708D01*
X777425Y1922458D01*
X777383Y1922208D01*
X777217Y1922000D01*
X776383Y1921583D01*
X776008Y1921292D01*
X775758Y1920875D01*
X775675Y1920500D01*
X777425D01*
G01X780150D02*
Y1923000D01*
X778608Y1921208D01*
X780692D01*
G01X780199Y1933050D02*
Y1937050D01*
X772799D01*
G01X769517Y1924500D02*
Y1927000D01*
X770558D01*
X770892Y1926875D01*
X771100Y1926708D01*
X771183Y1926375D01*
X771100Y1926042D01*
X770850Y1925833D01*
X770558Y1925708D01*
X769517D01*
G01X770558D02*
X771183Y1924500D01*
G01X773950D02*
Y1927000D01*
X772408Y1925208D01*
X774492D01*
G01X775758Y1926583D02*
X776008Y1926833D01*
X776300Y1926958D01*
X776633Y1927000D01*
X777050Y1926917D01*
X777342Y1926708D01*
X777425Y1926458D01*
X777383Y1926208D01*
X777217Y1926000D01*
X776383Y1925583D01*
X776008Y1925292D01*
X775758Y1924875D01*
X775675Y1924500D01*
X777425D01*
G01X778733Y1924875D02*
X778983Y1924667D01*
X779275Y1924542D01*
X779650Y1924500D01*
X780025Y1924583D01*
X780317Y1924750D01*
X780525Y1925042D01*
X780567Y1925375D01*
X780483Y1925708D01*
X780275Y1925917D01*
X779983Y1926083D01*
X779692Y1926125D01*
X779400Y1926083D01*
X779025Y1925917D01*
X779150Y1927000D01*
X780275D01*
G01X769517Y1928500D02*
Y1931000D01*
X770558D01*
X770892Y1930875D01*
X771100Y1930708D01*
X771183Y1930375D01*
X771100Y1930042D01*
X770850Y1929833D01*
X770558Y1929708D01*
X769517D01*
G01X770558D02*
X771183Y1928500D01*
G01X773950D02*
Y1931000D01*
X772408Y1929208D01*
X774492D01*
G01X776550Y1931000D02*
X776217Y1930917D01*
X775967Y1930708D01*
X775800Y1930458D01*
X775675Y1930125D01*
X775633Y1929750D01*
X775675Y1929375D01*
X775800Y1929042D01*
X775967Y1928792D01*
X776217Y1928583D01*
X776550Y1928500D01*
X776883Y1928583D01*
X777133Y1928792D01*
X777300Y1929042D01*
X777425Y1929375D01*
X777467Y1929750D01*
X777425Y1930125D01*
X777300Y1930458D01*
X777133Y1930708D01*
X776883Y1930917D01*
X776550Y1931000D01*
G01X779650Y1928500D02*
X779942Y1928542D01*
X780275Y1928667D01*
X780483Y1928875D01*
X780567Y1929167D01*
X780483Y1929458D01*
X780233Y1929708D01*
X779858Y1929833D01*
X779442D01*
X779192Y1929917D01*
X778983Y1930125D01*
X778900Y1930417D01*
X779025Y1930708D01*
X779317Y1930917D01*
X779650Y1931000D01*
X779983Y1930917D01*
X780275Y1930708D01*
X780400Y1930417D01*
X780317Y1930125D01*
X780108Y1929917D01*
X779858Y1929833D01*
X779442D01*
X779067Y1929708D01*
X778817Y1929458D01*
X778733Y1929167D01*
X778817Y1928875D01*
X779025Y1928667D01*
X779358Y1928542D01*
X779650Y1928500D01*
G01X760033Y1932000D02*
Y1930208D01*
X760200Y1929833D01*
X760533Y1929583D01*
X760950Y1929500D01*
X761367Y1929583D01*
X761700Y1929833D01*
X761867Y1930208D01*
Y1932000D01*
G01X763133Y1930000D02*
X763383Y1929708D01*
X763717Y1929542D01*
X764092Y1929500D01*
X764425Y1929542D01*
X764758Y1929750D01*
X764967Y1930000D01*
X765008Y1930250D01*
X764925Y1930542D01*
X764633Y1930750D01*
X764342Y1930833D01*
X763967D01*
G01X764342D02*
X764592Y1930958D01*
X764800Y1931167D01*
X764883Y1931417D01*
X764800Y1931667D01*
X764592Y1931875D01*
X764217Y1932000D01*
X763842Y1931958D01*
X763467Y1931792D01*
G01X770014Y1944713D02*
Y1934713D01*
G01X769514Y1946513D02*
Y1957913D01*
G01X780199Y1937050D02*
Y1941050D01*
X772799D01*
G01X774299Y1951050D02*
Y1947050D01*
X781699D01*
G01X772014Y1958713D02*
Y1962713D01*
X764614D01*
G01X772014Y1963213D02*
Y1967213D01*
X764614D01*
G01X802284Y171225D02*
X799784D01*
Y172266D01*
X799909Y172600D01*
X800076Y172808D01*
X800409Y172891D01*
X800742Y172808D01*
X800951Y172558D01*
X801076Y172266D01*
Y171225D01*
G01Y172266D02*
X802284Y172891D01*
G01X801784Y174241D02*
X802076Y174491D01*
X802242Y174825D01*
X802284Y175200D01*
X802242Y175533D01*
X802034Y175866D01*
X801784Y176075D01*
X801534Y176116D01*
X801242Y176033D01*
X801034Y175741D01*
X800951Y175450D01*
Y175075D01*
G01Y175450D02*
X800826Y175700D01*
X800617Y175908D01*
X800367Y175991D01*
X800117Y175908D01*
X799909Y175700D01*
X799784Y175325D01*
X799826Y174950D01*
X799992Y174575D01*
G01X801784Y177341D02*
X802076Y177591D01*
X802242Y177925D01*
X802284Y178300D01*
X802242Y178633D01*
X802034Y178966D01*
X801784Y179175D01*
X801534Y179216D01*
X801242Y179133D01*
X801034Y178841D01*
X800951Y178550D01*
Y178175D01*
G01Y178550D02*
X800826Y178800D01*
X800617Y179008D01*
X800367Y179091D01*
X800117Y179008D01*
X799909Y178800D01*
X799784Y178425D01*
X799826Y178050D01*
X799992Y177675D01*
G01X801992Y180650D02*
X802201Y180941D01*
X802284Y181275D01*
X802201Y181608D01*
X801951Y181900D01*
X801576Y182108D01*
X801201Y182191D01*
X800742D01*
X800367Y182108D01*
X800034Y181900D01*
X799867Y181650D01*
X799784Y181358D01*
X799867Y181025D01*
X800034Y180775D01*
X800284Y180608D01*
X800617Y180525D01*
X800909Y180608D01*
X801201Y180816D01*
X801367Y181066D01*
X801409Y181358D01*
X801326Y181691D01*
X801117Y181941D01*
X800742Y182191D01*
G01X792450Y302500D02*
X792117Y302542D01*
X791825Y302708D01*
X791575Y302958D01*
X791408Y303250D01*
X791325Y303583D01*
Y303917D01*
X791408Y304250D01*
X791575Y304542D01*
X791825Y304792D01*
X792117Y304958D01*
X792450Y305000D01*
X792783Y304958D01*
X793075Y304792D01*
X793325Y304542D01*
X793492Y304250D01*
X793575Y303917D01*
Y303583D01*
X793492Y303250D01*
X793325Y302958D01*
X793075Y302708D01*
X792783Y302542D01*
X792450Y302500D01*
G01X792783Y303167D02*
X793283Y302500D01*
G01X794842Y302792D02*
X795133Y302583D01*
X795467Y302500D01*
X795800Y302583D01*
X796092Y302833D01*
X796300Y303208D01*
X796383Y303583D01*
Y304042D01*
X796300Y304417D01*
X796092Y304750D01*
X795842Y304917D01*
X795550Y305000D01*
X795217Y304917D01*
X794967Y304750D01*
X794800Y304500D01*
X794717Y304167D01*
X794800Y303875D01*
X795008Y303583D01*
X795258Y303417D01*
X795550Y303375D01*
X795883Y303458D01*
X796133Y303667D01*
X796383Y304042D01*
G01X795499Y316533D02*
X797291D01*
X797666Y316700D01*
X797916Y317033D01*
X797999Y317450D01*
X797916Y317867D01*
X797666Y318200D01*
X797291Y318367D01*
X795499D01*
G01X797999Y320550D02*
X795499D01*
X795999Y320050D01*
G01X797999D02*
Y321050D01*
G01X797499Y322733D02*
X797791Y322983D01*
X797957Y323317D01*
X797999Y323692D01*
X797957Y324025D01*
X797749Y324358D01*
X797499Y324567D01*
X797249Y324608D01*
X796957Y324525D01*
X796749Y324233D01*
X796666Y323942D01*
Y323567D01*
G01Y323942D02*
X796541Y324192D01*
X796332Y324400D01*
X796082Y324483D01*
X795832Y324400D01*
X795624Y324192D01*
X795499Y323817D01*
X795541Y323442D01*
X795707Y323067D01*
G01X782999Y317850D02*
Y331250D01*
G01X792999Y317850D02*
X782999D01*
G01X792999Y331250D02*
Y317850D01*
G01X802699Y334050D02*
Y338050D01*
X795299D01*
G01X802699Y330050D02*
Y334050D01*
X795299D01*
G01X782517Y334500D02*
Y337000D01*
X783558D01*
X783892Y336875D01*
X784100Y336708D01*
X784183Y336375D01*
X784100Y336042D01*
X783850Y335833D01*
X783558Y335708D01*
X782517D01*
G01X783558D02*
X784183Y334500D01*
G01X786950D02*
Y337000D01*
X785408Y335208D01*
X787492D01*
G01X789550Y334500D02*
Y337000D01*
X789050Y336500D01*
G01Y334500D02*
X790050D01*
G01X791858Y336583D02*
X792108Y336833D01*
X792400Y336958D01*
X792733Y337000D01*
X793150Y336917D01*
X793442Y336708D01*
X793525Y336458D01*
X793483Y336208D01*
X793317Y336000D01*
X792483Y335583D01*
X792108Y335292D01*
X791858Y334875D01*
X791775Y334500D01*
X793525D01*
G01X782999Y331250D02*
X792999D01*
G01X782378Y360224D02*
Y341024D01*
X793578D01*
Y360224D01*
X782378D01*
G01X789516Y366550D02*
Y369050D01*
X790557D01*
X790891Y368925D01*
X791099Y368758D01*
X791182Y368425D01*
X791099Y368092D01*
X790849Y367883D01*
X790557Y367758D01*
X789516D01*
G01X790557D02*
X791182Y366550D01*
G01X793949D02*
Y369050D01*
X792407Y367258D01*
X794491D01*
G01X795632Y367050D02*
X795882Y366758D01*
X796216Y366592D01*
X796591Y366550D01*
X796924Y366592D01*
X797257Y366800D01*
X797466Y367050D01*
X797507Y367300D01*
X797424Y367592D01*
X797132Y367800D01*
X796841Y367883D01*
X796466D01*
G01X796841D02*
X797091Y368008D01*
X797299Y368217D01*
X797382Y368467D01*
X797299Y368717D01*
X797091Y368925D01*
X796716Y369050D01*
X796341Y369008D01*
X795966Y368842D01*
G01X799649Y366550D02*
X799941Y366592D01*
X800274Y366717D01*
X800482Y366925D01*
X800566Y367217D01*
X800482Y367508D01*
X800232Y367758D01*
X799857Y367883D01*
X799441D01*
X799191Y367967D01*
X798982Y368175D01*
X798899Y368467D01*
X799024Y368758D01*
X799316Y368967D01*
X799649Y369050D01*
X799982Y368967D01*
X800274Y368758D01*
X800399Y368467D01*
X800316Y368175D01*
X800107Y367967D01*
X799857Y367883D01*
X799441D01*
X799066Y367758D01*
X798816Y367508D01*
X798732Y367217D01*
X798816Y366925D01*
X799024Y366717D01*
X799357Y366592D01*
X799649Y366550D01*
G01X789516Y362550D02*
Y365050D01*
X790557D01*
X790891Y364925D01*
X791099Y364758D01*
X791182Y364425D01*
X791099Y364092D01*
X790849Y363883D01*
X790557Y363758D01*
X789516D01*
G01X790557D02*
X791182Y362550D01*
G01X793949D02*
Y365050D01*
X792407Y363258D01*
X794491D01*
G01X795632Y363050D02*
X795882Y362758D01*
X796216Y362592D01*
X796591Y362550D01*
X796924Y362592D01*
X797257Y362800D01*
X797466Y363050D01*
X797507Y363300D01*
X797424Y363592D01*
X797132Y363800D01*
X796841Y363883D01*
X796466D01*
G01X796841D02*
X797091Y364008D01*
X797299Y364217D01*
X797382Y364467D01*
X797299Y364717D01*
X797091Y364925D01*
X796716Y365050D01*
X796341Y365008D01*
X795966Y364842D01*
G01X798941Y362842D02*
X799232Y362633D01*
X799566Y362550D01*
X799899Y362633D01*
X800191Y362883D01*
X800399Y363258D01*
X800482Y363633D01*
Y364092D01*
X800399Y364467D01*
X800191Y364800D01*
X799941Y364967D01*
X799649Y365050D01*
X799316Y364967D01*
X799066Y364800D01*
X798899Y364550D01*
X798816Y364217D01*
X798899Y363925D01*
X799107Y363633D01*
X799357Y363467D01*
X799649Y363425D01*
X799982Y363508D01*
X800232Y363717D01*
X800482Y364092D01*
G01X789978Y360224D02*
X787978Y358224D01*
X785978Y360224D01*
G01X789482Y373050D02*
Y371258D01*
X789649Y370883D01*
X789982Y370633D01*
X790399Y370550D01*
X790816Y370633D01*
X791149Y370883D01*
X791316Y371258D01*
Y373050D01*
G01X793499Y370550D02*
Y373050D01*
X792999Y372550D01*
G01Y370550D02*
X793999D01*
G01X797099D02*
Y373050D01*
X795557Y371258D01*
X797641D01*
G01X790950Y705000D02*
X790617Y705042D01*
X790325Y705208D01*
X790075Y705458D01*
X789908Y705750D01*
X789825Y706083D01*
Y706417D01*
X789908Y706750D01*
X790075Y707042D01*
X790325Y707292D01*
X790617Y707458D01*
X790950Y707500D01*
X791283Y707458D01*
X791575Y707292D01*
X791825Y707042D01*
X791992Y706750D01*
X792075Y706417D01*
Y706083D01*
X791992Y705750D01*
X791825Y705458D01*
X791575Y705208D01*
X791283Y705042D01*
X790950Y705000D01*
G01X791283Y705667D02*
X791783Y705000D01*
G01X793967D02*
X794050Y705542D01*
X794175Y706000D01*
X794342Y706417D01*
X794550Y706875D01*
X794883Y707500D01*
X793217D01*
G01X794499Y718533D02*
X796291D01*
X796666Y718700D01*
X796916Y719033D01*
X796999Y719450D01*
X796916Y719867D01*
X796666Y720200D01*
X796291Y720367D01*
X794499D01*
G01X796999Y722550D02*
X794499D01*
X794999Y722050D01*
G01X796999D02*
Y723050D01*
G01X794499Y725650D02*
X794582Y725317D01*
X794791Y725067D01*
X795041Y724900D01*
X795374Y724775D01*
X795749Y724733D01*
X796124Y724775D01*
X796457Y724900D01*
X796707Y725067D01*
X796916Y725317D01*
X796999Y725650D01*
X796916Y725983D01*
X796707Y726233D01*
X796457Y726400D01*
X796124Y726525D01*
X795749Y726567D01*
X795374Y726525D01*
X795041Y726400D01*
X794791Y726233D01*
X794582Y725983D01*
X794499Y725650D01*
G01X782499Y718850D02*
Y732250D01*
G01X792499Y718850D02*
X782499D01*
G01X792499Y732250D02*
Y718850D01*
G01X801199Y734050D02*
Y738050D01*
X793799D01*
G01X801199Y730050D02*
Y734050D01*
X793799D01*
G01X781517Y735500D02*
Y738000D01*
X782558D01*
X782892Y737875D01*
X783100Y737708D01*
X783183Y737375D01*
X783100Y737042D01*
X782850Y736833D01*
X782558Y736708D01*
X781517D01*
G01X782558D02*
X783183Y735500D01*
G01X785950D02*
Y738000D01*
X784408Y736208D01*
X786492D01*
G01X788550Y735500D02*
Y738000D01*
X788050Y737500D01*
G01Y735500D02*
X789050D01*
G01X791650D02*
Y738000D01*
X791150Y737500D01*
G01Y735500D02*
X792150D01*
G01X782499Y732250D02*
X792499D01*
G01X781096Y760682D02*
Y741482D01*
X792296D01*
Y760682D01*
X781096D01*
G01X787016Y768050D02*
Y770550D01*
X788057D01*
X788391Y770425D01*
X788599Y770258D01*
X788682Y769925D01*
X788599Y769592D01*
X788349Y769383D01*
X788057Y769258D01*
X787016D01*
G01X788057D02*
X788682Y768050D01*
G01X791449D02*
Y770550D01*
X789907Y768758D01*
X791991D01*
G01X793132Y768550D02*
X793382Y768258D01*
X793716Y768092D01*
X794091Y768050D01*
X794424Y768092D01*
X794757Y768300D01*
X794966Y768550D01*
X795007Y768800D01*
X794924Y769092D01*
X794632Y769300D01*
X794341Y769383D01*
X793966D01*
G01X794341D02*
X794591Y769508D01*
X794799Y769717D01*
X794882Y769967D01*
X794799Y770217D01*
X794591Y770425D01*
X794216Y770550D01*
X793841Y770508D01*
X793466Y770342D01*
G01X797649Y768050D02*
Y770550D01*
X796107Y768758D01*
X798191D01*
G01X787016Y764050D02*
Y766550D01*
X788057D01*
X788391Y766425D01*
X788599Y766258D01*
X788682Y765925D01*
X788599Y765592D01*
X788349Y765383D01*
X788057Y765258D01*
X787016D01*
G01X788057D02*
X788682Y764050D01*
G01X791449D02*
Y766550D01*
X789907Y764758D01*
X791991D01*
G01X793132Y764550D02*
X793382Y764258D01*
X793716Y764092D01*
X794091Y764050D01*
X794424Y764092D01*
X794757Y764300D01*
X794966Y764550D01*
X795007Y764800D01*
X794924Y765092D01*
X794632Y765300D01*
X794341Y765383D01*
X793966D01*
G01X794341D02*
X794591Y765508D01*
X794799Y765717D01*
X794882Y765967D01*
X794799Y766217D01*
X794591Y766425D01*
X794216Y766550D01*
X793841Y766508D01*
X793466Y766342D01*
G01X796232Y764425D02*
X796482Y764217D01*
X796774Y764092D01*
X797149Y764050D01*
X797524Y764133D01*
X797816Y764300D01*
X798024Y764592D01*
X798066Y764925D01*
X797982Y765258D01*
X797774Y765467D01*
X797482Y765633D01*
X797191Y765675D01*
X796899Y765633D01*
X796524Y765467D01*
X796649Y766550D01*
X797774D01*
G01X788696Y760682D02*
X786696Y758682D01*
X784696Y760682D01*
G01X786982Y775050D02*
Y773258D01*
X787149Y772883D01*
X787482Y772633D01*
X787899Y772550D01*
X788316Y772633D01*
X788649Y772883D01*
X788816Y773258D01*
Y775050D01*
G01X790999Y772550D02*
Y775050D01*
X790499Y774550D01*
G01Y772550D02*
X791499D01*
G01X794099D02*
Y775050D01*
X793599Y774550D01*
G01Y772550D02*
X794599D01*
G01X794850Y1084000D02*
Y1081500D01*
G01X793892Y1084000D02*
X795808D01*
G01X797117Y1081500D02*
Y1084000D01*
X798117D01*
X798450Y1083875D01*
X798700Y1083583D01*
X798783Y1083250D01*
X798700Y1082917D01*
X798492Y1082667D01*
X798117Y1082542D01*
X797117D01*
G01X800258Y1083583D02*
X800508Y1083833D01*
X800800Y1083958D01*
X801133Y1084000D01*
X801550Y1083917D01*
X801842Y1083708D01*
X801925Y1083458D01*
X801883Y1083208D01*
X801717Y1083000D01*
X800883Y1082583D01*
X800508Y1082292D01*
X800258Y1081875D01*
X800175Y1081500D01*
X801925D01*
G01X804067D02*
X804150Y1082042D01*
X804275Y1082500D01*
X804442Y1082917D01*
X804650Y1083375D01*
X804983Y1084000D01*
X803317D01*
G01X791450Y1108500D02*
X791117Y1108542D01*
X790825Y1108708D01*
X790575Y1108958D01*
X790408Y1109250D01*
X790325Y1109583D01*
Y1109917D01*
X790408Y1110250D01*
X790575Y1110542D01*
X790825Y1110792D01*
X791117Y1110958D01*
X791450Y1111000D01*
X791783Y1110958D01*
X792075Y1110792D01*
X792325Y1110542D01*
X792492Y1110250D01*
X792575Y1109917D01*
Y1109583D01*
X792492Y1109250D01*
X792325Y1108958D01*
X792075Y1108708D01*
X791783Y1108542D01*
X791450Y1108500D01*
G01X791783Y1109167D02*
X792283Y1108500D01*
G01X793633Y1108875D02*
X793883Y1108667D01*
X794175Y1108542D01*
X794550Y1108500D01*
X794925Y1108583D01*
X795217Y1108750D01*
X795425Y1109042D01*
X795467Y1109375D01*
X795383Y1109708D01*
X795175Y1109917D01*
X794883Y1110083D01*
X794592Y1110125D01*
X794300Y1110083D01*
X793925Y1109917D01*
X794050Y1111000D01*
X795175D01*
G01X801199Y1131050D02*
Y1135050D01*
X793799D01*
G01X794499Y1123083D02*
X796291D01*
X796666Y1123250D01*
X796916Y1123583D01*
X796999Y1124000D01*
X796916Y1124417D01*
X796666Y1124750D01*
X796291Y1124917D01*
X794499D01*
G01X796999Y1127017D02*
X796457Y1127100D01*
X795999Y1127225D01*
X795582Y1127392D01*
X795124Y1127600D01*
X794499Y1127933D01*
Y1126267D01*
G01X781999Y1121850D02*
Y1135250D01*
G01X791999Y1121850D02*
X781999D01*
G01X791999Y1135250D02*
Y1121850D01*
G01X801199Y1135050D02*
Y1139050D01*
X793799D01*
G01X781017Y1137000D02*
Y1139500D01*
X782058D01*
X782392Y1139375D01*
X782600Y1139208D01*
X782683Y1138875D01*
X782600Y1138542D01*
X782350Y1138333D01*
X782058Y1138208D01*
X781017D01*
G01X782058D02*
X782683Y1137000D01*
G01X785450D02*
Y1139500D01*
X783908Y1137708D01*
X785992D01*
G01X788050Y1137000D02*
Y1139500D01*
X787550Y1139000D01*
G01Y1137000D02*
X788550D01*
G01X791150Y1139500D02*
X790817Y1139417D01*
X790567Y1139208D01*
X790400Y1138958D01*
X790275Y1138625D01*
X790233Y1138250D01*
X790275Y1137875D01*
X790400Y1137542D01*
X790567Y1137292D01*
X790817Y1137083D01*
X791150Y1137000D01*
X791483Y1137083D01*
X791733Y1137292D01*
X791900Y1137542D01*
X792025Y1137875D01*
X792067Y1138250D01*
X792025Y1138625D01*
X791900Y1138958D01*
X791733Y1139208D01*
X791483Y1139417D01*
X791150Y1139500D01*
G01X781999Y1135250D02*
X791999D01*
G01X781233Y1162192D02*
Y1142992D01*
X792433D01*
Y1162192D01*
X781233D01*
G01X788016Y1165550D02*
Y1168050D01*
X789057D01*
X789391Y1167925D01*
X789599Y1167758D01*
X789682Y1167425D01*
X789599Y1167092D01*
X789349Y1166883D01*
X789057Y1166758D01*
X788016D01*
G01X789057D02*
X789682Y1165550D01*
G01X792449D02*
Y1168050D01*
X790907Y1166258D01*
X792991D01*
G01X794132Y1166050D02*
X794382Y1165758D01*
X794716Y1165592D01*
X795091Y1165550D01*
X795424Y1165592D01*
X795757Y1165800D01*
X795966Y1166050D01*
X796007Y1166300D01*
X795924Y1166592D01*
X795632Y1166800D01*
X795341Y1166883D01*
X794966D01*
G01X795341D02*
X795591Y1167008D01*
X795799Y1167217D01*
X795882Y1167467D01*
X795799Y1167717D01*
X795591Y1167925D01*
X795216Y1168050D01*
X794841Y1168008D01*
X794466Y1167842D01*
G01X798149Y1168050D02*
X797816Y1167967D01*
X797566Y1167758D01*
X797399Y1167508D01*
X797274Y1167175D01*
X797232Y1166800D01*
X797274Y1166425D01*
X797399Y1166092D01*
X797566Y1165842D01*
X797816Y1165633D01*
X798149Y1165550D01*
X798482Y1165633D01*
X798732Y1165842D01*
X798899Y1166092D01*
X799024Y1166425D01*
X799066Y1166800D01*
X799024Y1167175D01*
X798899Y1167508D01*
X798732Y1167758D01*
X798482Y1167967D01*
X798149Y1168050D01*
G01X788016Y1169550D02*
Y1172050D01*
X789057D01*
X789391Y1171925D01*
X789599Y1171758D01*
X789682Y1171425D01*
X789599Y1171092D01*
X789349Y1170883D01*
X789057Y1170758D01*
X788016D01*
G01X789057D02*
X789682Y1169550D01*
G01X792449D02*
Y1172050D01*
X790907Y1170258D01*
X792991D01*
G01X794132Y1170050D02*
X794382Y1169758D01*
X794716Y1169592D01*
X795091Y1169550D01*
X795424Y1169592D01*
X795757Y1169800D01*
X795966Y1170050D01*
X796007Y1170300D01*
X795924Y1170592D01*
X795632Y1170800D01*
X795341Y1170883D01*
X794966D01*
G01X795341D02*
X795591Y1171008D01*
X795799Y1171217D01*
X795882Y1171467D01*
X795799Y1171717D01*
X795591Y1171925D01*
X795216Y1172050D01*
X794841Y1172008D01*
X794466Y1171842D01*
G01X798149Y1169550D02*
Y1172050D01*
X797649Y1171550D01*
G01Y1169550D02*
X798649D01*
G01X788033Y1176500D02*
Y1174708D01*
X788200Y1174333D01*
X788533Y1174083D01*
X788950Y1174000D01*
X789367Y1174083D01*
X789700Y1174333D01*
X789867Y1174708D01*
Y1176500D01*
G01X792050Y1174000D02*
X792342Y1174042D01*
X792675Y1174167D01*
X792883Y1174375D01*
X792967Y1174667D01*
X792883Y1174958D01*
X792633Y1175208D01*
X792258Y1175333D01*
X791842D01*
X791592Y1175417D01*
X791383Y1175625D01*
X791300Y1175917D01*
X791425Y1176208D01*
X791717Y1176417D01*
X792050Y1176500D01*
X792383Y1176417D01*
X792675Y1176208D01*
X792800Y1175917D01*
X792717Y1175625D01*
X792508Y1175417D01*
X792258Y1175333D01*
X791842D01*
X791467Y1175208D01*
X791217Y1174958D01*
X791133Y1174667D01*
X791217Y1174375D01*
X791425Y1174167D01*
X791758Y1174042D01*
X792050Y1174000D01*
G01X788833Y1162192D02*
X786833Y1160192D01*
X784833Y1162192D01*
G01X798500Y1473400D02*
X798458Y1473067D01*
X798292Y1472775D01*
X798042Y1472525D01*
X797750Y1472358D01*
X797417Y1472275D01*
X797083D01*
X796750Y1472358D01*
X796458Y1472525D01*
X796208Y1472775D01*
X796042Y1473067D01*
X796000Y1473400D01*
X796042Y1473733D01*
X796208Y1474025D01*
X796458Y1474275D01*
X796750Y1474442D01*
X797083Y1474525D01*
X797417D01*
X797750Y1474442D01*
X798042Y1474275D01*
X798292Y1474025D01*
X798458Y1473733D01*
X798500Y1473400D01*
G01X797833Y1473733D02*
X798500Y1474233D01*
G01X798000Y1475583D02*
X798292Y1475833D01*
X798458Y1476167D01*
X798500Y1476542D01*
X798458Y1476875D01*
X798250Y1477208D01*
X798000Y1477417D01*
X797750Y1477458D01*
X797458Y1477375D01*
X797250Y1477083D01*
X797167Y1476792D01*
Y1476417D01*
G01Y1476792D02*
X797042Y1477042D01*
X796833Y1477250D01*
X796583Y1477333D01*
X796333Y1477250D01*
X796125Y1477042D01*
X796000Y1476667D01*
X796042Y1476292D01*
X796208Y1475917D01*
G01X796417Y1478808D02*
X796167Y1479058D01*
X796042Y1479350D01*
X796000Y1479683D01*
X796083Y1480100D01*
X796292Y1480392D01*
X796542Y1480475D01*
X796792Y1480433D01*
X797000Y1480267D01*
X797417Y1479433D01*
X797708Y1479058D01*
X798125Y1478808D01*
X798500Y1478725D01*
Y1480475D01*
G01X802500Y1472567D02*
X800000D01*
Y1473608D01*
X800125Y1473942D01*
X800292Y1474150D01*
X800625Y1474233D01*
X800958Y1474150D01*
X801167Y1473900D01*
X801292Y1473608D01*
Y1472567D01*
G01Y1473608D02*
X802500Y1474233D01*
G01X802000Y1475583D02*
X802292Y1475833D01*
X802458Y1476167D01*
X802500Y1476542D01*
X802458Y1476875D01*
X802250Y1477208D01*
X802000Y1477417D01*
X801750Y1477458D01*
X801458Y1477375D01*
X801250Y1477083D01*
X801167Y1476792D01*
Y1476417D01*
G01Y1476792D02*
X801042Y1477042D01*
X800833Y1477250D01*
X800583Y1477333D01*
X800333Y1477250D01*
X800125Y1477042D01*
X800000Y1476667D01*
X800042Y1476292D01*
X800208Y1475917D01*
G01X802500Y1480100D02*
X800000D01*
X801792Y1478558D01*
Y1480642D01*
G01X802500Y1483200D02*
X800000D01*
X801792Y1481658D01*
Y1483742D01*
G01X796000Y1486850D02*
X798500D01*
G01X796000Y1485892D02*
Y1487808D01*
G01X798500Y1489117D02*
X796000D01*
Y1490117D01*
X796125Y1490450D01*
X796417Y1490700D01*
X796750Y1490783D01*
X797083Y1490700D01*
X797333Y1490492D01*
X797458Y1490117D01*
Y1489117D01*
G01X796417Y1492258D02*
X796167Y1492508D01*
X796042Y1492800D01*
X796000Y1493133D01*
X796083Y1493550D01*
X796292Y1493842D01*
X796542Y1493925D01*
X796792Y1493883D01*
X797000Y1493717D01*
X797417Y1492883D01*
X797708Y1492508D01*
X798125Y1492258D01*
X798500Y1492175D01*
Y1493925D01*
G01X797458Y1495358D02*
X797167Y1495650D01*
X797000Y1495900D01*
X796917Y1496233D01*
X797000Y1496525D01*
X797167Y1496733D01*
X797417Y1496900D01*
X797708Y1496942D01*
X797958Y1496900D01*
X798208Y1496733D01*
X798417Y1496483D01*
X798500Y1496192D01*
X798417Y1495858D01*
X798167Y1495567D01*
X797792Y1495400D01*
X797375Y1495358D01*
X796833Y1495442D01*
X796542Y1495567D01*
X796250Y1495775D01*
X796042Y1496067D01*
X796000Y1496358D01*
X796083Y1496650D01*
X796292Y1496858D01*
G01X791950Y1513500D02*
X791617Y1513542D01*
X791325Y1513708D01*
X791075Y1513958D01*
X790908Y1514250D01*
X790825Y1514583D01*
Y1514917D01*
X790908Y1515250D01*
X791075Y1515542D01*
X791325Y1515792D01*
X791617Y1515958D01*
X791950Y1516000D01*
X792283Y1515958D01*
X792575Y1515792D01*
X792825Y1515542D01*
X792992Y1515250D01*
X793075Y1514917D01*
Y1514583D01*
X792992Y1514250D01*
X792825Y1513958D01*
X792575Y1513708D01*
X792283Y1513542D01*
X791950Y1513500D01*
G01X792283Y1514167D02*
X792783Y1513500D01*
G01X794133Y1514000D02*
X794383Y1513708D01*
X794717Y1513542D01*
X795092Y1513500D01*
X795425Y1513542D01*
X795758Y1513750D01*
X795967Y1514000D01*
X796008Y1514250D01*
X795925Y1514542D01*
X795633Y1514750D01*
X795342Y1514833D01*
X794967D01*
G01X795342D02*
X795592Y1514958D01*
X795800Y1515167D01*
X795883Y1515417D01*
X795800Y1515667D01*
X795592Y1515875D01*
X795217Y1516000D01*
X794842Y1515958D01*
X794467Y1515792D01*
G01X797999Y1527083D02*
X799791D01*
X800166Y1527250D01*
X800416Y1527583D01*
X800499Y1528000D01*
X800416Y1528417D01*
X800166Y1528750D01*
X799791Y1528917D01*
X797999D01*
G01X800499Y1531600D02*
X797999D01*
X799791Y1530058D01*
Y1532142D01*
G01X785253Y1525678D02*
Y1539078D01*
G01X795253Y1525678D02*
X785253D01*
G01X795253Y1539078D02*
Y1525678D01*
G01X803881Y1536893D02*
Y1540893D01*
X796481D01*
G01X803881D02*
Y1544893D01*
X796481D01*
G01X785253Y1539078D02*
X795253D01*
G01X783727Y1567096D02*
Y1547896D01*
X794927D01*
Y1567096D01*
X783727D01*
G01X792198Y1570893D02*
Y1573393D01*
X793239D01*
X793573Y1573268D01*
X793781Y1573101D01*
X793864Y1572768D01*
X793781Y1572435D01*
X793531Y1572226D01*
X793239Y1572101D01*
X792198D01*
G01X793239D02*
X793864Y1570893D01*
G01X796631D02*
Y1573393D01*
X795089Y1571601D01*
X797173D01*
G01X798439Y1572976D02*
X798689Y1573226D01*
X798981Y1573351D01*
X799314Y1573393D01*
X799731Y1573310D01*
X800023Y1573101D01*
X800106Y1572851D01*
X800064Y1572601D01*
X799898Y1572393D01*
X799064Y1571976D01*
X798689Y1571685D01*
X798439Y1571268D01*
X798356Y1570893D01*
X800106D01*
G01X801539Y1571935D02*
X801831Y1572226D01*
X802081Y1572393D01*
X802414Y1572476D01*
X802706Y1572393D01*
X802914Y1572226D01*
X803081Y1571976D01*
X803123Y1571685D01*
X803081Y1571435D01*
X802914Y1571185D01*
X802664Y1570976D01*
X802373Y1570893D01*
X802039Y1570976D01*
X801748Y1571226D01*
X801581Y1571601D01*
X801539Y1572018D01*
X801623Y1572560D01*
X801748Y1572851D01*
X801956Y1573143D01*
X802248Y1573351D01*
X802539Y1573393D01*
X802831Y1573310D01*
X803039Y1573101D01*
G01X792198Y1574893D02*
Y1577393D01*
X793239D01*
X793573Y1577268D01*
X793781Y1577101D01*
X793864Y1576768D01*
X793781Y1576435D01*
X793531Y1576226D01*
X793239Y1576101D01*
X792198D01*
G01X793239D02*
X793864Y1574893D01*
G01X796631D02*
Y1577393D01*
X795089Y1575601D01*
X797173D01*
G01X798439Y1576976D02*
X798689Y1577226D01*
X798981Y1577351D01*
X799314Y1577393D01*
X799731Y1577310D01*
X800023Y1577101D01*
X800106Y1576851D01*
X800064Y1576601D01*
X799898Y1576393D01*
X799064Y1575976D01*
X798689Y1575685D01*
X798439Y1575268D01*
X798356Y1574893D01*
X800106D01*
G01X802248D02*
X802331Y1575435D01*
X802456Y1575893D01*
X802623Y1576310D01*
X802831Y1576768D01*
X803164Y1577393D01*
X801498D01*
G01X791327Y1567096D02*
X789327Y1565096D01*
X787327Y1567096D01*
G01X792032Y1581550D02*
Y1579758D01*
X792199Y1579383D01*
X792532Y1579133D01*
X792949Y1579050D01*
X793366Y1579133D01*
X793699Y1579383D01*
X793866Y1579758D01*
Y1581550D01*
G01X795132Y1579425D02*
X795382Y1579217D01*
X795674Y1579092D01*
X796049Y1579050D01*
X796424Y1579133D01*
X796716Y1579300D01*
X796924Y1579592D01*
X796966Y1579925D01*
X796882Y1580258D01*
X796674Y1580467D01*
X796382Y1580633D01*
X796091Y1580675D01*
X795799Y1580633D01*
X795424Y1580467D01*
X795549Y1581550D01*
X796674D01*
G01X790016Y1791550D02*
Y1794050D01*
X791057D01*
X791391Y1793925D01*
X791599Y1793758D01*
X791682Y1793425D01*
X791599Y1793092D01*
X791349Y1792883D01*
X791057Y1792758D01*
X790016D01*
G01X791057D02*
X791682Y1791550D01*
G01X793032Y1792050D02*
X793282Y1791758D01*
X793616Y1791592D01*
X793991Y1791550D01*
X794324Y1791592D01*
X794657Y1791800D01*
X794866Y1792050D01*
X794907Y1792300D01*
X794824Y1792592D01*
X794532Y1792800D01*
X794241Y1792883D01*
X793866D01*
G01X794241D02*
X794491Y1793008D01*
X794699Y1793217D01*
X794782Y1793467D01*
X794699Y1793717D01*
X794491Y1793925D01*
X794116Y1794050D01*
X793741Y1794008D01*
X793366Y1793842D01*
G01X796132Y1792050D02*
X796382Y1791758D01*
X796716Y1791592D01*
X797091Y1791550D01*
X797424Y1791592D01*
X797757Y1791800D01*
X797966Y1792050D01*
X798007Y1792300D01*
X797924Y1792592D01*
X797632Y1792800D01*
X797341Y1792883D01*
X796966D01*
G01X797341D02*
X797591Y1793008D01*
X797799Y1793217D01*
X797882Y1793467D01*
X797799Y1793717D01*
X797591Y1793925D01*
X797216Y1794050D01*
X796841Y1794008D01*
X796466Y1793842D01*
G01X799357Y1792592D02*
X799649Y1792883D01*
X799899Y1793050D01*
X800232Y1793133D01*
X800524Y1793050D01*
X800732Y1792883D01*
X800899Y1792633D01*
X800941Y1792342D01*
X800899Y1792092D01*
X800732Y1791842D01*
X800482Y1791633D01*
X800191Y1791550D01*
X799857Y1791633D01*
X799566Y1791883D01*
X799399Y1792258D01*
X799357Y1792675D01*
X799441Y1793217D01*
X799566Y1793508D01*
X799774Y1793800D01*
X800066Y1794008D01*
X800357Y1794050D01*
X800649Y1793967D01*
X800857Y1793758D01*
G01X792566Y1803134D02*
Y1805634D01*
X793607D01*
X793941Y1805509D01*
X794149Y1805342D01*
X794232Y1805009D01*
X794149Y1804676D01*
X793899Y1804467D01*
X793607Y1804342D01*
X792566D01*
G01X793607D02*
X794232Y1803134D01*
G01X795582Y1803634D02*
X795832Y1803342D01*
X796166Y1803176D01*
X796541Y1803134D01*
X796874Y1803176D01*
X797207Y1803384D01*
X797416Y1803634D01*
X797457Y1803884D01*
X797374Y1804176D01*
X797082Y1804384D01*
X796791Y1804467D01*
X796416D01*
G01X796791D02*
X797041Y1804592D01*
X797249Y1804801D01*
X797332Y1805051D01*
X797249Y1805301D01*
X797041Y1805509D01*
X796666Y1805634D01*
X796291Y1805592D01*
X795916Y1805426D01*
G01X798682Y1803509D02*
X798932Y1803301D01*
X799224Y1803176D01*
X799599Y1803134D01*
X799974Y1803217D01*
X800266Y1803384D01*
X800474Y1803676D01*
X800516Y1804009D01*
X800432Y1804342D01*
X800224Y1804551D01*
X799932Y1804717D01*
X799641Y1804759D01*
X799349Y1804717D01*
X798974Y1804551D01*
X799099Y1805634D01*
X800224D01*
G01X801907Y1805217D02*
X802157Y1805467D01*
X802449Y1805592D01*
X802782Y1805634D01*
X803199Y1805551D01*
X803491Y1805342D01*
X803574Y1805092D01*
X803532Y1804842D01*
X803366Y1804634D01*
X802532Y1804217D01*
X802157Y1803926D01*
X801907Y1803509D01*
X801824Y1803134D01*
X803574D01*
G01X783849Y1806634D02*
Y1802634D01*
X791249D01*
G01X792566Y1799134D02*
Y1801634D01*
X793607D01*
X793941Y1801509D01*
X794149Y1801342D01*
X794232Y1801009D01*
X794149Y1800676D01*
X793899Y1800467D01*
X793607Y1800342D01*
X792566D01*
G01X793607D02*
X794232Y1799134D01*
G01X795582Y1799634D02*
X795832Y1799342D01*
X796166Y1799176D01*
X796541Y1799134D01*
X796874Y1799176D01*
X797207Y1799384D01*
X797416Y1799634D01*
X797457Y1799884D01*
X797374Y1800176D01*
X797082Y1800384D01*
X796791Y1800467D01*
X796416D01*
G01X796791D02*
X797041Y1800592D01*
X797249Y1800801D01*
X797332Y1801051D01*
X797249Y1801301D01*
X797041Y1801509D01*
X796666Y1801634D01*
X796291Y1801592D01*
X795916Y1801426D01*
G01X798682Y1799509D02*
X798932Y1799301D01*
X799224Y1799176D01*
X799599Y1799134D01*
X799974Y1799217D01*
X800266Y1799384D01*
X800474Y1799676D01*
X800516Y1800009D01*
X800432Y1800342D01*
X800224Y1800551D01*
X799932Y1800717D01*
X799641Y1800759D01*
X799349Y1800717D01*
X798974Y1800551D01*
X799099Y1801634D01*
X800224D01*
G01X803199Y1799134D02*
Y1801634D01*
X801657Y1799842D01*
X803741D01*
G01X783849Y1802634D02*
Y1798634D01*
X791249D01*
G01X781757Y1825401D02*
X781632Y1825151D01*
X781549Y1824859D01*
Y1824526D01*
X781674Y1824151D01*
X781882Y1823859D01*
X782132Y1823651D01*
X782549Y1823484D01*
X782924Y1823442D01*
X783299Y1823526D01*
X783549Y1823651D01*
X783799Y1823901D01*
X783966Y1824192D01*
X784049Y1824484D01*
Y1824776D01*
X783966Y1825067D01*
X783841Y1825317D01*
X783674Y1825526D01*
G01X783549Y1826667D02*
X783841Y1826917D01*
X784007Y1827251D01*
X784049Y1827626D01*
X784007Y1827959D01*
X783799Y1828292D01*
X783549Y1828501D01*
X783299Y1828542D01*
X783007Y1828459D01*
X782799Y1828167D01*
X782716Y1827876D01*
Y1827501D01*
G01Y1827876D02*
X782591Y1828126D01*
X782382Y1828334D01*
X782132Y1828417D01*
X781882Y1828334D01*
X781674Y1828126D01*
X781549Y1827751D01*
X781591Y1827376D01*
X781757Y1827001D01*
G01X784049Y1831184D02*
X781549D01*
X783341Y1829642D01*
Y1831726D01*
G01X783007Y1832992D02*
X782716Y1833284D01*
X782549Y1833534D01*
X782466Y1833867D01*
X782549Y1834159D01*
X782716Y1834367D01*
X782966Y1834534D01*
X783257Y1834576D01*
X783507Y1834534D01*
X783757Y1834367D01*
X783966Y1834117D01*
X784049Y1833826D01*
X783966Y1833492D01*
X783716Y1833201D01*
X783341Y1833034D01*
X782924Y1832992D01*
X782382Y1833076D01*
X782091Y1833201D01*
X781799Y1833409D01*
X781591Y1833701D01*
X781549Y1833992D01*
X781632Y1834284D01*
X781841Y1834492D01*
G01X786757Y1825401D02*
X786632Y1825151D01*
X786549Y1824859D01*
Y1824526D01*
X786674Y1824151D01*
X786882Y1823859D01*
X787132Y1823651D01*
X787549Y1823484D01*
X787924Y1823442D01*
X788299Y1823526D01*
X788549Y1823651D01*
X788799Y1823901D01*
X788966Y1824192D01*
X789049Y1824484D01*
Y1824776D01*
X788966Y1825067D01*
X788841Y1825317D01*
X788674Y1825526D01*
G01X788549Y1826667D02*
X788841Y1826917D01*
X789007Y1827251D01*
X789049Y1827626D01*
X789007Y1827959D01*
X788799Y1828292D01*
X788549Y1828501D01*
X788299Y1828542D01*
X788007Y1828459D01*
X787799Y1828167D01*
X787716Y1827876D01*
Y1827501D01*
G01Y1827876D02*
X787591Y1828126D01*
X787382Y1828334D01*
X787132Y1828417D01*
X786882Y1828334D01*
X786674Y1828126D01*
X786549Y1827751D01*
X786591Y1827376D01*
X786757Y1827001D01*
G01X789049Y1831184D02*
X786549D01*
X788341Y1829642D01*
Y1831726D01*
G01X789049Y1833701D02*
X788507Y1833784D01*
X788049Y1833909D01*
X787632Y1834076D01*
X787174Y1834284D01*
X786549Y1834617D01*
Y1832951D01*
G01X798816Y1824450D02*
Y1826950D01*
X799857D01*
X800191Y1826825D01*
X800399Y1826658D01*
X800482Y1826325D01*
X800399Y1825992D01*
X800149Y1825783D01*
X799857Y1825658D01*
X798816D01*
G01X799857D02*
X800482Y1824450D01*
G01X801832Y1824950D02*
X802082Y1824658D01*
X802416Y1824492D01*
X802791Y1824450D01*
X803124Y1824492D01*
X803457Y1824700D01*
X803666Y1824950D01*
X803707Y1825200D01*
X803624Y1825492D01*
X803332Y1825700D01*
X803041Y1825783D01*
X802666D01*
G01X803041D02*
X803291Y1825908D01*
X803499Y1826117D01*
X803582Y1826367D01*
X803499Y1826617D01*
X803291Y1826825D01*
X802916Y1826950D01*
X802541Y1826908D01*
X802166Y1826742D01*
G01X805057Y1826533D02*
X805307Y1826783D01*
X805599Y1826908D01*
X805932Y1826950D01*
X806349Y1826867D01*
X806641Y1826658D01*
X806724Y1826408D01*
X806682Y1826158D01*
X806516Y1825950D01*
X805682Y1825533D01*
X805307Y1825242D01*
X805057Y1824825D01*
X804974Y1824450D01*
X806724D01*
G01X808157Y1825492D02*
X808449Y1825783D01*
X808699Y1825950D01*
X809032Y1826033D01*
X809324Y1825950D01*
X809532Y1825783D01*
X809699Y1825533D01*
X809741Y1825242D01*
X809699Y1824992D01*
X809532Y1824742D01*
X809282Y1824533D01*
X808991Y1824450D01*
X808657Y1824533D01*
X808366Y1824783D01*
X808199Y1825158D01*
X808157Y1825575D01*
X808241Y1826117D01*
X808366Y1826408D01*
X808574Y1826700D01*
X808866Y1826908D01*
X809157Y1826950D01*
X809449Y1826867D01*
X809657Y1826658D01*
G01X798816Y1820450D02*
Y1822950D01*
X799857D01*
X800191Y1822825D01*
X800399Y1822658D01*
X800482Y1822325D01*
X800399Y1821992D01*
X800149Y1821783D01*
X799857Y1821658D01*
X798816D01*
G01X799857D02*
X800482Y1820450D01*
G01X801832Y1820950D02*
X802082Y1820658D01*
X802416Y1820492D01*
X802791Y1820450D01*
X803124Y1820492D01*
X803457Y1820700D01*
X803666Y1820950D01*
X803707Y1821200D01*
X803624Y1821492D01*
X803332Y1821700D01*
X803041Y1821783D01*
X802666D01*
G01X803041D02*
X803291Y1821908D01*
X803499Y1822117D01*
X803582Y1822367D01*
X803499Y1822617D01*
X803291Y1822825D01*
X802916Y1822950D01*
X802541Y1822908D01*
X802166Y1822742D01*
G01X804932Y1820950D02*
X805182Y1820658D01*
X805516Y1820492D01*
X805891Y1820450D01*
X806224Y1820492D01*
X806557Y1820700D01*
X806766Y1820950D01*
X806807Y1821200D01*
X806724Y1821492D01*
X806432Y1821700D01*
X806141Y1821783D01*
X805766D01*
G01X806141D02*
X806391Y1821908D01*
X806599Y1822117D01*
X806682Y1822367D01*
X806599Y1822617D01*
X806391Y1822825D01*
X806016Y1822950D01*
X805641Y1822908D01*
X805266Y1822742D01*
G01X809449Y1820450D02*
Y1822950D01*
X807907Y1821158D01*
X809991D01*
G01X783208Y1905767D02*
X783083Y1905517D01*
X783000Y1905225D01*
Y1904892D01*
X783125Y1904517D01*
X783333Y1904225D01*
X783583Y1904017D01*
X784000Y1903850D01*
X784375Y1903808D01*
X784750Y1903892D01*
X785000Y1904017D01*
X785250Y1904267D01*
X785417Y1904558D01*
X785500Y1904850D01*
Y1905142D01*
X785417Y1905433D01*
X785292Y1905683D01*
X785125Y1905892D01*
G01X785500Y1907950D02*
X783000D01*
X783500Y1907450D01*
G01X785500D02*
Y1908450D01*
G01X783000Y1911050D02*
X783083Y1910717D01*
X783292Y1910467D01*
X783542Y1910300D01*
X783875Y1910175D01*
X784250Y1910133D01*
X784625Y1910175D01*
X784958Y1910300D01*
X785208Y1910467D01*
X785417Y1910717D01*
X785500Y1911050D01*
X785417Y1911383D01*
X785208Y1911633D01*
X784958Y1911800D01*
X784625Y1911925D01*
X784250Y1911967D01*
X783875Y1911925D01*
X783542Y1911800D01*
X783292Y1911633D01*
X783083Y1911383D01*
X783000Y1911050D01*
G01X783417Y1913358D02*
X783167Y1913608D01*
X783042Y1913900D01*
X783000Y1914233D01*
X783083Y1914650D01*
X783292Y1914942D01*
X783542Y1915025D01*
X783792Y1914983D01*
X784000Y1914817D01*
X784417Y1913983D01*
X784708Y1913608D01*
X785125Y1913358D01*
X785500Y1913275D01*
Y1915025D01*
G01X794950Y1902500D02*
X794617Y1902542D01*
X794325Y1902708D01*
X794075Y1902958D01*
X793908Y1903250D01*
X793825Y1903583D01*
Y1903917D01*
X793908Y1904250D01*
X794075Y1904542D01*
X794325Y1904792D01*
X794617Y1904958D01*
X794950Y1905000D01*
X795283Y1904958D01*
X795575Y1904792D01*
X795825Y1904542D01*
X795992Y1904250D01*
X796075Y1903917D01*
Y1903583D01*
X795992Y1903250D01*
X795825Y1902958D01*
X795575Y1902708D01*
X795283Y1902542D01*
X794950Y1902500D01*
G01X795283Y1903167D02*
X795783Y1902500D01*
G01X797258Y1904583D02*
X797508Y1904833D01*
X797800Y1904958D01*
X798133Y1905000D01*
X798550Y1904917D01*
X798842Y1904708D01*
X798925Y1904458D01*
X798883Y1904208D01*
X798717Y1904000D01*
X797883Y1903583D01*
X797508Y1903292D01*
X797258Y1902875D01*
X797175Y1902500D01*
X798925D01*
G01X797350Y1898500D02*
Y1896000D01*
G01X796392Y1898500D02*
X798308D01*
G01X799617Y1896000D02*
Y1898500D01*
X800617D01*
X800950Y1898375D01*
X801200Y1898083D01*
X801283Y1897750D01*
X801200Y1897417D01*
X800992Y1897167D01*
X800617Y1897042D01*
X799617D01*
G01X802758Y1898083D02*
X803008Y1898333D01*
X803300Y1898458D01*
X803633Y1898500D01*
X804050Y1898417D01*
X804342Y1898208D01*
X804425Y1897958D01*
X804383Y1897708D01*
X804217Y1897500D01*
X803383Y1897083D01*
X803008Y1896792D01*
X802758Y1896375D01*
X802675Y1896000D01*
X804425D01*
G01X805733Y1896375D02*
X805983Y1896167D01*
X806275Y1896042D01*
X806650Y1896000D01*
X807025Y1896083D01*
X807317Y1896250D01*
X807525Y1896542D01*
X807567Y1896875D01*
X807483Y1897208D01*
X807275Y1897417D01*
X806983Y1897583D01*
X806692Y1897625D01*
X806400Y1897583D01*
X806025Y1897417D01*
X806150Y1898500D01*
X807275D01*
G01X795500Y1934533D02*
X797292D01*
X797667Y1934700D01*
X797917Y1935033D01*
X798000Y1935450D01*
X797917Y1935867D01*
X797667Y1936200D01*
X797292Y1936367D01*
X795500D01*
G01X798000Y1938550D02*
X795500D01*
X796000Y1938050D01*
G01X798000D02*
Y1939050D01*
G01X783499Y1932350D02*
Y1945750D01*
G01X793499Y1932350D02*
X783499D01*
G01X793499Y1945750D02*
Y1932350D01*
G01X802381Y1942393D02*
Y1946393D01*
X794981D01*
G01X802381D02*
Y1950393D01*
X794981D01*
G01X783499Y1945750D02*
X793499D01*
G01X781214Y1973013D02*
Y1953813D01*
X792414D01*
Y1973013D01*
X781214D01*
G01X793698Y1975893D02*
Y1978393D01*
X794739D01*
X795073Y1978268D01*
X795281Y1978101D01*
X795364Y1977768D01*
X795281Y1977435D01*
X795031Y1977226D01*
X794739Y1977101D01*
X793698D01*
G01X794739D02*
X795364Y1975893D01*
G01X798131D02*
Y1978393D01*
X796589Y1976601D01*
X798673D01*
G01X799939Y1977976D02*
X800189Y1978226D01*
X800481Y1978351D01*
X800814Y1978393D01*
X801231Y1978310D01*
X801523Y1978101D01*
X801606Y1977851D01*
X801564Y1977601D01*
X801398Y1977393D01*
X800564Y1976976D01*
X800189Y1976685D01*
X799939Y1976268D01*
X799856Y1975893D01*
X801606D01*
G01X803039Y1977976D02*
X803289Y1978226D01*
X803581Y1978351D01*
X803914Y1978393D01*
X804331Y1978310D01*
X804623Y1978101D01*
X804706Y1977851D01*
X804664Y1977601D01*
X804498Y1977393D01*
X803664Y1976976D01*
X803289Y1976685D01*
X803039Y1976268D01*
X802956Y1975893D01*
X804706D01*
G01X788814Y1973013D02*
X786814Y1971013D01*
X784814Y1973013D01*
G01X793698Y1979893D02*
Y1982393D01*
X794739D01*
X795073Y1982268D01*
X795281Y1982101D01*
X795364Y1981768D01*
X795281Y1981435D01*
X795031Y1981226D01*
X794739Y1981101D01*
X793698D01*
G01X794739D02*
X795364Y1979893D01*
G01X798131D02*
Y1982393D01*
X796589Y1980601D01*
X798673D01*
G01X799939Y1981976D02*
X800189Y1982226D01*
X800481Y1982351D01*
X800814Y1982393D01*
X801231Y1982310D01*
X801523Y1982101D01*
X801606Y1981851D01*
X801564Y1981601D01*
X801398Y1981393D01*
X800564Y1980976D01*
X800189Y1980685D01*
X799939Y1980268D01*
X799856Y1979893D01*
X801606D01*
G01X802914Y1980393D02*
X803164Y1980101D01*
X803498Y1979935D01*
X803873Y1979893D01*
X804206Y1979935D01*
X804539Y1980143D01*
X804748Y1980393D01*
X804789Y1980643D01*
X804706Y1980935D01*
X804414Y1981143D01*
X804123Y1981226D01*
X803748D01*
G01X804123D02*
X804373Y1981351D01*
X804581Y1981560D01*
X804664Y1981810D01*
X804581Y1982060D01*
X804373Y1982268D01*
X803998Y1982393D01*
X803623Y1982351D01*
X803248Y1982185D01*
G01X794032Y1987050D02*
Y1985258D01*
X794199Y1984883D01*
X794532Y1984633D01*
X794949Y1984550D01*
X795366Y1984633D01*
X795699Y1984883D01*
X795866Y1985258D01*
Y1987050D01*
G01X797257Y1986633D02*
X797507Y1986883D01*
X797799Y1987008D01*
X798132Y1987050D01*
X798549Y1986967D01*
X798841Y1986758D01*
X798924Y1986508D01*
X798882Y1986258D01*
X798716Y1986050D01*
X797882Y1985633D01*
X797507Y1985342D01*
X797257Y1984925D01*
X797174Y1984550D01*
X798924D01*
G01X817999Y144567D02*
X815499D01*
Y145608D01*
X815624Y145942D01*
X815791Y146150D01*
X816124Y146233D01*
X816457Y146150D01*
X816666Y145900D01*
X816791Y145608D01*
Y144567D01*
G01Y145608D02*
X817999Y146233D01*
G01X817499Y147583D02*
X817791Y147833D01*
X817957Y148167D01*
X817999Y148542D01*
X817957Y148875D01*
X817749Y149208D01*
X817499Y149417D01*
X817249Y149458D01*
X816957Y149375D01*
X816749Y149083D01*
X816666Y148792D01*
Y148417D01*
G01Y148792D02*
X816541Y149042D01*
X816332Y149250D01*
X816082Y149333D01*
X815832Y149250D01*
X815624Y149042D01*
X815499Y148667D01*
X815541Y148292D01*
X815707Y147917D01*
G01X817499Y150683D02*
X817791Y150933D01*
X817957Y151267D01*
X817999Y151642D01*
X817957Y151975D01*
X817749Y152308D01*
X817499Y152517D01*
X817249Y152558D01*
X816957Y152475D01*
X816749Y152183D01*
X816666Y151892D01*
Y151517D01*
G01Y151892D02*
X816541Y152142D01*
X816332Y152350D01*
X816082Y152433D01*
X815832Y152350D01*
X815624Y152142D01*
X815499Y151767D01*
X815541Y151392D01*
X815707Y151017D01*
G01X817999Y154700D02*
X815499D01*
X815999Y154200D01*
G01X817999D02*
Y155200D01*
G01X814499Y157350D02*
X818499D01*
Y164750D01*
G01X821999Y157350D02*
X825999D01*
Y164750D01*
G01X811992Y172975D02*
X811867Y172725D01*
X811784Y172433D01*
Y172100D01*
X811909Y171725D01*
X812117Y171433D01*
X812367Y171225D01*
X812784Y171058D01*
X813159Y171016D01*
X813534Y171100D01*
X813784Y171225D01*
X814034Y171475D01*
X814201Y171766D01*
X814284Y172058D01*
Y172350D01*
X814201Y172641D01*
X814076Y172891D01*
X813909Y173100D01*
G01X813784Y174241D02*
X814076Y174491D01*
X814242Y174825D01*
X814284Y175200D01*
X814242Y175533D01*
X814034Y175866D01*
X813784Y176075D01*
X813534Y176116D01*
X813242Y176033D01*
X813034Y175741D01*
X812951Y175450D01*
Y175075D01*
G01Y175450D02*
X812826Y175700D01*
X812617Y175908D01*
X812367Y175991D01*
X812117Y175908D01*
X811909Y175700D01*
X811784Y175325D01*
X811826Y174950D01*
X811992Y174575D01*
G01X814284Y178758D02*
X811784D01*
X813576Y177216D01*
Y179300D01*
G01X813784Y180441D02*
X814076Y180691D01*
X814242Y181025D01*
X814284Y181400D01*
X814242Y181733D01*
X814034Y182066D01*
X813784Y182275D01*
X813534Y182316D01*
X813242Y182233D01*
X813034Y181941D01*
X812951Y181650D01*
Y181275D01*
G01Y181650D02*
X812826Y181900D01*
X812617Y182108D01*
X812367Y182191D01*
X812117Y182108D01*
X811909Y181900D01*
X811784Y181525D01*
X811826Y181150D01*
X811992Y180775D01*
G01X818699Y165050D02*
Y169050D01*
X811299D01*
G01X806284Y171225D02*
X803784D01*
Y172266D01*
X803909Y172600D01*
X804076Y172808D01*
X804409Y172891D01*
X804742Y172808D01*
X804951Y172558D01*
X805076Y172266D01*
Y171225D01*
G01Y172266D02*
X806284Y172891D01*
G01X805784Y174241D02*
X806076Y174491D01*
X806242Y174825D01*
X806284Y175200D01*
X806242Y175533D01*
X806034Y175866D01*
X805784Y176075D01*
X805534Y176116D01*
X805242Y176033D01*
X805034Y175741D01*
X804951Y175450D01*
Y175075D01*
G01Y175450D02*
X804826Y175700D01*
X804617Y175908D01*
X804367Y175991D01*
X804117Y175908D01*
X803909Y175700D01*
X803784Y175325D01*
X803826Y174950D01*
X803992Y174575D01*
G01X806284Y178758D02*
X803784D01*
X805576Y177216D01*
Y179300D01*
G01X803784Y181358D02*
X803867Y181025D01*
X804076Y180775D01*
X804326Y180608D01*
X804659Y180483D01*
X805034Y180441D01*
X805409Y180483D01*
X805742Y180608D01*
X805992Y180775D01*
X806201Y181025D01*
X806284Y181358D01*
X806201Y181691D01*
X805992Y181941D01*
X805742Y182108D01*
X805409Y182233D01*
X805034Y182275D01*
X804659Y182233D01*
X804326Y182108D01*
X804076Y181941D01*
X803867Y181691D01*
X803784Y181358D01*
G01X826199Y165050D02*
Y169050D01*
X818799D01*
G01X810284Y171225D02*
X807784D01*
Y172266D01*
X807909Y172600D01*
X808076Y172808D01*
X808409Y172891D01*
X808742Y172808D01*
X808951Y172558D01*
X809076Y172266D01*
Y171225D01*
G01Y172266D02*
X810284Y172891D01*
G01X809784Y174241D02*
X810076Y174491D01*
X810242Y174825D01*
X810284Y175200D01*
X810242Y175533D01*
X810034Y175866D01*
X809784Y176075D01*
X809534Y176116D01*
X809242Y176033D01*
X809034Y175741D01*
X808951Y175450D01*
Y175075D01*
G01Y175450D02*
X808826Y175700D01*
X808617Y175908D01*
X808367Y175991D01*
X808117Y175908D01*
X807909Y175700D01*
X807784Y175325D01*
X807826Y174950D01*
X807992Y174575D01*
G01X810284Y178758D02*
X807784D01*
X809576Y177216D01*
Y179300D01*
G01X810284Y181358D02*
X807784D01*
X808284Y180858D01*
G01X810284D02*
Y181858D01*
G01X817193Y200960D02*
X819693D01*
G01X817193Y200002D02*
Y201918D01*
G01X819693Y203227D02*
X817193D01*
Y204227D01*
X817318Y204560D01*
X817610Y204810D01*
X817943Y204893D01*
X818276Y204810D01*
X818526Y204602D01*
X818651Y204227D01*
Y203227D01*
G01X819693Y207660D02*
X817193D01*
X818985Y206118D01*
Y208202D01*
G01X816413Y185678D02*
X818205D01*
X818580Y185845D01*
X818830Y186178D01*
X818913Y186595D01*
X818830Y187012D01*
X818580Y187345D01*
X818205Y187512D01*
X816413D01*
G01X818913Y190195D02*
X816413D01*
X818205Y188653D01*
Y190737D01*
G01X818621Y192087D02*
X818830Y192378D01*
X818913Y192712D01*
X818830Y193045D01*
X818580Y193337D01*
X818205Y193545D01*
X817830Y193628D01*
X817371D01*
X816996Y193545D01*
X816663Y193337D01*
X816496Y193087D01*
X816413Y192795D01*
X816496Y192462D01*
X816663Y192212D01*
X816913Y192045D01*
X817246Y191962D01*
X817538Y192045D01*
X817830Y192253D01*
X817996Y192503D01*
X818038Y192795D01*
X817955Y193128D01*
X817746Y193378D01*
X817371Y193628D01*
G01X810000Y264400D02*
X809958Y264067D01*
X809792Y263775D01*
X809542Y263525D01*
X809250Y263358D01*
X808917Y263275D01*
X808583D01*
X808250Y263358D01*
X807958Y263525D01*
X807708Y263775D01*
X807542Y264067D01*
X807500Y264400D01*
X807542Y264733D01*
X807708Y265025D01*
X807958Y265275D01*
X808250Y265442D01*
X808583Y265525D01*
X808917D01*
X809250Y265442D01*
X809542Y265275D01*
X809792Y265025D01*
X809958Y264733D01*
X810000Y264400D01*
G01X809333Y264733D02*
X810000Y265233D01*
G01X809625Y266583D02*
X809833Y266833D01*
X809958Y267125D01*
X810000Y267500D01*
X809917Y267875D01*
X809750Y268167D01*
X809458Y268375D01*
X809125Y268417D01*
X808792Y268333D01*
X808583Y268125D01*
X808417Y267833D01*
X808375Y267542D01*
X808417Y267250D01*
X808583Y266875D01*
X807500Y267000D01*
Y268125D01*
G01X810000Y271100D02*
X807500D01*
X809292Y269558D01*
Y271642D01*
G01X811700Y273200D02*
Y261800D01*
G01D02*
X825100D01*
G01Y273200D02*
X811700D01*
G01X806017Y283000D02*
Y285500D01*
X807058D01*
X807392Y285375D01*
X807600Y285208D01*
X807683Y284875D01*
X807600Y284542D01*
X807350Y284333D01*
X807058Y284208D01*
X806017D01*
G01X807058D02*
X807683Y283000D01*
G01X809033Y283375D02*
X809283Y283167D01*
X809575Y283042D01*
X809950Y283000D01*
X810325Y283083D01*
X810617Y283250D01*
X810825Y283542D01*
X810867Y283875D01*
X810783Y284208D01*
X810575Y284417D01*
X810283Y284583D01*
X809992Y284625D01*
X809700Y284583D01*
X809325Y284417D01*
X809450Y285500D01*
X810575D01*
G01X812258Y285083D02*
X812508Y285333D01*
X812800Y285458D01*
X813133Y285500D01*
X813550Y285417D01*
X813842Y285208D01*
X813925Y284958D01*
X813883Y284708D01*
X813717Y284500D01*
X812883Y284083D01*
X812508Y283792D01*
X812258Y283375D01*
X812175Y283000D01*
X813925D01*
G01X816150Y285500D02*
X815817Y285417D01*
X815567Y285208D01*
X815400Y284958D01*
X815275Y284625D01*
X815233Y284250D01*
X815275Y283875D01*
X815400Y283542D01*
X815567Y283292D01*
X815817Y283083D01*
X816150Y283000D01*
X816483Y283083D01*
X816733Y283292D01*
X816900Y283542D01*
X817025Y283875D01*
X817067Y284250D01*
X817025Y284625D01*
X816900Y284958D01*
X816733Y285208D01*
X816483Y285417D01*
X816150Y285500D01*
G01X820100Y281500D02*
Y288500D01*
X833500D01*
Y281500D01*
X820100D01*
G01X810873Y289271D02*
X812673Y291371D01*
X814873Y289271D01*
G01X818473Y289171D02*
Y308371D01*
X807273D01*
Y289171D01*
X818473D01*
Y289571D01*
G01X816350Y314000D02*
Y311500D01*
G01X815392Y314000D02*
X817308D01*
G01X818617Y311500D02*
Y314000D01*
X819617D01*
X819950Y313875D01*
X820200Y313583D01*
X820283Y313250D01*
X820200Y312917D01*
X819992Y312667D01*
X819617Y312542D01*
X818617D01*
G01X821758Y313583D02*
X822008Y313833D01*
X822300Y313958D01*
X822633Y314000D01*
X823050Y313917D01*
X823342Y313708D01*
X823425Y313458D01*
X823383Y313208D01*
X823217Y313000D01*
X822383Y312583D01*
X822008Y312292D01*
X821758Y311875D01*
X821675Y311500D01*
X823425D01*
G01X824942Y311792D02*
X825233Y311583D01*
X825567Y311500D01*
X825900Y311583D01*
X826192Y311833D01*
X826400Y312208D01*
X826483Y312583D01*
Y313042D01*
X826400Y313417D01*
X826192Y313750D01*
X825942Y313917D01*
X825650Y314000D01*
X825317Y313917D01*
X825067Y313750D01*
X824900Y313500D01*
X824817Y313167D01*
X824900Y312875D01*
X825108Y312583D01*
X825358Y312417D01*
X825650Y312375D01*
X825983Y312458D01*
X826233Y312667D01*
X826483Y313042D01*
G01X803999Y320150D02*
Y358950D01*
G01X826999Y320150D02*
X803999D01*
G01X817267Y317792D02*
X817017Y317917D01*
X816725Y318000D01*
X816392D01*
X816017Y317875D01*
X815725Y317667D01*
X815517Y317417D01*
X815350Y317000D01*
X815308Y316625D01*
X815392Y316250D01*
X815517Y316000D01*
X815767Y315750D01*
X816058Y315583D01*
X816350Y315500D01*
X816642D01*
X816933Y315583D01*
X817183Y315708D01*
X817392Y315875D01*
G01X819450Y315500D02*
Y318000D01*
X818950Y317500D01*
G01Y315500D02*
X819950D01*
G01X822467D02*
X822550Y316042D01*
X822675Y316500D01*
X822842Y316917D01*
X823050Y317375D01*
X823383Y318000D01*
X821717D01*
G01X826150Y315500D02*
Y318000D01*
X824608Y316208D01*
X826692D01*
G01X813107Y361050D02*
Y363550D01*
X814691D01*
G01X814107Y362342D02*
X813107D01*
G01X816999Y361050D02*
Y363550D01*
X816499Y363050D01*
G01Y361050D02*
X817499D01*
G01X820099Y363550D02*
X819766Y363467D01*
X819516Y363258D01*
X819349Y363008D01*
X819224Y362675D01*
X819182Y362300D01*
X819224Y361925D01*
X819349Y361592D01*
X819516Y361342D01*
X819766Y361133D01*
X820099Y361050D01*
X820432Y361133D01*
X820682Y361342D01*
X820849Y361592D01*
X820974Y361925D01*
X821016Y362300D01*
X820974Y362675D01*
X820849Y363008D01*
X820682Y363258D01*
X820432Y363467D01*
X820099Y363550D01*
G01X803999Y358950D02*
X826999D01*
G01X810416Y375550D02*
Y380550D01*
X813582D01*
G01X812416Y378133D02*
X810416D01*
G01X817599Y375550D02*
Y380550D01*
X816599Y379550D01*
G01Y375550D02*
X818599D01*
G01X823199Y380550D02*
X822532Y380383D01*
X822032Y379967D01*
X821699Y379467D01*
X821449Y378800D01*
X821366Y378050D01*
X821449Y377300D01*
X821699Y376633D01*
X822032Y376133D01*
X822532Y375717D01*
X823199Y375550D01*
X823866Y375717D01*
X824366Y376133D01*
X824699Y376633D01*
X824949Y377300D01*
X825032Y378050D01*
X824949Y378800D01*
X824699Y379467D01*
X824366Y379967D01*
X823866Y380383D01*
X823199Y380550D01*
G01X828799Y375383D02*
X828632Y375467D01*
Y375633D01*
X828799Y375717D01*
X828966Y375633D01*
Y375467D01*
X828799Y375383D01*
G01Y377633D02*
X828632Y377717D01*
Y377883D01*
X828799Y377967D01*
X828966Y377883D01*
Y377717D01*
X828799Y377633D01*
G01X832566Y376550D02*
X833066Y375967D01*
X833732Y375633D01*
X834482Y375550D01*
X835149Y375633D01*
X835816Y376050D01*
X836232Y376550D01*
X836316Y377050D01*
X836149Y377633D01*
X835566Y378050D01*
X834982Y378217D01*
X834232D01*
G01X834982D02*
X835482Y378467D01*
X835899Y378883D01*
X836066Y379383D01*
X835899Y379883D01*
X835482Y380300D01*
X834732Y380550D01*
X833982Y380467D01*
X833232Y380133D01*
G01X837916Y375550D02*
X839999Y380550D01*
X842082Y375550D01*
G01X841332Y377300D02*
X838666D01*
G01X844099Y375383D02*
X847099Y380550D01*
G01X851199Y375550D02*
Y380550D01*
X850199Y379550D01*
G01Y375550D02*
X852199D01*
G01X854966Y376300D02*
X855466Y375883D01*
X856049Y375633D01*
X856799Y375550D01*
X857549Y375717D01*
X858132Y376050D01*
X858549Y376633D01*
X858632Y377300D01*
X858466Y377967D01*
X858049Y378383D01*
X857466Y378717D01*
X856882Y378800D01*
X856299Y378717D01*
X855549Y378383D01*
X855799Y380550D01*
X858049D01*
G01X860316D02*
X862399Y375550D01*
X864482Y380550D01*
G01X819500Y651400D02*
X819458Y651067D01*
X819292Y650775D01*
X819042Y650525D01*
X818750Y650358D01*
X818417Y650275D01*
X818083D01*
X817750Y650358D01*
X817458Y650525D01*
X817208Y650775D01*
X817042Y651067D01*
X817000Y651400D01*
X817042Y651733D01*
X817208Y652025D01*
X817458Y652275D01*
X817750Y652442D01*
X818083Y652525D01*
X818417D01*
X818750Y652442D01*
X819042Y652275D01*
X819292Y652025D01*
X819458Y651733D01*
X819500Y651400D01*
G01X818833Y651733D02*
X819500Y652233D01*
G01X819125Y653583D02*
X819333Y653833D01*
X819458Y654125D01*
X819500Y654500D01*
X819417Y654875D01*
X819250Y655167D01*
X818958Y655375D01*
X818625Y655417D01*
X818292Y655333D01*
X818083Y655125D01*
X817917Y654833D01*
X817875Y654542D01*
X817917Y654250D01*
X818083Y653875D01*
X817000Y654000D01*
Y655125D01*
G01X817417Y656808D02*
X817167Y657058D01*
X817042Y657350D01*
X817000Y657683D01*
X817083Y658100D01*
X817292Y658392D01*
X817542Y658475D01*
X817792Y658433D01*
X818000Y658267D01*
X818417Y657433D01*
X818708Y657058D01*
X819125Y656808D01*
X819500Y656725D01*
Y658475D01*
G01X810200Y675800D02*
Y664400D01*
G01D02*
X823600D01*
G01X823500Y650567D02*
X821000D01*
Y651608D01*
X821125Y651942D01*
X821292Y652150D01*
X821625Y652233D01*
X821958Y652150D01*
X822167Y651900D01*
X822292Y651608D01*
Y650567D01*
G01Y651608D02*
X823500Y652233D01*
G01X823000Y653583D02*
X823292Y653833D01*
X823458Y654167D01*
X823500Y654542D01*
X823458Y654875D01*
X823250Y655208D01*
X823000Y655417D01*
X822750Y655458D01*
X822458Y655375D01*
X822250Y655083D01*
X822167Y654792D01*
Y654417D01*
G01Y654792D02*
X822042Y655042D01*
X821833Y655250D01*
X821583Y655333D01*
X821333Y655250D01*
X821125Y655042D01*
X821000Y654667D01*
X821042Y654292D01*
X821208Y653917D01*
G01X822458Y656808D02*
X822167Y657100D01*
X822000Y657350D01*
X821917Y657683D01*
X822000Y657975D01*
X822167Y658183D01*
X822417Y658350D01*
X822708Y658392D01*
X822958Y658350D01*
X823208Y658183D01*
X823417Y657933D01*
X823500Y657642D01*
X823417Y657308D01*
X823167Y657017D01*
X822792Y656850D01*
X822375Y656808D01*
X821833Y656892D01*
X821542Y657017D01*
X821250Y657225D01*
X821042Y657517D01*
X821000Y657808D01*
X821083Y658100D01*
X821292Y658308D01*
G01X822458Y659908D02*
X822167Y660200D01*
X822000Y660450D01*
X821917Y660783D01*
X822000Y661075D01*
X822167Y661283D01*
X822417Y661450D01*
X822708Y661492D01*
X822958Y661450D01*
X823208Y661283D01*
X823417Y661033D01*
X823500Y660742D01*
X823417Y660408D01*
X823167Y660117D01*
X822792Y659950D01*
X822375Y659908D01*
X821833Y659992D01*
X821542Y660117D01*
X821250Y660325D01*
X821042Y660617D01*
X821000Y660908D01*
X821083Y661200D01*
X821292Y661408D01*
G01X823600Y675800D02*
X810200D01*
G01X811517Y680000D02*
Y682500D01*
X812558D01*
X812892Y682375D01*
X813100Y682208D01*
X813183Y681875D01*
X813100Y681542D01*
X812850Y681333D01*
X812558Y681208D01*
X811517D01*
G01X812558D02*
X813183Y680000D01*
G01X814533Y680375D02*
X814783Y680167D01*
X815075Y680042D01*
X815450Y680000D01*
X815825Y680083D01*
X816117Y680250D01*
X816325Y680542D01*
X816367Y680875D01*
X816283Y681208D01*
X816075Y681417D01*
X815783Y681583D01*
X815492Y681625D01*
X815200Y681583D01*
X814825Y681417D01*
X814950Y682500D01*
X816075D01*
G01X818550Y680000D02*
Y682500D01*
X818050Y682000D01*
G01Y680000D02*
X819050D01*
G01X821650D02*
X821942Y680042D01*
X822275Y680167D01*
X822483Y680375D01*
X822567Y680667D01*
X822483Y680958D01*
X822233Y681208D01*
X821858Y681333D01*
X821442D01*
X821192Y681417D01*
X820983Y681625D01*
X820900Y681917D01*
X821025Y682208D01*
X821317Y682417D01*
X821650Y682500D01*
X821983Y682417D01*
X822275Y682208D01*
X822400Y681917D01*
X822317Y681625D01*
X822108Y681417D01*
X821858Y681333D01*
X821442D01*
X821067Y681208D01*
X820817Y680958D01*
X820733Y680667D01*
X820817Y680375D01*
X821025Y680167D01*
X821358Y680042D01*
X821650Y680000D01*
G01X818300Y684700D02*
Y691700D01*
X831700D01*
Y684700D01*
X818300D01*
G01X808831Y693653D02*
X810631Y695753D01*
X812831Y693653D01*
G01X816431Y693553D02*
Y712753D01*
X805231D01*
Y693553D01*
X816431D01*
Y693953D01*
G01X801999Y723150D02*
Y761950D01*
G01X824999Y723150D02*
X801999D01*
G01X814767Y718792D02*
X814517Y718917D01*
X814225Y719000D01*
X813892D01*
X813517Y718875D01*
X813225Y718667D01*
X813017Y718417D01*
X812850Y718000D01*
X812808Y717625D01*
X812892Y717250D01*
X813017Y717000D01*
X813267Y716750D01*
X813558Y716583D01*
X813850Y716500D01*
X814142D01*
X814433Y716583D01*
X814683Y716708D01*
X814892Y716875D01*
G01X816950Y716500D02*
Y719000D01*
X816450Y718500D01*
G01Y716500D02*
X817450D01*
G01X819133Y716875D02*
X819383Y716667D01*
X819675Y716542D01*
X820050Y716500D01*
X820425Y716583D01*
X820717Y716750D01*
X820925Y717042D01*
X820967Y717375D01*
X820883Y717708D01*
X820675Y717917D01*
X820383Y718083D01*
X820092Y718125D01*
X819800Y718083D01*
X819425Y717917D01*
X819550Y719000D01*
X820675D01*
G01X822442Y716792D02*
X822733Y716583D01*
X823067Y716500D01*
X823400Y716583D01*
X823692Y716833D01*
X823900Y717208D01*
X823983Y717583D01*
Y718042D01*
X823900Y718417D01*
X823692Y718750D01*
X823442Y718917D01*
X823150Y719000D01*
X822817Y718917D01*
X822567Y718750D01*
X822400Y718500D01*
X822317Y718167D01*
X822400Y717875D01*
X822608Y717583D01*
X822858Y717417D01*
X823150Y717375D01*
X823483Y717458D01*
X823733Y717667D01*
X823983Y718042D01*
G01X809657Y767050D02*
Y769550D01*
X811241D01*
G01X810657Y768342D02*
X809657D01*
G01X813549Y767050D02*
X813841Y767092D01*
X814174Y767217D01*
X814382Y767425D01*
X814466Y767717D01*
X814382Y768008D01*
X814132Y768258D01*
X813757Y768383D01*
X813341D01*
X813091Y768467D01*
X812882Y768675D01*
X812799Y768967D01*
X812924Y769258D01*
X813216Y769467D01*
X813549Y769550D01*
X813882Y769467D01*
X814174Y769258D01*
X814299Y768967D01*
X814216Y768675D01*
X814007Y768467D01*
X813757Y768383D01*
X813341D01*
X812966Y768258D01*
X812716Y768008D01*
X812632Y767717D01*
X812716Y767425D01*
X812924Y767217D01*
X813257Y767092D01*
X813549Y767050D01*
G01X801999Y761950D02*
X824999D01*
G01X807916Y778550D02*
Y783550D01*
X811082D01*
G01X809916Y781133D02*
X807916D01*
G01X815099Y778550D02*
X815682Y778633D01*
X816349Y778883D01*
X816766Y779300D01*
X816932Y779883D01*
X816766Y780467D01*
X816266Y780967D01*
X815516Y781217D01*
X814682D01*
X814182Y781383D01*
X813766Y781800D01*
X813599Y782383D01*
X813849Y782967D01*
X814432Y783383D01*
X815099Y783550D01*
X815766Y783383D01*
X816349Y782967D01*
X816599Y782383D01*
X816432Y781800D01*
X816016Y781383D01*
X815516Y781217D01*
X814682D01*
X813932Y780967D01*
X813432Y780467D01*
X813266Y779883D01*
X813432Y779300D01*
X813849Y778883D01*
X814516Y778633D01*
X815099Y778550D01*
G01X820699Y778383D02*
X820532Y778467D01*
Y778633D01*
X820699Y778717D01*
X820866Y778633D01*
Y778467D01*
X820699Y778383D01*
G01Y780633D02*
X820532Y780717D01*
Y780883D01*
X820699Y780967D01*
X820866Y780883D01*
Y780717D01*
X820699Y780633D01*
G01X824466Y779550D02*
X824966Y778967D01*
X825632Y778633D01*
X826382Y778550D01*
X827049Y778633D01*
X827716Y779050D01*
X828132Y779550D01*
X828216Y780050D01*
X828049Y780633D01*
X827466Y781050D01*
X826882Y781217D01*
X826132D01*
G01X826882D02*
X827382Y781467D01*
X827799Y781883D01*
X827966Y782383D01*
X827799Y782883D01*
X827382Y783300D01*
X826632Y783550D01*
X825882Y783467D01*
X825132Y783133D01*
G01X829816Y778550D02*
X831899Y783550D01*
X833982Y778550D01*
G01X833232Y780300D02*
X830566D01*
G01X835999Y778383D02*
X838999Y783550D01*
G01X843099Y778550D02*
Y783550D01*
X842099Y782550D01*
G01Y778550D02*
X844099D01*
G01X846866Y779300D02*
X847366Y778883D01*
X847949Y778633D01*
X848699Y778550D01*
X849449Y778717D01*
X850032Y779050D01*
X850449Y779633D01*
X850532Y780300D01*
X850366Y780967D01*
X849949Y781383D01*
X849366Y781717D01*
X848782Y781800D01*
X848199Y781717D01*
X847449Y781383D01*
X847699Y783550D01*
X849949D01*
G01X852216D02*
X854299Y778550D01*
X856382Y783550D01*
G01X807500Y1064400D02*
X807458Y1064067D01*
X807292Y1063775D01*
X807042Y1063525D01*
X806750Y1063358D01*
X806417Y1063275D01*
X806083D01*
X805750Y1063358D01*
X805458Y1063525D01*
X805208Y1063775D01*
X805042Y1064067D01*
X805000Y1064400D01*
X805042Y1064733D01*
X805208Y1065025D01*
X805458Y1065275D01*
X805750Y1065442D01*
X806083Y1065525D01*
X806417D01*
X806750Y1065442D01*
X807042Y1065275D01*
X807292Y1065025D01*
X807458Y1064733D01*
X807500Y1064400D01*
G01X806833Y1064733D02*
X807500Y1065233D01*
G01X807000Y1066583D02*
X807292Y1066833D01*
X807458Y1067167D01*
X807500Y1067542D01*
X807458Y1067875D01*
X807250Y1068208D01*
X807000Y1068417D01*
X806750Y1068458D01*
X806458Y1068375D01*
X806250Y1068083D01*
X806167Y1067792D01*
Y1067417D01*
G01Y1067792D02*
X806042Y1068042D01*
X805833Y1068250D01*
X805583Y1068333D01*
X805333Y1068250D01*
X805125Y1068042D01*
X805000Y1067667D01*
X805042Y1067292D01*
X805208Y1066917D01*
G01X807000Y1069683D02*
X807292Y1069933D01*
X807458Y1070267D01*
X807500Y1070642D01*
X807458Y1070975D01*
X807250Y1071308D01*
X807000Y1071517D01*
X806750Y1071558D01*
X806458Y1071475D01*
X806250Y1071183D01*
X806167Y1070892D01*
Y1070517D01*
G01Y1070892D02*
X806042Y1071142D01*
X805833Y1071350D01*
X805583Y1071433D01*
X805333Y1071350D01*
X805125Y1071142D01*
X805000Y1070767D01*
X805042Y1070392D01*
X805208Y1070017D01*
G01X809900Y1078600D02*
Y1067200D01*
G01D02*
X823300D01*
G01Y1078600D02*
X809900D01*
G01X814017Y1086000D02*
Y1088500D01*
X815058D01*
X815392Y1088375D01*
X815600Y1088208D01*
X815683Y1087875D01*
X815600Y1087542D01*
X815350Y1087333D01*
X815058Y1087208D01*
X814017D01*
G01X815058D02*
X815683Y1086000D01*
G01X817033Y1086375D02*
X817283Y1086167D01*
X817575Y1086042D01*
X817950Y1086000D01*
X818325Y1086083D01*
X818617Y1086250D01*
X818825Y1086542D01*
X818867Y1086875D01*
X818783Y1087208D01*
X818575Y1087417D01*
X818283Y1087583D01*
X817992Y1087625D01*
X817700Y1087583D01*
X817325Y1087417D01*
X817450Y1088500D01*
X818575D01*
G01X821050Y1086000D02*
Y1088500D01*
X820550Y1088000D01*
G01Y1086000D02*
X821550D01*
G01X823358Y1087042D02*
X823650Y1087333D01*
X823900Y1087500D01*
X824233Y1087583D01*
X824525Y1087500D01*
X824733Y1087333D01*
X824900Y1087083D01*
X824942Y1086792D01*
X824900Y1086542D01*
X824733Y1086292D01*
X824483Y1086083D01*
X824192Y1086000D01*
X823858Y1086083D01*
X823567Y1086333D01*
X823400Y1086708D01*
X823358Y1087125D01*
X823442Y1087667D01*
X823567Y1087958D01*
X823775Y1088250D01*
X824067Y1088458D01*
X824358Y1088500D01*
X824650Y1088417D01*
X824858Y1088208D01*
G01X808841Y1098016D02*
X810641Y1100116D01*
X812841Y1098016D01*
G01X816441Y1097916D02*
Y1117116D01*
X805241D01*
Y1097916D01*
X816441D01*
Y1098316D01*
G01X818500Y1090200D02*
Y1097200D01*
X831900D01*
Y1090200D01*
X818500D01*
G01X801999Y1125650D02*
Y1164450D01*
G01X824999Y1125650D02*
X801999D01*
G01X813267Y1123292D02*
X813017Y1123417D01*
X812725Y1123500D01*
X812392D01*
X812017Y1123375D01*
X811725Y1123167D01*
X811517Y1122917D01*
X811350Y1122500D01*
X811308Y1122125D01*
X811392Y1121750D01*
X811517Y1121500D01*
X811767Y1121250D01*
X812058Y1121083D01*
X812350Y1121000D01*
X812642D01*
X812933Y1121083D01*
X813183Y1121208D01*
X813392Y1121375D01*
G01X815450Y1121000D02*
Y1123500D01*
X814950Y1123000D01*
G01Y1121000D02*
X815950D01*
G01X819050D02*
Y1123500D01*
X817508Y1121708D01*
X819592D01*
G01X820858Y1123083D02*
X821108Y1123333D01*
X821400Y1123458D01*
X821733Y1123500D01*
X822150Y1123417D01*
X822442Y1123208D01*
X822525Y1122958D01*
X822483Y1122708D01*
X822317Y1122500D01*
X821483Y1122083D01*
X821108Y1121792D01*
X820858Y1121375D01*
X820775Y1121000D01*
X822525D01*
G01X811157Y1168050D02*
Y1170550D01*
X812741D01*
G01X812157Y1169342D02*
X811157D01*
G01X814257Y1169092D02*
X814549Y1169383D01*
X814799Y1169550D01*
X815132Y1169633D01*
X815424Y1169550D01*
X815632Y1169383D01*
X815799Y1169133D01*
X815841Y1168842D01*
X815799Y1168592D01*
X815632Y1168342D01*
X815382Y1168133D01*
X815091Y1168050D01*
X814757Y1168133D01*
X814466Y1168383D01*
X814299Y1168758D01*
X814257Y1169175D01*
X814341Y1169717D01*
X814466Y1170008D01*
X814674Y1170300D01*
X814966Y1170508D01*
X815257Y1170550D01*
X815549Y1170467D01*
X815757Y1170258D01*
G01X801999Y1164450D02*
X824999D01*
G01X803416Y1182550D02*
Y1187550D01*
X806582D01*
G01X805416Y1185133D02*
X803416D01*
G01X809016Y1184633D02*
X809599Y1185217D01*
X810099Y1185550D01*
X810766Y1185717D01*
X811349Y1185550D01*
X811766Y1185217D01*
X812099Y1184717D01*
X812182Y1184133D01*
X812099Y1183633D01*
X811766Y1183133D01*
X811266Y1182717D01*
X810682Y1182550D01*
X810016Y1182717D01*
X809432Y1183217D01*
X809099Y1183967D01*
X809016Y1184800D01*
X809182Y1185883D01*
X809432Y1186467D01*
X809849Y1187050D01*
X810432Y1187467D01*
X811016Y1187550D01*
X811599Y1187383D01*
X812016Y1186967D01*
G01X816199Y1182383D02*
X816032Y1182467D01*
Y1182633D01*
X816199Y1182717D01*
X816366Y1182633D01*
Y1182467D01*
X816199Y1182383D01*
G01Y1184633D02*
X816032Y1184717D01*
Y1184883D01*
X816199Y1184967D01*
X816366Y1184883D01*
Y1184717D01*
X816199Y1184633D01*
G01X819966Y1183550D02*
X820466Y1182967D01*
X821132Y1182633D01*
X821882Y1182550D01*
X822549Y1182633D01*
X823216Y1183050D01*
X823632Y1183550D01*
X823716Y1184050D01*
X823549Y1184633D01*
X822966Y1185050D01*
X822382Y1185217D01*
X821632D01*
G01X822382D02*
X822882Y1185467D01*
X823299Y1185883D01*
X823466Y1186383D01*
X823299Y1186883D01*
X822882Y1187300D01*
X822132Y1187550D01*
X821382Y1187467D01*
X820632Y1187133D01*
G01X825316Y1182550D02*
X827399Y1187550D01*
X829482Y1182550D01*
G01X828732Y1184300D02*
X826066D01*
G01X831499Y1182383D02*
X834499Y1187550D01*
G01X838599Y1182550D02*
Y1187550D01*
X837599Y1186550D01*
G01Y1182550D02*
X839599D01*
G01X842366Y1183300D02*
X842866Y1182883D01*
X843449Y1182633D01*
X844199Y1182550D01*
X844949Y1182717D01*
X845532Y1183050D01*
X845949Y1183633D01*
X846032Y1184300D01*
X845866Y1184967D01*
X845449Y1185383D01*
X844866Y1185717D01*
X844282Y1185800D01*
X843699Y1185717D01*
X842949Y1185383D01*
X843199Y1187550D01*
X845449D01*
G01X847716D02*
X849799Y1182550D01*
X851882Y1187550D01*
G01X811700Y1486300D02*
Y1474900D01*
G01X825100Y1486300D02*
X811700D01*
G01Y1474900D02*
X825100D01*
G01X807017Y1489000D02*
Y1491500D01*
X808058D01*
X808392Y1491375D01*
X808600Y1491208D01*
X808683Y1490875D01*
X808600Y1490542D01*
X808350Y1490333D01*
X808058Y1490208D01*
X807017D01*
G01X808058D02*
X808683Y1489000D01*
G01X810033Y1489375D02*
X810283Y1489167D01*
X810575Y1489042D01*
X810950Y1489000D01*
X811325Y1489083D01*
X811617Y1489250D01*
X811825Y1489542D01*
X811867Y1489875D01*
X811783Y1490208D01*
X811575Y1490417D01*
X811283Y1490583D01*
X810992Y1490625D01*
X810700Y1490583D01*
X810325Y1490417D01*
X810450Y1491500D01*
X811575D01*
G01X814050Y1489000D02*
Y1491500D01*
X813550Y1491000D01*
G01Y1489000D02*
X814550D01*
G01X816233Y1489375D02*
X816483Y1489167D01*
X816775Y1489042D01*
X817150Y1489000D01*
X817525Y1489083D01*
X817817Y1489250D01*
X818025Y1489542D01*
X818067Y1489875D01*
X817983Y1490208D01*
X817775Y1490417D01*
X817483Y1490583D01*
X817192Y1490625D01*
X816900Y1490583D01*
X816525Y1490417D01*
X816650Y1491500D01*
X817775D01*
G01X810245Y1500522D02*
X812045Y1502622D01*
X814245Y1500522D01*
G01X817845Y1500422D02*
Y1519622D01*
X806645D01*
Y1500422D01*
X817845D01*
Y1500822D01*
G01X820300Y1492700D02*
Y1499700D01*
X833700D01*
Y1492700D01*
X820300D01*
G01X804671Y1530904D02*
Y1569704D01*
G01X827671Y1530904D02*
X804671D01*
G01X818267Y1528292D02*
X818017Y1528417D01*
X817725Y1528500D01*
X817392D01*
X817017Y1528375D01*
X816725Y1528167D01*
X816517Y1527917D01*
X816350Y1527500D01*
X816308Y1527125D01*
X816392Y1526750D01*
X816517Y1526500D01*
X816767Y1526250D01*
X817058Y1526083D01*
X817350Y1526000D01*
X817642D01*
X817933Y1526083D01*
X818183Y1526208D01*
X818392Y1526375D01*
G01X820450Y1526000D02*
Y1528500D01*
X819950Y1528000D01*
G01Y1526000D02*
X820950D01*
G01X822758Y1528083D02*
X823008Y1528333D01*
X823300Y1528458D01*
X823633Y1528500D01*
X824050Y1528417D01*
X824342Y1528208D01*
X824425Y1527958D01*
X824383Y1527708D01*
X824217Y1527500D01*
X823383Y1527083D01*
X823008Y1526792D01*
X822758Y1526375D01*
X822675Y1526000D01*
X824425D01*
G01X825858Y1527042D02*
X826150Y1527333D01*
X826400Y1527500D01*
X826733Y1527583D01*
X827025Y1527500D01*
X827233Y1527333D01*
X827400Y1527083D01*
X827442Y1526792D01*
X827400Y1526542D01*
X827233Y1526292D01*
X826983Y1526083D01*
X826692Y1526000D01*
X826358Y1526083D01*
X826067Y1526333D01*
X825900Y1526708D01*
X825858Y1527125D01*
X825942Y1527667D01*
X826067Y1527958D01*
X826275Y1528250D01*
X826567Y1528458D01*
X826858Y1528500D01*
X827150Y1528417D01*
X827358Y1528208D01*
G01X815157Y1572050D02*
Y1574550D01*
X816741D01*
G01X816157Y1573342D02*
X815157D01*
G01X819549Y1572050D02*
Y1574550D01*
X818007Y1572758D01*
X820091D01*
G01X804671Y1569704D02*
X827671D01*
G01X809916Y1587550D02*
Y1592550D01*
X813082D01*
G01X811916Y1590133D02*
X809916D01*
G01X818099Y1587550D02*
Y1592550D01*
X815016Y1588967D01*
X819182D01*
G01X822699Y1587383D02*
X822532Y1587467D01*
Y1587633D01*
X822699Y1587717D01*
X822866Y1587633D01*
Y1587467D01*
X822699Y1587383D01*
G01Y1589633D02*
X822532Y1589717D01*
Y1589883D01*
X822699Y1589967D01*
X822866Y1589883D01*
Y1589717D01*
X822699Y1589633D01*
G01X826466Y1588550D02*
X826966Y1587967D01*
X827632Y1587633D01*
X828382Y1587550D01*
X829049Y1587633D01*
X829716Y1588050D01*
X830132Y1588550D01*
X830216Y1589050D01*
X830049Y1589633D01*
X829466Y1590050D01*
X828882Y1590217D01*
X828132D01*
G01X828882D02*
X829382Y1590467D01*
X829799Y1590883D01*
X829966Y1591383D01*
X829799Y1591883D01*
X829382Y1592300D01*
X828632Y1592550D01*
X827882Y1592467D01*
X827132Y1592133D01*
G01X831816Y1587550D02*
X833899Y1592550D01*
X835982Y1587550D01*
G01X835232Y1589300D02*
X832566D01*
G01X837999Y1587383D02*
X840999Y1592550D01*
G01X845099Y1587550D02*
Y1592550D01*
X844099Y1591550D01*
G01Y1587550D02*
X846099D01*
G01X848866Y1588300D02*
X849366Y1587883D01*
X849949Y1587633D01*
X850699Y1587550D01*
X851449Y1587717D01*
X852032Y1588050D01*
X852449Y1588633D01*
X852532Y1589300D01*
X852366Y1589967D01*
X851949Y1590383D01*
X851366Y1590717D01*
X850782Y1590800D01*
X850199Y1590717D01*
X849449Y1590383D01*
X849699Y1592550D01*
X851949D01*
G01X854216D02*
X856299Y1587550D01*
X858382Y1592550D01*
G01X822000Y1722200D02*
Y1730200D01*
G01X827500Y1722200D02*
X822000D01*
G01Y1730200D02*
X827500D01*
G01X812017Y1732000D02*
Y1734500D01*
X813017D01*
X813350Y1734375D01*
X813600Y1734083D01*
X813683Y1733750D01*
X813600Y1733417D01*
X813392Y1733167D01*
X813017Y1733042D01*
X812017D01*
G01X815117Y1732000D02*
Y1734500D01*
X816158D01*
X816492Y1734375D01*
X816700Y1734208D01*
X816783Y1733875D01*
X816700Y1733542D01*
X816450Y1733333D01*
X816158Y1733208D01*
X815117D01*
G01X816158D02*
X816783Y1732000D01*
G01X818133Y1732375D02*
X818383Y1732167D01*
X818675Y1732042D01*
X819050Y1732000D01*
X819425Y1732083D01*
X819717Y1732250D01*
X819925Y1732542D01*
X819967Y1732875D01*
X819883Y1733208D01*
X819675Y1733417D01*
X819383Y1733583D01*
X819092Y1733625D01*
X818800Y1733583D01*
X818425Y1733417D01*
X818550Y1734500D01*
X819675D01*
G01X822067Y1732000D02*
X822150Y1732542D01*
X822275Y1733000D01*
X822442Y1733417D01*
X822650Y1733875D01*
X822983Y1734500D01*
X821317D01*
G01X815999Y1765067D02*
X813499D01*
Y1766108D01*
X813624Y1766442D01*
X813791Y1766650D01*
X814124Y1766733D01*
X814457Y1766650D01*
X814666Y1766400D01*
X814791Y1766108D01*
Y1765067D01*
G01Y1766108D02*
X815999Y1766733D01*
G01X815499Y1768083D02*
X815791Y1768333D01*
X815957Y1768667D01*
X815999Y1769042D01*
X815957Y1769375D01*
X815749Y1769708D01*
X815499Y1769917D01*
X815249Y1769958D01*
X814957Y1769875D01*
X814749Y1769583D01*
X814666Y1769292D01*
Y1768917D01*
G01Y1769292D02*
X814541Y1769542D01*
X814332Y1769750D01*
X814082Y1769833D01*
X813832Y1769750D01*
X813624Y1769542D01*
X813499Y1769167D01*
X813541Y1768792D01*
X813707Y1768417D01*
G01X813916Y1771308D02*
X813666Y1771558D01*
X813541Y1771850D01*
X813499Y1772183D01*
X813582Y1772600D01*
X813791Y1772892D01*
X814041Y1772975D01*
X814291Y1772933D01*
X814499Y1772767D01*
X814916Y1771933D01*
X815207Y1771558D01*
X815624Y1771308D01*
X815999Y1771225D01*
Y1772975D01*
G01Y1775200D02*
X815957Y1775492D01*
X815832Y1775825D01*
X815624Y1776033D01*
X815332Y1776117D01*
X815041Y1776033D01*
X814791Y1775783D01*
X814666Y1775408D01*
Y1774992D01*
X814582Y1774742D01*
X814374Y1774533D01*
X814082Y1774450D01*
X813791Y1774575D01*
X813582Y1774867D01*
X813499Y1775200D01*
X813582Y1775533D01*
X813791Y1775825D01*
X814082Y1775950D01*
X814374Y1775867D01*
X814582Y1775658D01*
X814666Y1775408D01*
Y1774992D01*
X814791Y1774617D01*
X815041Y1774367D01*
X815332Y1774283D01*
X815624Y1774367D01*
X815832Y1774575D01*
X815957Y1774908D01*
X815999Y1775200D01*
G01X812999Y1778350D02*
X816999D01*
Y1785750D01*
G01X822499Y1778350D02*
X826499D01*
Y1785750D01*
G01X819199Y1786050D02*
Y1790050D01*
X811799D01*
G01X803016Y1791550D02*
Y1794050D01*
X804057D01*
X804391Y1793925D01*
X804599Y1793758D01*
X804682Y1793425D01*
X804599Y1793092D01*
X804349Y1792883D01*
X804057Y1792758D01*
X803016D01*
G01X804057D02*
X804682Y1791550D01*
G01X806032Y1792050D02*
X806282Y1791758D01*
X806616Y1791592D01*
X806991Y1791550D01*
X807324Y1791592D01*
X807657Y1791800D01*
X807866Y1792050D01*
X807907Y1792300D01*
X807824Y1792592D01*
X807532Y1792800D01*
X807241Y1792883D01*
X806866D01*
G01X807241D02*
X807491Y1793008D01*
X807699Y1793217D01*
X807782Y1793467D01*
X807699Y1793717D01*
X807491Y1793925D01*
X807116Y1794050D01*
X806741Y1794008D01*
X806366Y1793842D01*
G01X809132Y1792050D02*
X809382Y1791758D01*
X809716Y1791592D01*
X810091Y1791550D01*
X810424Y1791592D01*
X810757Y1791800D01*
X810966Y1792050D01*
X811007Y1792300D01*
X810924Y1792592D01*
X810632Y1792800D01*
X810341Y1792883D01*
X809966D01*
G01X810341D02*
X810591Y1793008D01*
X810799Y1793217D01*
X810882Y1793467D01*
X810799Y1793717D01*
X810591Y1793925D01*
X810216Y1794050D01*
X809841Y1794008D01*
X809466Y1793842D01*
G01X813066Y1791550D02*
X813149Y1792092D01*
X813274Y1792550D01*
X813441Y1792967D01*
X813649Y1793425D01*
X813982Y1794050D01*
X812316D01*
G01X826699Y1786050D02*
Y1790050D01*
X819299D01*
G01X806099Y1807550D02*
X808599D01*
G01X806099Y1806592D02*
Y1808508D01*
G01X808599Y1809817D02*
X806099D01*
Y1810817D01*
X806224Y1811150D01*
X806516Y1811400D01*
X806849Y1811483D01*
X807182Y1811400D01*
X807432Y1811192D01*
X807557Y1810817D01*
Y1809817D01*
G01X808099Y1812833D02*
X808391Y1813083D01*
X808557Y1813417D01*
X808599Y1813792D01*
X808557Y1814125D01*
X808349Y1814458D01*
X808099Y1814667D01*
X807849Y1814708D01*
X807557Y1814625D01*
X807349Y1814333D01*
X807266Y1814042D01*
Y1813667D01*
G01Y1814042D02*
X807141Y1814292D01*
X806932Y1814500D01*
X806682Y1814583D01*
X806432Y1814500D01*
X806224Y1814292D01*
X806099Y1813917D01*
X806141Y1813542D01*
X806307Y1813167D01*
G01X811799Y1827550D02*
Y1823550D01*
X819199D01*
G01X811799D02*
Y1819550D01*
X819199D01*
G01X803900Y1879500D02*
X803567Y1879542D01*
X803275Y1879708D01*
X803025Y1879958D01*
X802858Y1880250D01*
X802775Y1880583D01*
Y1880917D01*
X802858Y1881250D01*
X803025Y1881542D01*
X803275Y1881792D01*
X803567Y1881958D01*
X803900Y1882000D01*
X804233Y1881958D01*
X804525Y1881792D01*
X804775Y1881542D01*
X804942Y1881250D01*
X805025Y1880917D01*
Y1880583D01*
X804942Y1880250D01*
X804775Y1879958D01*
X804525Y1879708D01*
X804233Y1879542D01*
X803900Y1879500D01*
G01X804233Y1880167D02*
X804733Y1879500D01*
G01X806083Y1880000D02*
X806333Y1879708D01*
X806667Y1879542D01*
X807042Y1879500D01*
X807375Y1879542D01*
X807708Y1879750D01*
X807917Y1880000D01*
X807958Y1880250D01*
X807875Y1880542D01*
X807583Y1880750D01*
X807292Y1880833D01*
X806917D01*
G01X807292D02*
X807542Y1880958D01*
X807750Y1881167D01*
X807833Y1881417D01*
X807750Y1881667D01*
X807542Y1881875D01*
X807167Y1882000D01*
X806792Y1881958D01*
X806417Y1881792D01*
G01X810100Y1879500D02*
Y1882000D01*
X809600Y1881500D01*
G01Y1879500D02*
X810600D01*
G01X812300Y1890700D02*
Y1879300D01*
G01X825700Y1890700D02*
X812300D01*
G01Y1879300D02*
X825700D01*
G01X809436Y1907165D02*
X811236Y1909265D01*
X813436Y1907165D01*
G01X817036Y1907065D02*
Y1926265D01*
X805836D01*
Y1907065D01*
X817036D01*
Y1907465D01*
G01X813517Y1894000D02*
Y1896500D01*
X814558D01*
X814892Y1896375D01*
X815100Y1896208D01*
X815183Y1895875D01*
X815100Y1895542D01*
X814850Y1895333D01*
X814558Y1895208D01*
X813517D01*
G01X814558D02*
X815183Y1894000D01*
G01X816533Y1894375D02*
X816783Y1894167D01*
X817075Y1894042D01*
X817450Y1894000D01*
X817825Y1894083D01*
X818117Y1894250D01*
X818325Y1894542D01*
X818367Y1894875D01*
X818283Y1895208D01*
X818075Y1895417D01*
X817783Y1895583D01*
X817492Y1895625D01*
X817200Y1895583D01*
X816825Y1895417D01*
X816950Y1896500D01*
X818075D01*
G01X820550Y1894000D02*
Y1896500D01*
X820050Y1896000D01*
G01Y1894000D02*
X821050D01*
G01X824150D02*
Y1896500D01*
X822608Y1894708D01*
X824692D01*
G01X820500Y1899400D02*
Y1906400D01*
X833900D01*
Y1899400D01*
X820500D01*
G01X803499Y1934650D02*
Y1973450D01*
G01X826499Y1934650D02*
X803499D01*
G01X816767Y1931792D02*
X816517Y1931917D01*
X816225Y1932000D01*
X815892D01*
X815517Y1931875D01*
X815225Y1931667D01*
X815017Y1931417D01*
X814850Y1931000D01*
X814808Y1930625D01*
X814892Y1930250D01*
X815017Y1930000D01*
X815267Y1929750D01*
X815558Y1929583D01*
X815850Y1929500D01*
X816142D01*
X816433Y1929583D01*
X816683Y1929708D01*
X816892Y1929875D01*
G01X818950Y1929500D02*
Y1932000D01*
X818450Y1931500D01*
G01Y1929500D02*
X819450D01*
G01X822050D02*
Y1932000D01*
X821550Y1931500D01*
G01Y1929500D02*
X822550D01*
G01X824358Y1931583D02*
X824608Y1931833D01*
X824900Y1931958D01*
X825233Y1932000D01*
X825650Y1931917D01*
X825942Y1931708D01*
X826025Y1931458D01*
X825983Y1931208D01*
X825817Y1931000D01*
X824983Y1930583D01*
X824608Y1930292D01*
X824358Y1929875D01*
X824275Y1929500D01*
X826025D01*
G01X812157Y1976550D02*
Y1979050D01*
X813741D01*
G01X813157Y1977842D02*
X812157D01*
G01X815257Y1978633D02*
X815507Y1978883D01*
X815799Y1979008D01*
X816132Y1979050D01*
X816549Y1978967D01*
X816841Y1978758D01*
X816924Y1978508D01*
X816882Y1978258D01*
X816716Y1978050D01*
X815882Y1977633D01*
X815507Y1977342D01*
X815257Y1976925D01*
X815174Y1976550D01*
X816924D01*
G01X803499Y1973450D02*
X826499D01*
G01X883699Y102650D02*
X842299D01*
Y52450D01*
X883699D01*
Y102650D01*
G01X832066Y106550D02*
Y109050D01*
X833066D01*
X833399Y108925D01*
X833649Y108633D01*
X833732Y108300D01*
X833649Y107967D01*
X833441Y107717D01*
X833066Y107592D01*
X832066D01*
G01X835166Y109050D02*
Y106550D01*
X836832D01*
G01X838307Y108633D02*
X838557Y108883D01*
X838849Y109008D01*
X839182Y109050D01*
X839599Y108967D01*
X839891Y108758D01*
X839974Y108508D01*
X839932Y108258D01*
X839766Y108050D01*
X838932Y107633D01*
X838557Y107342D01*
X838307Y106925D01*
X838224Y106550D01*
X839974D01*
G01X829000Y122017D02*
X826500D01*
Y123017D01*
X826625Y123350D01*
X826917Y123600D01*
X827250Y123683D01*
X827583Y123600D01*
X827833Y123392D01*
X827958Y123017D01*
Y122017D01*
G01X826708Y126867D02*
X826583Y126617D01*
X826500Y126325D01*
Y125992D01*
X826625Y125617D01*
X826833Y125325D01*
X827083Y125117D01*
X827500Y124950D01*
X827875Y124908D01*
X828250Y124992D01*
X828500Y125117D01*
X828750Y125367D01*
X828917Y125658D01*
X829000Y125950D01*
Y126242D01*
X828917Y126533D01*
X828792Y126783D01*
X828625Y126992D01*
G01X829000Y129050D02*
X826500D01*
X827000Y128550D01*
G01X829000D02*
Y129550D01*
G01Y132150D02*
X826500D01*
X827000Y131650D01*
G01X829000D02*
Y132650D01*
G01X842999Y121250D02*
Y126750D01*
G01X850999Y121250D02*
X842999D01*
G01Y133350D02*
Y138850D01*
G01X839000Y122517D02*
X836500D01*
Y123517D01*
X836625Y123850D01*
X836917Y124100D01*
X837250Y124183D01*
X837583Y124100D01*
X837833Y123892D01*
X837958Y123517D01*
Y122517D01*
G01X836500Y126450D02*
X839000D01*
G01X836500Y125492D02*
Y127408D01*
G01X836708Y130467D02*
X836583Y130217D01*
X836500Y129925D01*
Y129592D01*
X836625Y129217D01*
X836833Y128925D01*
X837083Y128717D01*
X837500Y128550D01*
X837875Y128508D01*
X838250Y128592D01*
X838500Y128717D01*
X838750Y128967D01*
X838917Y129258D01*
X839000Y129550D01*
Y129842D01*
X838917Y130133D01*
X838792Y130383D01*
X838625Y130592D01*
G01X839000Y132650D02*
X836500D01*
X837000Y132150D01*
G01X839000D02*
Y133150D01*
G01X834500Y121517D02*
X832000D01*
Y122517D01*
X832125Y122850D01*
X832417Y123100D01*
X832750Y123183D01*
X833083Y123100D01*
X833333Y122892D01*
X833458Y122517D01*
Y121517D01*
G01X832000Y125450D02*
X834500D01*
G01X832000Y124492D02*
Y126408D01*
G01X832208Y129467D02*
X832083Y129217D01*
X832000Y128925D01*
Y128592D01*
X832125Y128217D01*
X832333Y127925D01*
X832583Y127717D01*
X833000Y127550D01*
X833375Y127508D01*
X833750Y127592D01*
X834000Y127717D01*
X834250Y127967D01*
X834417Y128258D01*
X834500Y128550D01*
Y128842D01*
X834417Y129133D01*
X834292Y129383D01*
X834125Y129592D01*
G01X832417Y130858D02*
X832167Y131108D01*
X832042Y131400D01*
X832000Y131733D01*
X832083Y132150D01*
X832292Y132442D01*
X832542Y132525D01*
X832792Y132483D01*
X833000Y132317D01*
X833417Y131483D01*
X833708Y131108D01*
X834125Y130858D01*
X834500Y130775D01*
Y132525D01*
G01X825499Y144567D02*
X822999D01*
Y145608D01*
X823124Y145942D01*
X823291Y146150D01*
X823624Y146233D01*
X823957Y146150D01*
X824166Y145900D01*
X824291Y145608D01*
Y144567D01*
G01Y145608D02*
X825499Y146233D01*
G01X824999Y147583D02*
X825291Y147833D01*
X825457Y148167D01*
X825499Y148542D01*
X825457Y148875D01*
X825249Y149208D01*
X824999Y149417D01*
X824749Y149458D01*
X824457Y149375D01*
X824249Y149083D01*
X824166Y148792D01*
Y148417D01*
G01Y148792D02*
X824041Y149042D01*
X823832Y149250D01*
X823582Y149333D01*
X823332Y149250D01*
X823124Y149042D01*
X822999Y148667D01*
X823041Y148292D01*
X823207Y147917D01*
G01X824999Y150683D02*
X825291Y150933D01*
X825457Y151267D01*
X825499Y151642D01*
X825457Y151975D01*
X825249Y152308D01*
X824999Y152517D01*
X824749Y152558D01*
X824457Y152475D01*
X824249Y152183D01*
X824166Y151892D01*
Y151517D01*
G01Y151892D02*
X824041Y152142D01*
X823832Y152350D01*
X823582Y152433D01*
X823332Y152350D01*
X823124Y152142D01*
X822999Y151767D01*
X823041Y151392D01*
X823207Y151017D01*
G01X823416Y153908D02*
X823166Y154158D01*
X823041Y154450D01*
X822999Y154783D01*
X823082Y155200D01*
X823291Y155492D01*
X823541Y155575D01*
X823791Y155533D01*
X823999Y155367D01*
X824416Y154533D01*
X824707Y154158D01*
X825124Y153908D01*
X825499Y153825D01*
Y155575D01*
G01X832999Y144567D02*
X830499D01*
Y145608D01*
X830624Y145942D01*
X830791Y146150D01*
X831124Y146233D01*
X831457Y146150D01*
X831666Y145900D01*
X831791Y145608D01*
Y144567D01*
G01Y145608D02*
X832999Y146233D01*
G01X832499Y147583D02*
X832791Y147833D01*
X832957Y148167D01*
X832999Y148542D01*
X832957Y148875D01*
X832749Y149208D01*
X832499Y149417D01*
X832249Y149458D01*
X831957Y149375D01*
X831749Y149083D01*
X831666Y148792D01*
Y148417D01*
G01Y148792D02*
X831541Y149042D01*
X831332Y149250D01*
X831082Y149333D01*
X830832Y149250D01*
X830624Y149042D01*
X830499Y148667D01*
X830541Y148292D01*
X830707Y147917D01*
G01X832499Y150683D02*
X832791Y150933D01*
X832957Y151267D01*
X832999Y151642D01*
X832957Y151975D01*
X832749Y152308D01*
X832499Y152517D01*
X832249Y152558D01*
X831957Y152475D01*
X831749Y152183D01*
X831666Y151892D01*
Y151517D01*
G01Y151892D02*
X831541Y152142D01*
X831332Y152350D01*
X831082Y152433D01*
X830832Y152350D01*
X830624Y152142D01*
X830499Y151767D01*
X830541Y151392D01*
X830707Y151017D01*
G01X832499Y153783D02*
X832791Y154033D01*
X832957Y154367D01*
X832999Y154742D01*
X832957Y155075D01*
X832749Y155408D01*
X832499Y155617D01*
X832249Y155658D01*
X831957Y155575D01*
X831749Y155283D01*
X831666Y154992D01*
Y154617D01*
G01Y154992D02*
X831541Y155242D01*
X831332Y155450D01*
X831082Y155533D01*
X830832Y155450D01*
X830624Y155242D01*
X830499Y154867D01*
X830541Y154492D01*
X830707Y154117D01*
G01X829499Y157350D02*
X833499D01*
Y164750D01*
G01X842999Y138850D02*
X850999D01*
G01X833699Y165050D02*
Y169050D01*
X826299D01*
G01X824923Y189039D02*
Y181039D01*
X836873D01*
Y189039D01*
X824923D01*
G01X836873Y182889D02*
X834873Y184889D01*
X836873Y186889D01*
G01X835999Y210250D02*
X831999D01*
Y202850D01*
G01X843643Y201293D02*
X841143D01*
Y202334D01*
X841268Y202668D01*
X841435Y202876D01*
X841768Y202959D01*
X842101Y202876D01*
X842310Y202626D01*
X842435Y202334D01*
Y201293D01*
G01Y202334D02*
X843643Y202959D01*
G01X843143Y204309D02*
X843435Y204559D01*
X843601Y204893D01*
X843643Y205268D01*
X843601Y205601D01*
X843393Y205934D01*
X843143Y206143D01*
X842893Y206184D01*
X842601Y206101D01*
X842393Y205809D01*
X842310Y205518D01*
Y205143D01*
G01Y205518D02*
X842185Y205768D01*
X841976Y205976D01*
X841726Y206059D01*
X841476Y205976D01*
X841268Y205768D01*
X841143Y205393D01*
X841185Y205018D01*
X841351Y204643D01*
G01X843143Y207409D02*
X843435Y207659D01*
X843601Y207993D01*
X843643Y208368D01*
X843601Y208701D01*
X843393Y209034D01*
X843143Y209243D01*
X842893Y209284D01*
X842601Y209201D01*
X842393Y208909D01*
X842310Y208618D01*
Y208243D01*
G01Y208618D02*
X842185Y208868D01*
X841976Y209076D01*
X841726Y209159D01*
X841476Y209076D01*
X841268Y208868D01*
X841143Y208493D01*
X841185Y208118D01*
X841351Y207743D01*
G01X843268Y210509D02*
X843476Y210759D01*
X843601Y211051D01*
X843643Y211426D01*
X843560Y211801D01*
X843393Y212093D01*
X843101Y212301D01*
X842768Y212343D01*
X842435Y212259D01*
X842226Y212051D01*
X842060Y211759D01*
X842018Y211468D01*
X842060Y211176D01*
X842226Y210801D01*
X841143Y210926D01*
Y212051D01*
G01X831499Y210250D02*
X827499D01*
Y202850D01*
G01X843245Y225716D02*
X842995Y225841D01*
X842703Y225924D01*
X842370D01*
X841995Y225799D01*
X841703Y225591D01*
X841495Y225341D01*
X841328Y224924D01*
X841286Y224549D01*
X841370Y224174D01*
X841495Y223924D01*
X841745Y223674D01*
X842036Y223507D01*
X842328Y223424D01*
X842620D01*
X842911Y223507D01*
X843161Y223632D01*
X843370Y223799D01*
G01X845428Y223424D02*
Y225924D01*
X844928Y225424D01*
G01Y223424D02*
X845928D01*
G01X847736Y224466D02*
X848028Y224757D01*
X848278Y224924D01*
X848611Y225007D01*
X848903Y224924D01*
X849111Y224757D01*
X849278Y224507D01*
X849320Y224216D01*
X849278Y223966D01*
X849111Y223716D01*
X848861Y223507D01*
X848570Y223424D01*
X848236Y223507D01*
X847945Y223757D01*
X847778Y224132D01*
X847736Y224549D01*
X847820Y225091D01*
X847945Y225382D01*
X848153Y225674D01*
X848445Y225882D01*
X848736Y225924D01*
X849028Y225841D01*
X849236Y225632D01*
G01X850836Y224466D02*
X851128Y224757D01*
X851378Y224924D01*
X851711Y225007D01*
X852003Y224924D01*
X852211Y224757D01*
X852378Y224507D01*
X852420Y224216D01*
X852378Y223966D01*
X852211Y223716D01*
X851961Y223507D01*
X851670Y223424D01*
X851336Y223507D01*
X851045Y223757D01*
X850878Y224132D01*
X850836Y224549D01*
X850920Y225091D01*
X851045Y225382D01*
X851253Y225674D01*
X851545Y225882D01*
X851836Y225924D01*
X852128Y225841D01*
X852336Y225632D01*
G01X843245Y229216D02*
X842995Y229341D01*
X842703Y229424D01*
X842370D01*
X841995Y229299D01*
X841703Y229091D01*
X841495Y228841D01*
X841328Y228424D01*
X841286Y228049D01*
X841370Y227674D01*
X841495Y227424D01*
X841745Y227174D01*
X842036Y227007D01*
X842328Y226924D01*
X842620D01*
X842911Y227007D01*
X843161Y227132D01*
X843370Y227299D01*
G01X845428Y226924D02*
Y229424D01*
X844928Y228924D01*
G01Y226924D02*
X845928D01*
G01X847736Y227966D02*
X848028Y228257D01*
X848278Y228424D01*
X848611Y228507D01*
X848903Y228424D01*
X849111Y228257D01*
X849278Y228007D01*
X849320Y227716D01*
X849278Y227466D01*
X849111Y227216D01*
X848861Y227007D01*
X848570Y226924D01*
X848236Y227007D01*
X847945Y227257D01*
X847778Y227632D01*
X847736Y228049D01*
X847820Y228591D01*
X847945Y228882D01*
X848153Y229174D01*
X848445Y229382D01*
X848736Y229424D01*
X849028Y229341D01*
X849236Y229132D01*
G01X851545Y226924D02*
X851628Y227466D01*
X851753Y227924D01*
X851920Y228341D01*
X852128Y228799D01*
X852461Y229424D01*
X850795D01*
G01X843245Y250216D02*
X842995Y250341D01*
X842703Y250424D01*
X842370D01*
X841995Y250299D01*
X841703Y250091D01*
X841495Y249841D01*
X841328Y249424D01*
X841286Y249049D01*
X841370Y248674D01*
X841495Y248424D01*
X841745Y248174D01*
X842036Y248007D01*
X842328Y247924D01*
X842620D01*
X842911Y248007D01*
X843161Y248132D01*
X843370Y248299D01*
G01X845428Y247924D02*
Y250424D01*
X844928Y249924D01*
G01Y247924D02*
X845928D01*
G01X847736Y248966D02*
X848028Y249257D01*
X848278Y249424D01*
X848611Y249507D01*
X848903Y249424D01*
X849111Y249257D01*
X849278Y249007D01*
X849320Y248716D01*
X849278Y248466D01*
X849111Y248216D01*
X848861Y248007D01*
X848570Y247924D01*
X848236Y248007D01*
X847945Y248257D01*
X847778Y248632D01*
X847736Y249049D01*
X847820Y249591D01*
X847945Y249882D01*
X848153Y250174D01*
X848445Y250382D01*
X848736Y250424D01*
X849028Y250341D01*
X849236Y250132D01*
G01X851628Y247924D02*
X851920Y247966D01*
X852253Y248091D01*
X852461Y248299D01*
X852545Y248591D01*
X852461Y248882D01*
X852211Y249132D01*
X851836Y249257D01*
X851420D01*
X851170Y249341D01*
X850961Y249549D01*
X850878Y249841D01*
X851003Y250132D01*
X851295Y250341D01*
X851628Y250424D01*
X851961Y250341D01*
X852253Y250132D01*
X852378Y249841D01*
X852295Y249549D01*
X852086Y249341D01*
X851836Y249257D01*
X851420D01*
X851045Y249132D01*
X850795Y248882D01*
X850711Y248591D01*
X850795Y248299D01*
X851003Y248091D01*
X851336Y247966D01*
X851628Y247924D01*
G01X843266Y253842D02*
X843016Y253967D01*
X842724Y254050D01*
X842391D01*
X842016Y253925D01*
X841724Y253717D01*
X841516Y253467D01*
X841349Y253050D01*
X841307Y252675D01*
X841391Y252300D01*
X841516Y252050D01*
X841766Y251800D01*
X842057Y251633D01*
X842349Y251550D01*
X842641D01*
X842932Y251633D01*
X843182Y251758D01*
X843391Y251925D01*
G01X845449Y251550D02*
Y254050D01*
X844949Y253550D01*
G01Y251550D02*
X845949D01*
G01X847757Y252592D02*
X848049Y252883D01*
X848299Y253050D01*
X848632Y253133D01*
X848924Y253050D01*
X849132Y252883D01*
X849299Y252633D01*
X849341Y252342D01*
X849299Y252092D01*
X849132Y251842D01*
X848882Y251633D01*
X848591Y251550D01*
X848257Y251633D01*
X847966Y251883D01*
X847799Y252258D01*
X847757Y252675D01*
X847841Y253217D01*
X847966Y253508D01*
X848174Y253800D01*
X848466Y254008D01*
X848757Y254050D01*
X849049Y253967D01*
X849257Y253758D01*
G01X850941Y251842D02*
X851232Y251633D01*
X851566Y251550D01*
X851899Y251633D01*
X852191Y251883D01*
X852399Y252258D01*
X852482Y252633D01*
Y253092D01*
X852399Y253467D01*
X852191Y253800D01*
X851941Y253967D01*
X851649Y254050D01*
X851316Y253967D01*
X851066Y253800D01*
X850899Y253550D01*
X850816Y253217D01*
X850899Y252925D01*
X851107Y252633D01*
X851357Y252467D01*
X851649Y252425D01*
X851982Y252508D01*
X852232Y252717D01*
X852482Y253092D01*
G01X825100Y261800D02*
Y273200D01*
G01X829500Y249567D02*
X827000D01*
Y250608D01*
X827125Y250942D01*
X827292Y251150D01*
X827625Y251233D01*
X827958Y251150D01*
X828167Y250900D01*
X828292Y250608D01*
Y249567D01*
G01Y250608D02*
X829500Y251233D01*
G01X829000Y252583D02*
X829292Y252833D01*
X829458Y253167D01*
X829500Y253542D01*
X829458Y253875D01*
X829250Y254208D01*
X829000Y254417D01*
X828750Y254458D01*
X828458Y254375D01*
X828250Y254083D01*
X828167Y253792D01*
Y253417D01*
G01Y253792D02*
X828042Y254042D01*
X827833Y254250D01*
X827583Y254333D01*
X827333Y254250D01*
X827125Y254042D01*
X827000Y253667D01*
X827042Y253292D01*
X827208Y252917D01*
G01X829500Y256517D02*
X828958Y256600D01*
X828500Y256725D01*
X828083Y256892D01*
X827625Y257100D01*
X827000Y257433D01*
Y255767D01*
G01Y259700D02*
X827083Y259367D01*
X827292Y259117D01*
X827542Y258950D01*
X827875Y258825D01*
X828250Y258783D01*
X828625Y258825D01*
X828958Y258950D01*
X829208Y259117D01*
X829417Y259367D01*
X829500Y259700D01*
X829417Y260033D01*
X829208Y260283D01*
X828958Y260450D01*
X828625Y260575D01*
X828250Y260617D01*
X827875Y260575D01*
X827542Y260450D01*
X827292Y260283D01*
X827083Y260033D01*
X827000Y259700D01*
G01X840900Y260000D02*
X840567Y260042D01*
X840275Y260208D01*
X840025Y260458D01*
X839858Y260750D01*
X839775Y261083D01*
Y261417D01*
X839858Y261750D01*
X840025Y262042D01*
X840275Y262292D01*
X840567Y262458D01*
X840900Y262500D01*
X841233Y262458D01*
X841525Y262292D01*
X841775Y262042D01*
X841942Y261750D01*
X842025Y261417D01*
Y261083D01*
X841942Y260750D01*
X841775Y260458D01*
X841525Y260208D01*
X841233Y260042D01*
X840900Y260000D01*
G01X841233Y260667D02*
X841733Y260000D01*
G01X843083Y260375D02*
X843333Y260167D01*
X843625Y260042D01*
X844000Y260000D01*
X844375Y260083D01*
X844667Y260250D01*
X844875Y260542D01*
X844917Y260875D01*
X844833Y261208D01*
X844625Y261417D01*
X844333Y261583D01*
X844042Y261625D01*
X843750Y261583D01*
X843375Y261417D01*
X843500Y262500D01*
X844625D01*
G01X846183Y260375D02*
X846433Y260167D01*
X846725Y260042D01*
X847100Y260000D01*
X847475Y260083D01*
X847767Y260250D01*
X847975Y260542D01*
X848017Y260875D01*
X847933Y261208D01*
X847725Y261417D01*
X847433Y261583D01*
X847142Y261625D01*
X846850Y261583D01*
X846475Y261417D01*
X846600Y262500D01*
X847725D01*
G01X834228Y296624D02*
Y283624D01*
G01D02*
X860228D01*
G01X843778Y282924D02*
Y278924D01*
X851178D01*
G01X829500Y272900D02*
X825500D01*
Y265500D01*
G01X843200Y264200D02*
Y278200D01*
G01X830200Y264200D02*
X843200D01*
G01X830200Y278200D02*
Y264200D01*
G01X843200Y278200D02*
X830200D01*
G01X860228Y296624D02*
X834228D01*
G01X845388Y298674D02*
Y308174D01*
X827688D01*
Y298674D01*
X845388D01*
G01X837728Y330424D02*
Y317424D01*
G01D02*
X863728D01*
G01X826999Y358950D02*
Y320150D01*
G01X836978Y327724D02*
Y322224D01*
G01X828978D02*
Y327724D01*
G01Y310124D02*
Y315624D01*
G01X836978Y310124D02*
X828978D01*
G01X836978Y315624D02*
Y310124D01*
G01X863728Y330424D02*
X837728D01*
G01X828978Y327724D02*
X836978D01*
G01X836800Y332500D02*
Y338000D01*
G01X844800Y332500D02*
X836800D01*
G01Y344600D02*
Y350100D01*
G01X836100Y332500D02*
Y350100D01*
G01X828100Y332500D02*
X836100D01*
G01X828100Y350100D02*
Y332500D01*
G01X839508Y354467D02*
X839383Y354217D01*
X839300Y353925D01*
Y353592D01*
X839425Y353217D01*
X839633Y352925D01*
X839883Y352717D01*
X840300Y352550D01*
X840675Y352508D01*
X841050Y352592D01*
X841300Y352717D01*
X841550Y352967D01*
X841717Y353258D01*
X841800Y353550D01*
Y353842D01*
X841717Y354133D01*
X841592Y354383D01*
X841425Y354592D01*
G01X841800Y356650D02*
X839300D01*
X839800Y356150D01*
G01X841800D02*
Y357150D01*
G01Y359667D02*
X841258Y359750D01*
X840800Y359875D01*
X840383Y360042D01*
X839925Y360250D01*
X839300Y360583D01*
Y358917D01*
G01X841425Y361933D02*
X841633Y362183D01*
X841758Y362475D01*
X841800Y362850D01*
X841717Y363225D01*
X841550Y363517D01*
X841258Y363725D01*
X840925Y363767D01*
X840592Y363683D01*
X840383Y363475D01*
X840217Y363183D01*
X840175Y362892D01*
X840217Y362600D01*
X840383Y362225D01*
X839300Y362350D01*
Y363475D01*
G01X836800Y350100D02*
X844800D01*
G01X834000Y353517D02*
X831500D01*
Y354558D01*
X831625Y354892D01*
X831792Y355100D01*
X832125Y355183D01*
X832458Y355100D01*
X832667Y354850D01*
X832792Y354558D01*
Y353517D01*
G01Y354558D02*
X834000Y355183D01*
G01X833625Y356533D02*
X833833Y356783D01*
X833958Y357075D01*
X834000Y357450D01*
X833917Y357825D01*
X833750Y358117D01*
X833458Y358325D01*
X833125Y358367D01*
X832792Y358283D01*
X832583Y358075D01*
X832417Y357783D01*
X832375Y357492D01*
X832417Y357200D01*
X832583Y356825D01*
X831500Y356950D01*
Y358075D01*
G01X831917Y359758D02*
X831667Y360008D01*
X831542Y360300D01*
X831500Y360633D01*
X831583Y361050D01*
X831792Y361342D01*
X832042Y361425D01*
X832292Y361383D01*
X832500Y361217D01*
X832917Y360383D01*
X833208Y360008D01*
X833625Y359758D01*
X834000Y359675D01*
Y361425D01*
G01Y363650D02*
X831500D01*
X832000Y363150D01*
G01X834000D02*
Y364150D01*
G01X836100Y350100D02*
X828100D01*
G01X842963Y631674D02*
X842713Y631799D01*
X842421Y631882D01*
X842088D01*
X841713Y631757D01*
X841421Y631549D01*
X841213Y631299D01*
X841046Y630882D01*
X841004Y630507D01*
X841088Y630132D01*
X841213Y629882D01*
X841463Y629632D01*
X841754Y629465D01*
X842046Y629382D01*
X842338D01*
X842629Y629465D01*
X842879Y629590D01*
X843088Y629757D01*
G01X845146Y629382D02*
Y631882D01*
X844646Y631382D01*
G01Y629382D02*
X845646D01*
G01X847329Y629757D02*
X847579Y629549D01*
X847871Y629424D01*
X848246Y629382D01*
X848621Y629465D01*
X848913Y629632D01*
X849121Y629924D01*
X849163Y630257D01*
X849079Y630590D01*
X848871Y630799D01*
X848579Y630965D01*
X848288Y631007D01*
X847996Y630965D01*
X847621Y630799D01*
X847746Y631882D01*
X848871D01*
G01X851346D02*
X851013Y631799D01*
X850763Y631590D01*
X850596Y631340D01*
X850471Y631007D01*
X850429Y630632D01*
X850471Y630257D01*
X850596Y629924D01*
X850763Y629674D01*
X851013Y629465D01*
X851346Y629382D01*
X851679Y629465D01*
X851929Y629674D01*
X852096Y629924D01*
X852221Y630257D01*
X852263Y630632D01*
X852221Y631007D01*
X852096Y631340D01*
X851929Y631590D01*
X851679Y631799D01*
X851346Y631882D01*
G01X842766Y635842D02*
X842516Y635967D01*
X842224Y636050D01*
X841891D01*
X841516Y635925D01*
X841224Y635717D01*
X841016Y635467D01*
X840849Y635050D01*
X840807Y634675D01*
X840891Y634300D01*
X841016Y634050D01*
X841266Y633800D01*
X841557Y633633D01*
X841849Y633550D01*
X842141D01*
X842432Y633633D01*
X842682Y633758D01*
X842891Y633925D01*
G01X844949Y633550D02*
Y636050D01*
X844449Y635550D01*
G01Y633550D02*
X845449D01*
G01X847132Y633925D02*
X847382Y633717D01*
X847674Y633592D01*
X848049Y633550D01*
X848424Y633633D01*
X848716Y633800D01*
X848924Y634092D01*
X848966Y634425D01*
X848882Y634758D01*
X848674Y634967D01*
X848382Y635133D01*
X848091Y635175D01*
X847799Y635133D01*
X847424Y634967D01*
X847549Y636050D01*
X848674D01*
G01X851149Y633550D02*
Y636050D01*
X850649Y635550D01*
G01Y633550D02*
X851649D01*
G01X842410Y655358D02*
X842160Y655483D01*
X841868Y655566D01*
X841535D01*
X841160Y655441D01*
X840868Y655233D01*
X840660Y654983D01*
X840493Y654566D01*
X840451Y654191D01*
X840535Y653816D01*
X840660Y653566D01*
X840910Y653316D01*
X841201Y653149D01*
X841493Y653066D01*
X841785D01*
X842076Y653149D01*
X842326Y653274D01*
X842535Y653441D01*
G01X844593Y653066D02*
Y655566D01*
X844093Y655066D01*
G01Y653066D02*
X845093D01*
G01X846776Y653441D02*
X847026Y653233D01*
X847318Y653108D01*
X847693Y653066D01*
X848068Y653149D01*
X848360Y653316D01*
X848568Y653608D01*
X848610Y653941D01*
X848526Y654274D01*
X848318Y654483D01*
X848026Y654649D01*
X847735Y654691D01*
X847443Y654649D01*
X847068Y654483D01*
X847193Y655566D01*
X848318D01*
G01X850001Y655149D02*
X850251Y655399D01*
X850543Y655524D01*
X850876Y655566D01*
X851293Y655483D01*
X851585Y655274D01*
X851668Y655024D01*
X851626Y654774D01*
X851460Y654566D01*
X850626Y654149D01*
X850251Y653858D01*
X850001Y653441D01*
X849918Y653066D01*
X851668D01*
G01X842713Y659526D02*
X842463Y659651D01*
X842171Y659734D01*
X841838D01*
X841463Y659609D01*
X841171Y659401D01*
X840963Y659151D01*
X840796Y658734D01*
X840754Y658359D01*
X840838Y657984D01*
X840963Y657734D01*
X841213Y657484D01*
X841504Y657317D01*
X841796Y657234D01*
X842088D01*
X842379Y657317D01*
X842629Y657442D01*
X842838Y657609D01*
G01X844896Y657234D02*
Y659734D01*
X844396Y659234D01*
G01Y657234D02*
X845396D01*
G01X847079Y657609D02*
X847329Y657401D01*
X847621Y657276D01*
X847996Y657234D01*
X848371Y657317D01*
X848663Y657484D01*
X848871Y657776D01*
X848913Y658109D01*
X848829Y658442D01*
X848621Y658651D01*
X848329Y658817D01*
X848038Y658859D01*
X847746Y658817D01*
X847371Y658651D01*
X847496Y659734D01*
X848621D01*
G01X850179Y657734D02*
X850429Y657442D01*
X850763Y657276D01*
X851138Y657234D01*
X851471Y657276D01*
X851804Y657484D01*
X852013Y657734D01*
X852054Y657984D01*
X851971Y658276D01*
X851679Y658484D01*
X851388Y658567D01*
X851013D01*
G01X851388D02*
X851638Y658692D01*
X851846Y658901D01*
X851929Y659151D01*
X851846Y659401D01*
X851638Y659609D01*
X851263Y659734D01*
X850888Y659692D01*
X850513Y659526D01*
G01X823600Y664400D02*
Y675800D01*
G01X824100Y664700D02*
X828100D01*
Y672100D01*
G01X830900Y657500D02*
X830567Y657542D01*
X830275Y657708D01*
X830025Y657958D01*
X829858Y658250D01*
X829775Y658583D01*
Y658917D01*
X829858Y659250D01*
X830025Y659542D01*
X830275Y659792D01*
X830567Y659958D01*
X830900Y660000D01*
X831233Y659958D01*
X831525Y659792D01*
X831775Y659542D01*
X831942Y659250D01*
X832025Y658917D01*
Y658583D01*
X831942Y658250D01*
X831775Y657958D01*
X831525Y657708D01*
X831233Y657542D01*
X830900Y657500D01*
G01X831233Y658167D02*
X831733Y657500D01*
G01X833083Y657875D02*
X833333Y657667D01*
X833625Y657542D01*
X834000Y657500D01*
X834375Y657583D01*
X834667Y657750D01*
X834875Y658042D01*
X834917Y658375D01*
X834833Y658708D01*
X834625Y658917D01*
X834333Y659083D01*
X834042Y659125D01*
X833750Y659083D01*
X833375Y658917D01*
X833500Y660000D01*
X834625D01*
G01X836183Y658000D02*
X836433Y657708D01*
X836767Y657542D01*
X837142Y657500D01*
X837475Y657542D01*
X837808Y657750D01*
X838017Y658000D01*
X838058Y658250D01*
X837975Y658542D01*
X837683Y658750D01*
X837392Y658833D01*
X837017D01*
G01X837392D02*
X837642Y658958D01*
X837850Y659167D01*
X837933Y659417D01*
X837850Y659667D01*
X837642Y659875D01*
X837267Y660000D01*
X836892Y659958D01*
X836517Y659792D01*
G01X832446Y697682D02*
Y684682D01*
G01D02*
X858446D01*
G01X842496Y683882D02*
Y679882D01*
X849896D01*
G01X849900Y675700D02*
Y679700D01*
X842500D01*
G01X841800Y666900D02*
Y680900D01*
G01X828800Y666900D02*
X841800D01*
G01X828800Y680900D02*
Y666900D01*
G01X841800Y680900D02*
X828800D01*
G01X858446Y697682D02*
X832446D01*
G01X826158Y694000D02*
Y696500D01*
X827742D01*
G01X827158Y695292D02*
X826158D01*
G01X829967Y694000D02*
X830050Y694542D01*
X830175Y695000D01*
X830342Y695417D01*
X830550Y695875D01*
X830883Y696500D01*
X829217D01*
G01X843306Y699632D02*
Y709132D01*
X825606D01*
Y699632D01*
X843306D01*
G01X835499Y731050D02*
Y718050D01*
G01D02*
X861499D01*
G01X824999Y761950D02*
Y723150D01*
G01X834499Y729850D02*
Y724350D01*
G01X826499D02*
Y729850D01*
G01Y712250D02*
Y717750D01*
G01X834499Y712250D02*
X826499D01*
G01X834499Y717750D02*
Y712250D01*
G01X861499Y731050D02*
X835499D01*
G01X826499Y729850D02*
X834499D01*
G01X834796Y733282D02*
Y738782D01*
G01X842796Y733282D02*
X834796D01*
G01X842796Y738782D02*
Y733282D01*
G01Y750882D02*
Y745382D01*
G01X834796D02*
Y750882D01*
G01X843496Y733282D02*
Y738782D01*
G01X851496Y733282D02*
X843496D01*
G01Y745382D02*
Y750882D01*
G01X834100Y733300D02*
Y750900D01*
G01X826100Y733300D02*
X834100D01*
G01X826100Y750900D02*
Y733300D01*
G01X837504Y755249D02*
X837379Y754999D01*
X837296Y754707D01*
Y754374D01*
X837421Y753999D01*
X837629Y753707D01*
X837879Y753499D01*
X838296Y753332D01*
X838671Y753290D01*
X839046Y753374D01*
X839296Y753499D01*
X839546Y753749D01*
X839713Y754040D01*
X839796Y754332D01*
Y754624D01*
X839713Y754915D01*
X839588Y755165D01*
X839421Y755374D01*
G01X839796Y757432D02*
X837296D01*
X837796Y756932D01*
G01X839796D02*
Y757932D01*
G01X838754Y759740D02*
X838463Y760032D01*
X838296Y760282D01*
X838213Y760615D01*
X838296Y760907D01*
X838463Y761115D01*
X838713Y761282D01*
X839004Y761324D01*
X839254Y761282D01*
X839504Y761115D01*
X839713Y760865D01*
X839796Y760574D01*
X839713Y760240D01*
X839463Y759949D01*
X839088Y759782D01*
X838671Y759740D01*
X838129Y759824D01*
X837838Y759949D01*
X837546Y760157D01*
X837338Y760449D01*
X837296Y760740D01*
X837379Y761032D01*
X837588Y761240D01*
G01X837296Y763632D02*
X837379Y763299D01*
X837588Y763049D01*
X837838Y762882D01*
X838171Y762757D01*
X838546Y762715D01*
X838921Y762757D01*
X839254Y762882D01*
X839504Y763049D01*
X839713Y763299D01*
X839796Y763632D01*
X839713Y763965D01*
X839504Y764215D01*
X839254Y764382D01*
X838921Y764507D01*
X838546Y764549D01*
X838171Y764507D01*
X837838Y764382D01*
X837588Y764215D01*
X837379Y763965D01*
X837296Y763632D01*
G01X834796Y750882D02*
X842796D01*
G01X843496D02*
X851496D01*
G01X831500Y753017D02*
X829000D01*
Y754058D01*
X829125Y754392D01*
X829292Y754600D01*
X829625Y754683D01*
X829958Y754600D01*
X830167Y754350D01*
X830292Y754058D01*
Y753017D01*
G01Y754058D02*
X831500Y754683D01*
G01X831125Y756033D02*
X831333Y756283D01*
X831458Y756575D01*
X831500Y756950D01*
X831417Y757325D01*
X831250Y757617D01*
X830958Y757825D01*
X830625Y757867D01*
X830292Y757783D01*
X830083Y757575D01*
X829917Y757283D01*
X829875Y756992D01*
X829917Y756700D01*
X830083Y756325D01*
X829000Y756450D01*
Y757575D01*
G01X831500Y760050D02*
X829000D01*
X829500Y759550D01*
G01X831500D02*
Y760550D01*
G01X831208Y762442D02*
X831417Y762733D01*
X831500Y763067D01*
X831417Y763400D01*
X831167Y763692D01*
X830792Y763900D01*
X830417Y763983D01*
X829958D01*
X829583Y763900D01*
X829250Y763692D01*
X829083Y763442D01*
X829000Y763150D01*
X829083Y762817D01*
X829250Y762567D01*
X829500Y762400D01*
X829833Y762317D01*
X830125Y762400D01*
X830417Y762608D01*
X830583Y762858D01*
X830625Y763150D01*
X830542Y763483D01*
X830333Y763733D01*
X829958Y763983D01*
G01X834100Y750900D02*
X826100D01*
G01X843600Y1036684D02*
X843350Y1036809D01*
X843058Y1036892D01*
X842725D01*
X842350Y1036767D01*
X842058Y1036559D01*
X841850Y1036309D01*
X841683Y1035892D01*
X841641Y1035517D01*
X841725Y1035142D01*
X841850Y1034892D01*
X842100Y1034642D01*
X842391Y1034475D01*
X842683Y1034392D01*
X842975D01*
X843266Y1034475D01*
X843516Y1034600D01*
X843725Y1034767D01*
G01X845783Y1034392D02*
Y1036892D01*
X845283Y1036392D01*
G01Y1034392D02*
X846283D01*
G01X847966Y1034892D02*
X848216Y1034600D01*
X848550Y1034434D01*
X848925Y1034392D01*
X849258Y1034434D01*
X849591Y1034642D01*
X849800Y1034892D01*
X849841Y1035142D01*
X849758Y1035434D01*
X849466Y1035642D01*
X849175Y1035725D01*
X848800D01*
G01X849175D02*
X849425Y1035850D01*
X849633Y1036059D01*
X849716Y1036309D01*
X849633Y1036559D01*
X849425Y1036767D01*
X849050Y1036892D01*
X848675Y1036850D01*
X848300Y1036684D01*
G01X852483Y1034392D02*
Y1036892D01*
X850941Y1035100D01*
X853025D01*
G01X843600Y1040184D02*
X843350Y1040309D01*
X843058Y1040392D01*
X842725D01*
X842350Y1040267D01*
X842058Y1040059D01*
X841850Y1039809D01*
X841683Y1039392D01*
X841641Y1039017D01*
X841725Y1038642D01*
X841850Y1038392D01*
X842100Y1038142D01*
X842391Y1037975D01*
X842683Y1037892D01*
X842975D01*
X843266Y1037975D01*
X843516Y1038100D01*
X843725Y1038267D01*
G01X845783Y1037892D02*
Y1040392D01*
X845283Y1039892D01*
G01Y1037892D02*
X846283D01*
G01X847966Y1038392D02*
X848216Y1038100D01*
X848550Y1037934D01*
X848925Y1037892D01*
X849258Y1037934D01*
X849591Y1038142D01*
X849800Y1038392D01*
X849841Y1038642D01*
X849758Y1038934D01*
X849466Y1039142D01*
X849175Y1039225D01*
X848800D01*
G01X849175D02*
X849425Y1039350D01*
X849633Y1039559D01*
X849716Y1039809D01*
X849633Y1040059D01*
X849425Y1040267D01*
X849050Y1040392D01*
X848675Y1040350D01*
X848300Y1040184D01*
G01X851066Y1038267D02*
X851316Y1038059D01*
X851608Y1037934D01*
X851983Y1037892D01*
X852358Y1037975D01*
X852650Y1038142D01*
X852858Y1038434D01*
X852900Y1038767D01*
X852816Y1039100D01*
X852608Y1039309D01*
X852316Y1039475D01*
X852025Y1039517D01*
X851733Y1039475D01*
X851358Y1039309D01*
X851483Y1040392D01*
X852608D01*
G01X823300Y1067200D02*
Y1078600D01*
G01X839517Y1067500D02*
Y1070000D01*
X840558D01*
X840892Y1069875D01*
X841100Y1069708D01*
X841183Y1069375D01*
X841100Y1069042D01*
X840850Y1068833D01*
X840558Y1068708D01*
X839517D01*
G01X840558D02*
X841183Y1067500D01*
G01X843450D02*
Y1070000D01*
X842950Y1069500D01*
G01Y1067500D02*
X843950D01*
G01X845633Y1068000D02*
X845883Y1067708D01*
X846217Y1067542D01*
X846592Y1067500D01*
X846925Y1067542D01*
X847258Y1067750D01*
X847467Y1068000D01*
X847508Y1068250D01*
X847425Y1068542D01*
X847133Y1068750D01*
X846842Y1068833D01*
X846467D01*
G01X846842D02*
X847092Y1068958D01*
X847300Y1069167D01*
X847383Y1069417D01*
X847300Y1069667D01*
X847092Y1069875D01*
X846717Y1070000D01*
X846342Y1069958D01*
X845967Y1069792D01*
G01X848733Y1068000D02*
X848983Y1067708D01*
X849317Y1067542D01*
X849692Y1067500D01*
X850025Y1067542D01*
X850358Y1067750D01*
X850567Y1068000D01*
X850608Y1068250D01*
X850525Y1068542D01*
X850233Y1068750D01*
X849942Y1068833D01*
X849567D01*
G01X849942D02*
X850192Y1068958D01*
X850400Y1069167D01*
X850483Y1069417D01*
X850400Y1069667D01*
X850192Y1069875D01*
X849817Y1070000D01*
X849442Y1069958D01*
X849067Y1069792D01*
G01X839517Y1063500D02*
Y1066000D01*
X840558D01*
X840892Y1065875D01*
X841100Y1065708D01*
X841183Y1065375D01*
X841100Y1065042D01*
X840850Y1064833D01*
X840558Y1064708D01*
X839517D01*
G01X840558D02*
X841183Y1063500D01*
G01X842533Y1064000D02*
X842783Y1063708D01*
X843117Y1063542D01*
X843492Y1063500D01*
X843825Y1063542D01*
X844158Y1063750D01*
X844367Y1064000D01*
X844408Y1064250D01*
X844325Y1064542D01*
X844033Y1064750D01*
X843742Y1064833D01*
X843367D01*
G01X843742D02*
X843992Y1064958D01*
X844200Y1065167D01*
X844283Y1065417D01*
X844200Y1065667D01*
X843992Y1065875D01*
X843617Y1066000D01*
X843242Y1065958D01*
X842867Y1065792D01*
G01X845758Y1064542D02*
X846050Y1064833D01*
X846300Y1065000D01*
X846633Y1065083D01*
X846925Y1065000D01*
X847133Y1064833D01*
X847300Y1064583D01*
X847342Y1064292D01*
X847300Y1064042D01*
X847133Y1063792D01*
X846883Y1063583D01*
X846592Y1063500D01*
X846258Y1063583D01*
X845967Y1063833D01*
X845800Y1064208D01*
X845758Y1064625D01*
X845842Y1065167D01*
X845967Y1065458D01*
X846175Y1065750D01*
X846467Y1065958D01*
X846758Y1066000D01*
X847050Y1065917D01*
X847258Y1065708D01*
G01X848733Y1063875D02*
X848983Y1063667D01*
X849275Y1063542D01*
X849650Y1063500D01*
X850025Y1063583D01*
X850317Y1063750D01*
X850525Y1064042D01*
X850567Y1064375D01*
X850483Y1064708D01*
X850275Y1064917D01*
X849983Y1065083D01*
X849692Y1065125D01*
X849400Y1065083D01*
X849025Y1064917D01*
X849150Y1066000D01*
X850275D01*
G01X827000Y1058517D02*
X824500D01*
Y1059558D01*
X824625Y1059892D01*
X824792Y1060100D01*
X825125Y1060183D01*
X825458Y1060100D01*
X825667Y1059850D01*
X825792Y1059558D01*
Y1058517D01*
G01Y1059558D02*
X827000Y1060183D01*
G01X826500Y1061533D02*
X826792Y1061783D01*
X826958Y1062117D01*
X827000Y1062492D01*
X826958Y1062825D01*
X826750Y1063158D01*
X826500Y1063367D01*
X826250Y1063408D01*
X825958Y1063325D01*
X825750Y1063033D01*
X825667Y1062742D01*
Y1062367D01*
G01Y1062742D02*
X825542Y1062992D01*
X825333Y1063200D01*
X825083Y1063283D01*
X824833Y1063200D01*
X824625Y1062992D01*
X824500Y1062617D01*
X824542Y1062242D01*
X824708Y1061867D01*
G01X825958Y1064758D02*
X825667Y1065050D01*
X825500Y1065300D01*
X825417Y1065633D01*
X825500Y1065925D01*
X825667Y1066133D01*
X825917Y1066300D01*
X826208Y1066342D01*
X826458Y1066300D01*
X826708Y1066133D01*
X826917Y1065883D01*
X827000Y1065592D01*
X826917Y1065258D01*
X826667Y1064967D01*
X826292Y1064800D01*
X825875Y1064758D01*
X825333Y1064842D01*
X825042Y1064967D01*
X824750Y1065175D01*
X824542Y1065467D01*
X824500Y1065758D01*
X824583Y1066050D01*
X824792Y1066258D01*
G01X826500Y1067733D02*
X826792Y1067983D01*
X826958Y1068317D01*
X827000Y1068692D01*
X826958Y1069025D01*
X826750Y1069358D01*
X826500Y1069567D01*
X826250Y1069608D01*
X825958Y1069525D01*
X825750Y1069233D01*
X825667Y1068942D01*
Y1068567D01*
G01Y1068942D02*
X825542Y1069192D01*
X825333Y1069400D01*
X825083Y1069483D01*
X824833Y1069400D01*
X824625Y1069192D01*
X824500Y1068817D01*
X824542Y1068442D01*
X824708Y1068067D01*
G01X830400Y1062000D02*
X830067Y1062042D01*
X829775Y1062208D01*
X829525Y1062458D01*
X829358Y1062750D01*
X829275Y1063083D01*
Y1063417D01*
X829358Y1063750D01*
X829525Y1064042D01*
X829775Y1064292D01*
X830067Y1064458D01*
X830400Y1064500D01*
X830733Y1064458D01*
X831025Y1064292D01*
X831275Y1064042D01*
X831442Y1063750D01*
X831525Y1063417D01*
Y1063083D01*
X831442Y1062750D01*
X831275Y1062458D01*
X831025Y1062208D01*
X830733Y1062042D01*
X830400Y1062000D01*
G01X830733Y1062667D02*
X831233Y1062000D01*
G01X832583Y1062375D02*
X832833Y1062167D01*
X833125Y1062042D01*
X833500Y1062000D01*
X833875Y1062083D01*
X834167Y1062250D01*
X834375Y1062542D01*
X834417Y1062875D01*
X834333Y1063208D01*
X834125Y1063417D01*
X833833Y1063583D01*
X833542Y1063625D01*
X833250Y1063583D01*
X832875Y1063417D01*
X833000Y1064500D01*
X834125D01*
G01X836600Y1062000D02*
Y1064500D01*
X836100Y1064000D01*
G01Y1062000D02*
X837100D01*
G01X842133Y1089392D02*
Y1085392D01*
X849533D01*
G01X849500Y1081200D02*
Y1085200D01*
X842100D01*
G01X827700Y1081200D02*
X823700D01*
Y1073800D01*
G01X841500Y1072500D02*
Y1086500D01*
G01X828500Y1072500D02*
X841500D01*
G01X828500Y1086500D02*
Y1072500D01*
G01X841500Y1086500D02*
X828500D01*
G01X832583Y1103192D02*
Y1090192D01*
G01X858583Y1103192D02*
X832583D01*
G01Y1090192D02*
X858583D01*
G01X843443Y1105142D02*
Y1114642D01*
X825743D01*
Y1105142D01*
X843443D01*
G01X835999Y1136050D02*
Y1123050D01*
G01D02*
X861999D01*
G01X824999Y1164450D02*
Y1125650D01*
G01X834499Y1133850D02*
Y1128350D01*
G01X826499D02*
Y1133850D01*
G01Y1116250D02*
Y1121750D01*
G01X834499Y1116250D02*
X826499D01*
G01X834499Y1121750D02*
Y1116250D01*
G01X836658Y1117500D02*
Y1120000D01*
X838242D01*
G01X837658Y1118792D02*
X836658D01*
G01X839633Y1117875D02*
X839883Y1117667D01*
X840175Y1117542D01*
X840550Y1117500D01*
X840925Y1117583D01*
X841217Y1117750D01*
X841425Y1118042D01*
X841467Y1118375D01*
X841383Y1118708D01*
X841175Y1118917D01*
X840883Y1119083D01*
X840592Y1119125D01*
X840300Y1119083D01*
X839925Y1118917D01*
X840050Y1120000D01*
X841175D01*
G01X861999Y1136050D02*
X835999D01*
G01X826499Y1133850D02*
X834499D01*
G01X834833Y1138092D02*
Y1143592D01*
G01X842833Y1138092D02*
X834833D01*
G01X842833Y1143592D02*
Y1138092D01*
G01Y1155692D02*
Y1150192D01*
G01X834833D02*
Y1155692D01*
G01X843533Y1138092D02*
Y1143592D01*
G01X851533Y1138092D02*
X843533D01*
G01Y1150192D02*
Y1155692D01*
G01X834100Y1138100D02*
Y1155700D01*
G01X826100Y1138100D02*
X834100D01*
G01X826100Y1155700D02*
Y1138100D01*
G01X837541Y1160059D02*
X837416Y1159809D01*
X837333Y1159517D01*
Y1159184D01*
X837458Y1158809D01*
X837666Y1158517D01*
X837916Y1158309D01*
X838333Y1158142D01*
X838708Y1158100D01*
X839083Y1158184D01*
X839333Y1158309D01*
X839583Y1158559D01*
X839750Y1158850D01*
X839833Y1159142D01*
Y1159434D01*
X839750Y1159725D01*
X839625Y1159975D01*
X839458Y1160184D01*
G01X839833Y1162242D02*
X837333D01*
X837833Y1161742D01*
G01X839833D02*
Y1162742D01*
G01Y1165842D02*
X837333D01*
X839125Y1164300D01*
Y1166384D01*
G01X839333Y1167525D02*
X839625Y1167775D01*
X839791Y1168109D01*
X839833Y1168484D01*
X839791Y1168817D01*
X839583Y1169150D01*
X839333Y1169359D01*
X839083Y1169400D01*
X838791Y1169317D01*
X838583Y1169025D01*
X838500Y1168734D01*
Y1168359D01*
G01Y1168734D02*
X838375Y1168984D01*
X838166Y1169192D01*
X837916Y1169275D01*
X837666Y1169192D01*
X837458Y1168984D01*
X837333Y1168609D01*
X837375Y1168234D01*
X837541Y1167859D01*
G01X834833Y1155692D02*
X842833D01*
G01X843533D02*
X851533D01*
G01X831500Y1158017D02*
X829000D01*
Y1159058D01*
X829125Y1159392D01*
X829292Y1159600D01*
X829625Y1159683D01*
X829958Y1159600D01*
X830167Y1159350D01*
X830292Y1159058D01*
Y1158017D01*
G01Y1159058D02*
X831500Y1159683D01*
G01X831125Y1161033D02*
X831333Y1161283D01*
X831458Y1161575D01*
X831500Y1161950D01*
X831417Y1162325D01*
X831250Y1162617D01*
X830958Y1162825D01*
X830625Y1162867D01*
X830292Y1162783D01*
X830083Y1162575D01*
X829917Y1162283D01*
X829875Y1161992D01*
X829917Y1161700D01*
X830083Y1161325D01*
X829000Y1161450D01*
Y1162575D01*
G01X831500Y1165050D02*
X829000D01*
X829500Y1164550D01*
G01X831500D02*
Y1165550D01*
G01Y1168067D02*
X830958Y1168150D01*
X830500Y1168275D01*
X830083Y1168442D01*
X829625Y1168650D01*
X829000Y1168983D01*
Y1167317D01*
G01X834100Y1155700D02*
X826100D01*
G01X844594Y1441588D02*
X844344Y1441713D01*
X844052Y1441796D01*
X843719D01*
X843344Y1441671D01*
X843052Y1441463D01*
X842844Y1441213D01*
X842677Y1440796D01*
X842635Y1440421D01*
X842719Y1440046D01*
X842844Y1439796D01*
X843094Y1439546D01*
X843385Y1439379D01*
X843677Y1439296D01*
X843969D01*
X844260Y1439379D01*
X844510Y1439504D01*
X844719Y1439671D01*
G01X846777Y1439296D02*
Y1441796D01*
X846277Y1441296D01*
G01Y1439296D02*
X847277D01*
G01X849877D02*
Y1441796D01*
X849377Y1441296D01*
G01Y1439296D02*
X850377D01*
G01X852977D02*
X853269Y1439338D01*
X853602Y1439463D01*
X853810Y1439671D01*
X853894Y1439963D01*
X853810Y1440254D01*
X853560Y1440504D01*
X853185Y1440629D01*
X852769D01*
X852519Y1440713D01*
X852310Y1440921D01*
X852227Y1441213D01*
X852352Y1441504D01*
X852644Y1441713D01*
X852977Y1441796D01*
X853310Y1441713D01*
X853602Y1441504D01*
X853727Y1441213D01*
X853644Y1440921D01*
X853435Y1440713D01*
X853185Y1440629D01*
X852769D01*
X852394Y1440504D01*
X852144Y1440254D01*
X852060Y1439963D01*
X852144Y1439671D01*
X852352Y1439463D01*
X852685Y1439338D01*
X852977Y1439296D01*
G01X844766Y1445342D02*
X844516Y1445467D01*
X844224Y1445550D01*
X843891D01*
X843516Y1445425D01*
X843224Y1445217D01*
X843016Y1444967D01*
X842849Y1444550D01*
X842807Y1444175D01*
X842891Y1443800D01*
X843016Y1443550D01*
X843266Y1443300D01*
X843557Y1443133D01*
X843849Y1443050D01*
X844141D01*
X844432Y1443133D01*
X844682Y1443258D01*
X844891Y1443425D01*
G01X846949Y1443050D02*
Y1445550D01*
X846449Y1445050D01*
G01Y1443050D02*
X847449D01*
G01X850049D02*
Y1445550D01*
X849549Y1445050D01*
G01Y1443050D02*
X850549D01*
G01X852441Y1443342D02*
X852732Y1443133D01*
X853066Y1443050D01*
X853399Y1443133D01*
X853691Y1443383D01*
X853899Y1443758D01*
X853982Y1444133D01*
Y1444592D01*
X853899Y1444967D01*
X853691Y1445300D01*
X853441Y1445467D01*
X853149Y1445550D01*
X852816Y1445467D01*
X852566Y1445300D01*
X852399Y1445050D01*
X852316Y1444717D01*
X852399Y1444425D01*
X852607Y1444133D01*
X852857Y1443967D01*
X853149Y1443925D01*
X853482Y1444008D01*
X853732Y1444217D01*
X853982Y1444592D01*
G01X844094Y1466588D02*
X843844Y1466713D01*
X843552Y1466796D01*
X843219D01*
X842844Y1466671D01*
X842552Y1466463D01*
X842344Y1466213D01*
X842177Y1465796D01*
X842135Y1465421D01*
X842219Y1465046D01*
X842344Y1464796D01*
X842594Y1464546D01*
X842885Y1464379D01*
X843177Y1464296D01*
X843469D01*
X843760Y1464379D01*
X844010Y1464504D01*
X844219Y1464671D01*
G01X846277Y1464296D02*
Y1466796D01*
X845777Y1466296D01*
G01Y1464296D02*
X846777D01*
G01X848585Y1466379D02*
X848835Y1466629D01*
X849127Y1466754D01*
X849460Y1466796D01*
X849877Y1466713D01*
X850169Y1466504D01*
X850252Y1466254D01*
X850210Y1466004D01*
X850044Y1465796D01*
X849210Y1465379D01*
X848835Y1465088D01*
X848585Y1464671D01*
X848502Y1464296D01*
X850252D01*
G01X852477Y1466796D02*
X852144Y1466713D01*
X851894Y1466504D01*
X851727Y1466254D01*
X851602Y1465921D01*
X851560Y1465546D01*
X851602Y1465171D01*
X851727Y1464838D01*
X851894Y1464588D01*
X852144Y1464379D01*
X852477Y1464296D01*
X852810Y1464379D01*
X853060Y1464588D01*
X853227Y1464838D01*
X853352Y1465171D01*
X853394Y1465546D01*
X853352Y1465921D01*
X853227Y1466254D01*
X853060Y1466504D01*
X852810Y1466713D01*
X852477Y1466796D01*
G01X843766Y1470342D02*
X843516Y1470467D01*
X843224Y1470550D01*
X842891D01*
X842516Y1470425D01*
X842224Y1470217D01*
X842016Y1469967D01*
X841849Y1469550D01*
X841807Y1469175D01*
X841891Y1468800D01*
X842016Y1468550D01*
X842266Y1468300D01*
X842557Y1468133D01*
X842849Y1468050D01*
X843141D01*
X843432Y1468133D01*
X843682Y1468258D01*
X843891Y1468425D01*
G01X845949Y1468050D02*
Y1470550D01*
X845449Y1470050D01*
G01Y1468050D02*
X846449D01*
G01X848257Y1470133D02*
X848507Y1470383D01*
X848799Y1470508D01*
X849132Y1470550D01*
X849549Y1470467D01*
X849841Y1470258D01*
X849924Y1470008D01*
X849882Y1469758D01*
X849716Y1469550D01*
X848882Y1469133D01*
X848507Y1468842D01*
X848257Y1468425D01*
X848174Y1468050D01*
X849924D01*
G01X852149D02*
Y1470550D01*
X851649Y1470050D01*
G01Y1468050D02*
X852649D01*
G01X825100Y1474900D02*
Y1486300D01*
G01X829700Y1486100D02*
X825700D01*
Y1478700D01*
G01X826400Y1470500D02*
X826067Y1470542D01*
X825775Y1470708D01*
X825525Y1470958D01*
X825358Y1471250D01*
X825275Y1471583D01*
Y1471917D01*
X825358Y1472250D01*
X825525Y1472542D01*
X825775Y1472792D01*
X826067Y1472958D01*
X826400Y1473000D01*
X826733Y1472958D01*
X827025Y1472792D01*
X827275Y1472542D01*
X827442Y1472250D01*
X827525Y1471917D01*
Y1471583D01*
X827442Y1471250D01*
X827275Y1470958D01*
X827025Y1470708D01*
X826733Y1470542D01*
X826400Y1470500D01*
G01X826733Y1471167D02*
X827233Y1470500D01*
G01X828583Y1470875D02*
X828833Y1470667D01*
X829125Y1470542D01*
X829500Y1470500D01*
X829875Y1470583D01*
X830167Y1470750D01*
X830375Y1471042D01*
X830417Y1471375D01*
X830333Y1471708D01*
X830125Y1471917D01*
X829833Y1472083D01*
X829542Y1472125D01*
X829250Y1472083D01*
X828875Y1471917D01*
X829000Y1473000D01*
X830125D01*
G01X832600D02*
X832267Y1472917D01*
X832017Y1472708D01*
X831850Y1472458D01*
X831725Y1472125D01*
X831683Y1471750D01*
X831725Y1471375D01*
X831850Y1471042D01*
X832017Y1470792D01*
X832267Y1470583D01*
X832600Y1470500D01*
X832933Y1470583D01*
X833183Y1470792D01*
X833350Y1471042D01*
X833475Y1471375D01*
X833517Y1471750D01*
X833475Y1472125D01*
X833350Y1472458D01*
X833183Y1472708D01*
X832933Y1472917D01*
X832600Y1473000D01*
G01X843400Y1475800D02*
Y1489800D01*
G01X830400Y1475800D02*
X843400D01*
G01X830400Y1489800D02*
Y1475800D01*
G01X843400Y1489800D02*
X830400D01*
G01X834327Y1508096D02*
Y1495096D01*
G01X860327Y1508096D02*
X834327D01*
G01Y1495096D02*
X860327D01*
G01X844977Y1509546D02*
Y1519046D01*
X827277D01*
Y1509546D01*
X844977D01*
G01X838827Y1540796D02*
Y1527796D01*
G01D02*
X864827D01*
G01X827671Y1569704D02*
Y1530904D01*
G01X837827Y1538096D02*
Y1532596D01*
G01X829827D02*
Y1538096D01*
G01Y1520496D02*
Y1525996D01*
G01X837827Y1520496D02*
X829827D01*
G01X837827Y1525996D02*
Y1520496D01*
G01X839658Y1522000D02*
Y1524500D01*
X841242D01*
G01X840658Y1523292D02*
X839658D01*
G01X842633Y1522500D02*
X842883Y1522208D01*
X843217Y1522042D01*
X843592Y1522000D01*
X843925Y1522042D01*
X844258Y1522250D01*
X844467Y1522500D01*
X844508Y1522750D01*
X844425Y1523042D01*
X844133Y1523250D01*
X843842Y1523333D01*
X843467D01*
G01X843842D02*
X844092Y1523458D01*
X844300Y1523667D01*
X844383Y1523917D01*
X844300Y1524167D01*
X844092Y1524375D01*
X843717Y1524500D01*
X843342Y1524458D01*
X842967Y1524292D01*
G01X864827Y1540796D02*
X838827D01*
G01X829827Y1538096D02*
X837827D01*
G01X837500Y1542000D02*
Y1547500D01*
G01X845500Y1542000D02*
X837500D01*
G01Y1554100D02*
Y1559600D01*
G01X836800Y1542000D02*
Y1559600D01*
G01X828800Y1542000D02*
X836800D01*
G01X828800Y1559600D02*
Y1542000D01*
G01X840208Y1563467D02*
X840083Y1563217D01*
X840000Y1562925D01*
Y1562592D01*
X840125Y1562217D01*
X840333Y1561925D01*
X840583Y1561717D01*
X841000Y1561550D01*
X841375Y1561508D01*
X841750Y1561592D01*
X842000Y1561717D01*
X842250Y1561967D01*
X842417Y1562258D01*
X842500Y1562550D01*
Y1562842D01*
X842417Y1563133D01*
X842292Y1563383D01*
X842125Y1563592D01*
G01X842500Y1565650D02*
X840000D01*
X840500Y1565150D01*
G01X842500D02*
Y1566150D01*
G01X840417Y1567958D02*
X840167Y1568208D01*
X840042Y1568500D01*
X840000Y1568833D01*
X840083Y1569250D01*
X840292Y1569542D01*
X840542Y1569625D01*
X840792Y1569583D01*
X841000Y1569417D01*
X841417Y1568583D01*
X841708Y1568208D01*
X842125Y1567958D01*
X842500Y1567875D01*
Y1569625D01*
G01Y1571767D02*
X841958Y1571850D01*
X841500Y1571975D01*
X841083Y1572142D01*
X840625Y1572350D01*
X840000Y1572683D01*
Y1571017D01*
G01X837500Y1559600D02*
X845500D01*
G01X835000Y1563517D02*
X832500D01*
Y1564558D01*
X832625Y1564892D01*
X832792Y1565100D01*
X833125Y1565183D01*
X833458Y1565100D01*
X833667Y1564850D01*
X833792Y1564558D01*
Y1563517D01*
G01Y1564558D02*
X835000Y1565183D01*
G01X834625Y1566533D02*
X834833Y1566783D01*
X834958Y1567075D01*
X835000Y1567450D01*
X834917Y1567825D01*
X834750Y1568117D01*
X834458Y1568325D01*
X834125Y1568367D01*
X833792Y1568283D01*
X833583Y1568075D01*
X833417Y1567783D01*
X833375Y1567492D01*
X833417Y1567200D01*
X833583Y1566825D01*
X832500Y1566950D01*
Y1568075D01*
G01X835000Y1570550D02*
X832500D01*
X833000Y1570050D01*
G01X835000D02*
Y1571050D01*
G01X834500Y1572733D02*
X834792Y1572983D01*
X834958Y1573317D01*
X835000Y1573692D01*
X834958Y1574025D01*
X834750Y1574358D01*
X834500Y1574567D01*
X834250Y1574608D01*
X833958Y1574525D01*
X833750Y1574233D01*
X833667Y1573942D01*
Y1573567D01*
G01Y1573942D02*
X833542Y1574192D01*
X833333Y1574400D01*
X833083Y1574483D01*
X832833Y1574400D01*
X832625Y1574192D01*
X832500Y1573817D01*
X832542Y1573442D01*
X832708Y1573067D01*
G01X836800Y1559600D02*
X828800D01*
G01X839800Y1635133D02*
X841133Y1634300D01*
X842633Y1633800D01*
X843967D01*
X845300Y1634300D01*
X846300Y1635133D01*
X846800Y1636300D01*
X846467Y1637466D01*
X845633Y1638467D01*
X844133Y1639133D01*
X842133Y1639467D01*
X840967Y1640133D01*
X840467Y1641300D01*
X840800Y1642467D01*
X841633Y1643300D01*
X842800Y1643800D01*
X843967D01*
X845133Y1643467D01*
X846133Y1642633D01*
G01X853900Y1643800D02*
Y1633800D01*
G01X850067Y1643800D02*
X857733D01*
G01X861167Y1633800D02*
Y1643800D01*
X865333D01*
X866667Y1643300D01*
X867500Y1642633D01*
X867833Y1641300D01*
X867500Y1639967D01*
X866500Y1639133D01*
X865333Y1638633D01*
X861167D01*
G01X865333D02*
X867833Y1633800D01*
G01X870933D02*
X875100Y1643800D01*
X879267Y1633800D01*
G01X877767Y1637300D02*
X872433D01*
G01X882033Y1633800D02*
Y1643800D01*
X885367D01*
X886700Y1643300D01*
X887700Y1642633D01*
X888533Y1641633D01*
X889200Y1640466D01*
X889367Y1638800D01*
X889200Y1637133D01*
X888533Y1635967D01*
X887700Y1634966D01*
X886700Y1634300D01*
X885367Y1633800D01*
X882033D01*
G01X892633D02*
Y1643800D01*
X895967D01*
X897300Y1643300D01*
X898300Y1642633D01*
X899133Y1641633D01*
X899800Y1640466D01*
X899967Y1638800D01*
X899800Y1637133D01*
X899133Y1635967D01*
X898300Y1634966D01*
X897300Y1634300D01*
X895967Y1633800D01*
X892633D01*
G01X903567Y1643800D02*
Y1633800D01*
X910233D01*
G01X920833D02*
X914167D01*
Y1643800D01*
X920833D01*
G01X918167Y1638967D02*
X914167D01*
G01X942367Y1642967D02*
X941367Y1643467D01*
X940200Y1643800D01*
X938867D01*
X937366Y1643300D01*
X936200Y1642467D01*
X935367Y1641467D01*
X934700Y1639800D01*
X934533Y1638300D01*
X934867Y1636800D01*
X935367Y1635800D01*
X936367Y1634800D01*
X937533Y1634133D01*
X938700Y1633800D01*
X939867D01*
X941033Y1634133D01*
X942033Y1634633D01*
X942867Y1635300D01*
G01X949300Y1633800D02*
X947966Y1633967D01*
X946800Y1634633D01*
X945800Y1635633D01*
X945133Y1636800D01*
X944800Y1638133D01*
Y1639467D01*
X945133Y1640800D01*
X945800Y1641967D01*
X946800Y1642967D01*
X947966Y1643633D01*
X949300Y1643800D01*
X950633Y1643633D01*
X951800Y1642967D01*
X952800Y1641967D01*
X953467Y1640800D01*
X953800Y1639467D01*
Y1638133D01*
X953467Y1636800D01*
X952800Y1635633D01*
X951800Y1634633D01*
X950633Y1633967D01*
X949300Y1633800D01*
G01X956067D02*
Y1643800D01*
X963733Y1633800D01*
Y1643800D01*
G01X966667Y1633800D02*
Y1643800D01*
X974333Y1633800D01*
Y1643800D01*
G01X824917Y1714400D02*
Y1716900D01*
X825917D01*
X826250Y1716775D01*
X826500Y1716483D01*
X826583Y1716150D01*
X826500Y1715817D01*
X826292Y1715567D01*
X825917Y1715442D01*
X824917D01*
G01X829767Y1716692D02*
X829517Y1716817D01*
X829225Y1716900D01*
X828892D01*
X828517Y1716775D01*
X828225Y1716567D01*
X828017Y1716317D01*
X827850Y1715900D01*
X827808Y1715525D01*
X827892Y1715150D01*
X828017Y1714900D01*
X828267Y1714650D01*
X828558Y1714483D01*
X828850Y1714400D01*
X829142D01*
X829433Y1714483D01*
X829683Y1714608D01*
X829892Y1714775D01*
G01X832450Y1714400D02*
Y1716900D01*
X830908Y1715108D01*
X832992D01*
G01X834133Y1714900D02*
X834383Y1714608D01*
X834717Y1714442D01*
X835092Y1714400D01*
X835425Y1714442D01*
X835758Y1714650D01*
X835967Y1714900D01*
X836008Y1715150D01*
X835925Y1715442D01*
X835633Y1715650D01*
X835342Y1715733D01*
X834967D01*
G01X835342D02*
X835592Y1715858D01*
X835800Y1716067D01*
X835883Y1716317D01*
X835800Y1716567D01*
X835592Y1716775D01*
X835217Y1716900D01*
X834842Y1716858D01*
X834467Y1716692D01*
G01X839600Y1722200D02*
X834100D01*
G01X839600Y1730200D02*
Y1722200D01*
G01X860665Y1737100D02*
X867301Y1730464D01*
Y1713036D01*
X860665Y1706400D01*
X847537D01*
X840901Y1713036D01*
Y1730464D01*
X847537Y1737100D01*
X860665D01*
G01X834100Y1730200D02*
X839600D01*
G01X838800Y1738000D02*
Y1731000D01*
X825400D01*
Y1738000D01*
X838800D01*
G01X834499Y1765067D02*
X831999D01*
Y1766108D01*
X832124Y1766442D01*
X832291Y1766650D01*
X832624Y1766733D01*
X832957Y1766650D01*
X833166Y1766400D01*
X833291Y1766108D01*
Y1765067D01*
G01Y1766108D02*
X834499Y1766733D01*
G01X833999Y1768083D02*
X834291Y1768333D01*
X834457Y1768667D01*
X834499Y1769042D01*
X834457Y1769375D01*
X834249Y1769708D01*
X833999Y1769917D01*
X833749Y1769958D01*
X833457Y1769875D01*
X833249Y1769583D01*
X833166Y1769292D01*
Y1768917D01*
G01Y1769292D02*
X833041Y1769542D01*
X832832Y1769750D01*
X832582Y1769833D01*
X832332Y1769750D01*
X832124Y1769542D01*
X831999Y1769167D01*
X832041Y1768792D01*
X832207Y1768417D01*
G01X832416Y1771308D02*
X832166Y1771558D01*
X832041Y1771850D01*
X831999Y1772183D01*
X832082Y1772600D01*
X832291Y1772892D01*
X832541Y1772975D01*
X832791Y1772933D01*
X832999Y1772767D01*
X833416Y1771933D01*
X833707Y1771558D01*
X834124Y1771308D01*
X834499Y1771225D01*
Y1772975D01*
G01Y1775117D02*
X833957Y1775200D01*
X833499Y1775325D01*
X833082Y1775492D01*
X832624Y1775700D01*
X831999Y1776033D01*
Y1774367D01*
G01X825499Y1765067D02*
X822999D01*
Y1766108D01*
X823124Y1766442D01*
X823291Y1766650D01*
X823624Y1766733D01*
X823957Y1766650D01*
X824166Y1766400D01*
X824291Y1766108D01*
Y1765067D01*
G01Y1766108D02*
X825499Y1766733D01*
G01X824999Y1768083D02*
X825291Y1768333D01*
X825457Y1768667D01*
X825499Y1769042D01*
X825457Y1769375D01*
X825249Y1769708D01*
X824999Y1769917D01*
X824749Y1769958D01*
X824457Y1769875D01*
X824249Y1769583D01*
X824166Y1769292D01*
Y1768917D01*
G01Y1769292D02*
X824041Y1769542D01*
X823832Y1769750D01*
X823582Y1769833D01*
X823332Y1769750D01*
X823124Y1769542D01*
X822999Y1769167D01*
X823041Y1768792D01*
X823207Y1768417D01*
G01X823416Y1771308D02*
X823166Y1771558D01*
X823041Y1771850D01*
X822999Y1772183D01*
X823082Y1772600D01*
X823291Y1772892D01*
X823541Y1772975D01*
X823791Y1772933D01*
X823999Y1772767D01*
X824416Y1771933D01*
X824707Y1771558D01*
X825124Y1771308D01*
X825499Y1771225D01*
Y1772975D01*
G01X825207Y1774492D02*
X825416Y1774783D01*
X825499Y1775117D01*
X825416Y1775450D01*
X825166Y1775742D01*
X824791Y1775950D01*
X824416Y1776033D01*
X823957D01*
X823582Y1775950D01*
X823249Y1775742D01*
X823082Y1775492D01*
X822999Y1775200D01*
X823082Y1774867D01*
X823249Y1774617D01*
X823499Y1774450D01*
X823832Y1774367D01*
X824124Y1774450D01*
X824416Y1774658D01*
X824582Y1774908D01*
X824624Y1775200D01*
X824541Y1775533D01*
X824332Y1775783D01*
X823957Y1776033D01*
G01X831499Y1778350D02*
X835499D01*
Y1785750D01*
G01X834199Y1786050D02*
Y1790050D01*
X826799D01*
G01X844266Y1793342D02*
X844016Y1793467D01*
X843724Y1793550D01*
X843391D01*
X843016Y1793425D01*
X842724Y1793217D01*
X842516Y1792967D01*
X842349Y1792550D01*
X842307Y1792175D01*
X842391Y1791800D01*
X842516Y1791550D01*
X842766Y1791300D01*
X843057Y1791133D01*
X843349Y1791050D01*
X843641D01*
X843932Y1791133D01*
X844182Y1791258D01*
X844391Y1791425D01*
G01X845532Y1791550D02*
X845782Y1791258D01*
X846116Y1791092D01*
X846491Y1791050D01*
X846824Y1791092D01*
X847157Y1791300D01*
X847366Y1791550D01*
X847407Y1791800D01*
X847324Y1792092D01*
X847032Y1792300D01*
X846741Y1792383D01*
X846366D01*
G01X846741D02*
X846991Y1792508D01*
X847199Y1792717D01*
X847282Y1792967D01*
X847199Y1793217D01*
X846991Y1793425D01*
X846616Y1793550D01*
X846241Y1793508D01*
X845866Y1793342D01*
G01X850049Y1791050D02*
Y1793550D01*
X848507Y1791758D01*
X850591D01*
G01X851857Y1793133D02*
X852107Y1793383D01*
X852399Y1793508D01*
X852732Y1793550D01*
X853149Y1793467D01*
X853441Y1793258D01*
X853524Y1793008D01*
X853482Y1792758D01*
X853316Y1792550D01*
X852482Y1792133D01*
X852107Y1791842D01*
X851857Y1791425D01*
X851774Y1791050D01*
X853524D01*
G01X829016D02*
Y1793550D01*
X830057D01*
X830391Y1793425D01*
X830599Y1793258D01*
X830682Y1792925D01*
X830599Y1792592D01*
X830349Y1792383D01*
X830057Y1792258D01*
X829016D01*
G01X830057D02*
X830682Y1791050D01*
G01X832032Y1791550D02*
X832282Y1791258D01*
X832616Y1791092D01*
X832991Y1791050D01*
X833324Y1791092D01*
X833657Y1791300D01*
X833866Y1791550D01*
X833907Y1791800D01*
X833824Y1792092D01*
X833532Y1792300D01*
X833241Y1792383D01*
X832866D01*
G01X833241D02*
X833491Y1792508D01*
X833699Y1792717D01*
X833782Y1792967D01*
X833699Y1793217D01*
X833491Y1793425D01*
X833116Y1793550D01*
X832741Y1793508D01*
X832366Y1793342D01*
G01X835132Y1791550D02*
X835382Y1791258D01*
X835716Y1791092D01*
X836091Y1791050D01*
X836424Y1791092D01*
X836757Y1791300D01*
X836966Y1791550D01*
X837007Y1791800D01*
X836924Y1792092D01*
X836632Y1792300D01*
X836341Y1792383D01*
X835966D01*
G01X836341D02*
X836591Y1792508D01*
X836799Y1792717D01*
X836882Y1792967D01*
X836799Y1793217D01*
X836591Y1793425D01*
X836216Y1793550D01*
X835841Y1793508D01*
X835466Y1793342D01*
G01X839149Y1791050D02*
X839441Y1791092D01*
X839774Y1791217D01*
X839982Y1791425D01*
X840066Y1791717D01*
X839982Y1792008D01*
X839732Y1792258D01*
X839357Y1792383D01*
X838941D01*
X838691Y1792467D01*
X838482Y1792675D01*
X838399Y1792967D01*
X838524Y1793258D01*
X838816Y1793467D01*
X839149Y1793550D01*
X839482Y1793467D01*
X839774Y1793258D01*
X839899Y1792967D01*
X839816Y1792675D01*
X839607Y1792467D01*
X839357Y1792383D01*
X838941D01*
X838566Y1792258D01*
X838316Y1792008D01*
X838232Y1791717D01*
X838316Y1791425D01*
X838524Y1791217D01*
X838857Y1791092D01*
X839149Y1791050D01*
G01X839500Y1802546D02*
X841292D01*
X841667Y1802713D01*
X841917Y1803046D01*
X842000Y1803463D01*
X841917Y1803880D01*
X841667Y1804213D01*
X841292Y1804380D01*
X839500D01*
G01X842000Y1807063D02*
X839500D01*
X841292Y1805521D01*
Y1807605D01*
G01X842000Y1809663D02*
X841958Y1809955D01*
X841833Y1810288D01*
X841625Y1810496D01*
X841333Y1810580D01*
X841042Y1810496D01*
X840792Y1810246D01*
X840667Y1809871D01*
Y1809455D01*
X840583Y1809205D01*
X840375Y1808996D01*
X840083Y1808913D01*
X839792Y1809038D01*
X839583Y1809330D01*
X839500Y1809663D01*
X839583Y1809996D01*
X839792Y1810288D01*
X840083Y1810413D01*
X840375Y1810330D01*
X840583Y1810121D01*
X840667Y1809871D01*
Y1809455D01*
X840792Y1809080D01*
X841042Y1808830D01*
X841333Y1808746D01*
X841625Y1808830D01*
X841833Y1809038D01*
X841958Y1809371D01*
X842000Y1809663D01*
G01X824923Y1811087D02*
Y1803087D01*
X836873D01*
Y1811087D01*
X824923D01*
G01X836873Y1804937D02*
X834873Y1806937D01*
X836873Y1808937D01*
G01X829500Y1866517D02*
X827000D01*
Y1867558D01*
X827125Y1867892D01*
X827292Y1868100D01*
X827625Y1868183D01*
X827958Y1868100D01*
X828167Y1867850D01*
X828292Y1867558D01*
Y1866517D01*
G01Y1867558D02*
X829500Y1868183D01*
G01X829000Y1869533D02*
X829292Y1869783D01*
X829458Y1870117D01*
X829500Y1870492D01*
X829458Y1870825D01*
X829250Y1871158D01*
X829000Y1871367D01*
X828750Y1871408D01*
X828458Y1871325D01*
X828250Y1871033D01*
X828167Y1870742D01*
Y1870367D01*
G01Y1870742D02*
X828042Y1870992D01*
X827833Y1871200D01*
X827583Y1871283D01*
X827333Y1871200D01*
X827125Y1870992D01*
X827000Y1870617D01*
X827042Y1870242D01*
X827208Y1869867D01*
G01X829500Y1874050D02*
X827000D01*
X828792Y1872508D01*
Y1874592D01*
G01X827417Y1875858D02*
X827167Y1876108D01*
X827042Y1876400D01*
X827000Y1876733D01*
X827083Y1877150D01*
X827292Y1877442D01*
X827542Y1877525D01*
X827792Y1877483D01*
X828000Y1877317D01*
X828417Y1876483D01*
X828708Y1876108D01*
X829125Y1875858D01*
X829500Y1875775D01*
Y1877525D01*
G01X825700Y1879300D02*
Y1890700D01*
G01X826000Y1879300D02*
X830000D01*
Y1886700D01*
G01X841400Y1876500D02*
X841067Y1876542D01*
X840775Y1876708D01*
X840525Y1876958D01*
X840358Y1877250D01*
X840275Y1877583D01*
Y1877917D01*
X840358Y1878250D01*
X840525Y1878542D01*
X840775Y1878792D01*
X841067Y1878958D01*
X841400Y1879000D01*
X841733Y1878958D01*
X842025Y1878792D01*
X842275Y1878542D01*
X842442Y1878250D01*
X842525Y1877917D01*
Y1877583D01*
X842442Y1877250D01*
X842275Y1876958D01*
X842025Y1876708D01*
X841733Y1876542D01*
X841400Y1876500D01*
G01X841733Y1877167D02*
X842233Y1876500D01*
G01X845000D02*
Y1879000D01*
X843458Y1877208D01*
X845542D01*
G01X846892Y1876792D02*
X847183Y1876583D01*
X847517Y1876500D01*
X847850Y1876583D01*
X848142Y1876833D01*
X848350Y1877208D01*
X848433Y1877583D01*
Y1878042D01*
X848350Y1878417D01*
X848142Y1878750D01*
X847892Y1878917D01*
X847600Y1879000D01*
X847267Y1878917D01*
X847017Y1878750D01*
X846850Y1878500D01*
X846767Y1878167D01*
X846850Y1877875D01*
X847058Y1877583D01*
X847308Y1877417D01*
X847600Y1877375D01*
X847933Y1877458D01*
X848183Y1877667D01*
X848433Y1878042D01*
G01X830999Y1881550D02*
X843999D01*
G01X830999Y1895550D02*
Y1881550D01*
G01X834564Y1913813D02*
Y1900813D01*
G01D02*
X860564D01*
G01X827658Y1907500D02*
Y1910000D01*
X829242D01*
G01X828658Y1908792D02*
X827658D01*
G01X831550Y1907500D02*
Y1910000D01*
X831050Y1909500D01*
G01Y1907500D02*
X832050D01*
G01X843999Y1895550D02*
X830999D01*
G01X860564Y1913813D02*
X834564D01*
G01X837499Y1947050D02*
Y1934050D01*
G01D02*
X863499D01*
G01X826499Y1973450D02*
Y1934650D01*
G01X828499Y1926750D02*
Y1932250D01*
G01X836499Y1926750D02*
X828499D01*
G01X836499Y1932250D02*
Y1926750D01*
G01X844924Y1915863D02*
Y1925363D01*
X827224D01*
Y1915863D01*
X844924D01*
G01X863499Y1947050D02*
X837499D01*
G01X836400Y1950700D02*
Y1956200D01*
G01X844400Y1950700D02*
X836400D01*
G01X836499Y1944350D02*
Y1938850D01*
G01X828499Y1944350D02*
X836499D01*
G01X828499Y1938850D02*
Y1944350D01*
G01X835600Y1950700D02*
Y1968300D01*
G01X827600Y1950700D02*
X835600D01*
G01X827600Y1968300D02*
Y1950700D01*
G01X839108Y1972167D02*
X838983Y1971917D01*
X838900Y1971625D01*
Y1971292D01*
X839025Y1970917D01*
X839233Y1970625D01*
X839483Y1970417D01*
X839900Y1970250D01*
X840275Y1970208D01*
X840650Y1970292D01*
X840900Y1970417D01*
X841150Y1970667D01*
X841317Y1970958D01*
X841400Y1971250D01*
Y1971542D01*
X841317Y1971833D01*
X841192Y1972083D01*
X841025Y1972292D01*
G01X841400Y1974350D02*
X838900D01*
X839400Y1973850D01*
G01X841400D02*
Y1974850D01*
G01Y1977450D02*
X838900D01*
X839400Y1976950D01*
G01X841400D02*
Y1977950D01*
G01Y1980550D02*
X838900D01*
X839400Y1980050D01*
G01X841400D02*
Y1981050D01*
G01X836400Y1968300D02*
X844400D01*
G01X836400Y1962800D02*
Y1968300D01*
G01X834000Y1971517D02*
X831500D01*
Y1972558D01*
X831625Y1972892D01*
X831792Y1973100D01*
X832125Y1973183D01*
X832458Y1973100D01*
X832667Y1972850D01*
X832792Y1972558D01*
Y1971517D01*
G01Y1972558D02*
X834000Y1973183D01*
G01X833625Y1974533D02*
X833833Y1974783D01*
X833958Y1975075D01*
X834000Y1975450D01*
X833917Y1975825D01*
X833750Y1976117D01*
X833458Y1976325D01*
X833125Y1976367D01*
X832792Y1976283D01*
X832583Y1976075D01*
X832417Y1975783D01*
X832375Y1975492D01*
X832417Y1975200D01*
X832583Y1974825D01*
X831500Y1974950D01*
Y1976075D01*
G01X834000Y1978550D02*
X831500D01*
X832000Y1978050D01*
G01X834000D02*
Y1979050D01*
G01X831917Y1980858D02*
X831667Y1981108D01*
X831542Y1981400D01*
X831500Y1981733D01*
X831583Y1982150D01*
X831792Y1982442D01*
X832042Y1982525D01*
X832292Y1982483D01*
X832500Y1982317D01*
X832917Y1981483D01*
X833208Y1981108D01*
X833625Y1980858D01*
X834000Y1980775D01*
Y1982525D01*
G01X835600Y1968300D02*
X827600D01*
G01X852999Y107850D02*
X870999D01*
G01X852999Y119050D02*
Y107850D01*
G01X850999Y126750D02*
Y121250D01*
G01Y138850D02*
Y133350D01*
G01X852999Y135050D02*
Y146250D01*
G01X857245Y157924D02*
Y160424D01*
X858286D01*
X858620Y160299D01*
X858828Y160132D01*
X858911Y159799D01*
X858828Y159466D01*
X858578Y159257D01*
X858286Y159132D01*
X857245D01*
G01X858286D02*
X858911Y157924D01*
G01X861178D02*
Y160424D01*
X860678Y159924D01*
G01Y157924D02*
X861678D01*
G01X863361Y158299D02*
X863611Y158091D01*
X863903Y157966D01*
X864278Y157924D01*
X864653Y158007D01*
X864945Y158174D01*
X865153Y158466D01*
X865195Y158799D01*
X865111Y159132D01*
X864903Y159341D01*
X864611Y159507D01*
X864320Y159549D01*
X864028Y159507D01*
X863653Y159341D01*
X863778Y160424D01*
X864903D01*
G01X866670Y158216D02*
X866961Y158007D01*
X867295Y157924D01*
X867628Y158007D01*
X867920Y158257D01*
X868128Y158632D01*
X868211Y159007D01*
Y159466D01*
X868128Y159841D01*
X867920Y160174D01*
X867670Y160341D01*
X867378Y160424D01*
X867045Y160341D01*
X866795Y160174D01*
X866628Y159924D01*
X866545Y159591D01*
X866628Y159299D01*
X866836Y159007D01*
X867086Y158841D01*
X867378Y158799D01*
X867711Y158882D01*
X867961Y159091D01*
X868211Y159466D01*
G01X852999Y146250D02*
X870999D01*
G01X857245Y161924D02*
Y164424D01*
X858286D01*
X858620Y164299D01*
X858828Y164132D01*
X858911Y163799D01*
X858828Y163466D01*
X858578Y163257D01*
X858286Y163132D01*
X857245D01*
G01X858286D02*
X858911Y161924D01*
G01X861178D02*
Y164424D01*
X860678Y163924D01*
G01Y161924D02*
X861678D01*
G01X863361Y162299D02*
X863611Y162091D01*
X863903Y161966D01*
X864278Y161924D01*
X864653Y162007D01*
X864945Y162174D01*
X865153Y162466D01*
X865195Y162799D01*
X865111Y163132D01*
X864903Y163341D01*
X864611Y163507D01*
X864320Y163549D01*
X864028Y163507D01*
X863653Y163341D01*
X863778Y164424D01*
X864903D01*
G01X867295Y161924D02*
X867378Y162466D01*
X867503Y162924D01*
X867670Y163341D01*
X867878Y163799D01*
X868211Y164424D01*
X866545D01*
G01X848143Y201293D02*
X845643D01*
Y202334D01*
X845768Y202668D01*
X845935Y202876D01*
X846268Y202959D01*
X846601Y202876D01*
X846810Y202626D01*
X846935Y202334D01*
Y201293D01*
G01Y202334D02*
X848143Y202959D01*
G01X847643Y204309D02*
X847935Y204559D01*
X848101Y204893D01*
X848143Y205268D01*
X848101Y205601D01*
X847893Y205934D01*
X847643Y206143D01*
X847393Y206184D01*
X847101Y206101D01*
X846893Y205809D01*
X846810Y205518D01*
Y205143D01*
G01Y205518D02*
X846685Y205768D01*
X846476Y205976D01*
X846226Y206059D01*
X845976Y205976D01*
X845768Y205768D01*
X845643Y205393D01*
X845685Y205018D01*
X845851Y204643D01*
G01X847643Y207409D02*
X847935Y207659D01*
X848101Y207993D01*
X848143Y208368D01*
X848101Y208701D01*
X847893Y209034D01*
X847643Y209243D01*
X847393Y209284D01*
X847101Y209201D01*
X846893Y208909D01*
X846810Y208618D01*
Y208243D01*
G01Y208618D02*
X846685Y208868D01*
X846476Y209076D01*
X846226Y209159D01*
X845976Y209076D01*
X845768Y208868D01*
X845643Y208493D01*
X845685Y208118D01*
X845851Y207743D01*
G01X845643Y211426D02*
X845726Y211093D01*
X845935Y210843D01*
X846185Y210676D01*
X846518Y210551D01*
X846893Y210509D01*
X847268Y210551D01*
X847601Y210676D01*
X847851Y210843D01*
X848060Y211093D01*
X848143Y211426D01*
X848060Y211759D01*
X847851Y212009D01*
X847601Y212176D01*
X847268Y212301D01*
X846893Y212343D01*
X846518Y212301D01*
X846185Y212176D01*
X845935Y212009D01*
X845726Y211759D01*
X845643Y211426D01*
G01X851017Y262000D02*
Y264500D01*
X852058D01*
X852392Y264375D01*
X852600Y264208D01*
X852683Y263875D01*
X852600Y263542D01*
X852350Y263333D01*
X852058Y263208D01*
X851017D01*
G01X852058D02*
X852683Y262000D01*
G01X854950D02*
Y264500D01*
X854450Y264000D01*
G01Y262000D02*
X855450D01*
G01X857258Y263042D02*
X857550Y263333D01*
X857800Y263500D01*
X858133Y263583D01*
X858425Y263500D01*
X858633Y263333D01*
X858800Y263083D01*
X858842Y262792D01*
X858800Y262542D01*
X858633Y262292D01*
X858383Y262083D01*
X858092Y262000D01*
X857758Y262083D01*
X857467Y262333D01*
X857300Y262708D01*
X857258Y263125D01*
X857342Y263667D01*
X857467Y263958D01*
X857675Y264250D01*
X857967Y264458D01*
X858258Y264500D01*
X858550Y264417D01*
X858758Y264208D01*
G01X860358Y264083D02*
X860608Y264333D01*
X860900Y264458D01*
X861233Y264500D01*
X861650Y264417D01*
X861942Y264208D01*
X862025Y263958D01*
X861983Y263708D01*
X861817Y263500D01*
X860983Y263083D01*
X860608Y262792D01*
X860358Y262375D01*
X860275Y262000D01*
X862025D01*
G01X851017Y258000D02*
Y260500D01*
X852058D01*
X852392Y260375D01*
X852600Y260208D01*
X852683Y259875D01*
X852600Y259542D01*
X852350Y259333D01*
X852058Y259208D01*
X851017D01*
G01X852058D02*
X852683Y258000D01*
G01X854033Y258500D02*
X854283Y258208D01*
X854617Y258042D01*
X854992Y258000D01*
X855325Y258042D01*
X855658Y258250D01*
X855867Y258500D01*
X855908Y258750D01*
X855825Y259042D01*
X855533Y259250D01*
X855242Y259333D01*
X854867D01*
G01X855242D02*
X855492Y259458D01*
X855700Y259667D01*
X855783Y259917D01*
X855700Y260167D01*
X855492Y260375D01*
X855117Y260500D01*
X854742Y260458D01*
X854367Y260292D01*
G01X857967Y258000D02*
X858050Y258542D01*
X858175Y259000D01*
X858342Y259417D01*
X858550Y259875D01*
X858883Y260500D01*
X857217D01*
G01X861650Y258000D02*
Y260500D01*
X860108Y258708D01*
X862192D01*
G01X864499Y285067D02*
X861999D01*
Y286108D01*
X862124Y286442D01*
X862291Y286650D01*
X862624Y286733D01*
X862957Y286650D01*
X863166Y286400D01*
X863291Y286108D01*
Y285067D01*
G01Y286108D02*
X864499Y286733D01*
G01Y289000D02*
X861999D01*
X862499Y288500D01*
G01X864499D02*
Y289500D01*
G01X863457Y291308D02*
X863166Y291600D01*
X862999Y291850D01*
X862916Y292183D01*
X862999Y292475D01*
X863166Y292683D01*
X863416Y292850D01*
X863707Y292892D01*
X863957Y292850D01*
X864207Y292683D01*
X864416Y292433D01*
X864499Y292142D01*
X864416Y291808D01*
X864166Y291517D01*
X863791Y291350D01*
X863374Y291308D01*
X862832Y291392D01*
X862541Y291517D01*
X862249Y291725D01*
X862041Y292017D01*
X861999Y292308D01*
X862082Y292600D01*
X862291Y292808D01*
G01X864499Y295200D02*
X861999D01*
X862499Y294700D01*
G01X864499D02*
Y295700D01*
G01X860228Y283624D02*
Y296624D01*
G01X851200Y274800D02*
Y278800D01*
X843800D01*
G01X864500Y270017D02*
X862000D01*
Y271058D01*
X862125Y271392D01*
X862292Y271600D01*
X862625Y271683D01*
X862958Y271600D01*
X863167Y271350D01*
X863292Y271058D01*
Y270017D01*
G01Y271058D02*
X864500Y271683D01*
G01Y273950D02*
X862000D01*
X862500Y273450D01*
G01X864500D02*
Y274450D01*
G01X863458Y276258D02*
X863167Y276550D01*
X863000Y276800D01*
X862917Y277133D01*
X863000Y277425D01*
X863167Y277633D01*
X863417Y277800D01*
X863708Y277842D01*
X863958Y277800D01*
X864208Y277633D01*
X864417Y277383D01*
X864500Y277092D01*
X864417Y276758D01*
X864167Y276467D01*
X863792Y276300D01*
X863375Y276258D01*
X862833Y276342D01*
X862542Y276467D01*
X862250Y276675D01*
X862042Y276967D01*
X862000Y277258D01*
X862083Y277550D01*
X862292Y277758D01*
G01X864500Y280067D02*
X863958Y280150D01*
X863500Y280275D01*
X863083Y280442D01*
X862625Y280650D01*
X862000Y280983D01*
Y279317D01*
G01X862708Y305767D02*
X862583Y305517D01*
X862500Y305225D01*
Y304892D01*
X862625Y304517D01*
X862833Y304225D01*
X863083Y304017D01*
X863500Y303850D01*
X863875Y303808D01*
X864250Y303892D01*
X864500Y304017D01*
X864750Y304267D01*
X864917Y304558D01*
X865000Y304850D01*
Y305142D01*
X864917Y305433D01*
X864792Y305683D01*
X864625Y305892D01*
G01X865000Y307950D02*
X862500D01*
X863000Y307450D01*
G01X865000D02*
Y308450D01*
G01Y310967D02*
X864458Y311050D01*
X864000Y311175D01*
X863583Y311342D01*
X863125Y311550D01*
X862500Y311883D01*
Y310217D01*
G01X864500Y313233D02*
X864792Y313483D01*
X864958Y313817D01*
X865000Y314192D01*
X864958Y314525D01*
X864750Y314858D01*
X864500Y315067D01*
X864250Y315108D01*
X863958Y315025D01*
X863750Y314733D01*
X863667Y314442D01*
Y314067D01*
G01Y314442D02*
X863542Y314692D01*
X863333Y314900D01*
X863083Y314983D01*
X862833Y314900D01*
X862625Y314692D01*
X862500Y314317D01*
X862542Y313942D01*
X862708Y313567D01*
G01X846999Y298250D02*
Y303750D01*
G01X854999Y298250D02*
X846999D01*
G01X854999Y303750D02*
Y298250D01*
G01X857658Y298500D02*
Y301000D01*
X859242D01*
G01X858658Y299792D02*
X857658D01*
G01X860842Y298792D02*
X861133Y298583D01*
X861467Y298500D01*
X861800Y298583D01*
X862092Y298833D01*
X862300Y299208D01*
X862383Y299583D01*
Y300042D01*
X862300Y300417D01*
X862092Y300750D01*
X861842Y300917D01*
X861550Y301000D01*
X861217Y300917D01*
X860967Y300750D01*
X860800Y300500D01*
X860717Y300167D01*
X860800Y299875D01*
X861008Y299583D01*
X861258Y299417D01*
X861550Y299375D01*
X861883Y299458D01*
X862133Y299667D01*
X862383Y300042D01*
G01X863728Y317424D02*
Y330424D01*
G01X854999Y315850D02*
Y310350D01*
G01X846999Y315850D02*
X854999D01*
G01X846999Y310350D02*
Y315850D01*
G01X844800Y338000D02*
Y332500D01*
G01Y350100D02*
Y344600D01*
G01X845500Y332500D02*
Y338000D01*
G01X853500Y332500D02*
X845500D01*
G01X853500Y338000D02*
Y332500D01*
G01Y350100D02*
Y344600D01*
G01X845500D02*
Y350100D01*
G01X854200Y332500D02*
Y338000D01*
G01X862200Y332500D02*
X854200D01*
G01X862200Y338000D02*
Y332500D01*
G01Y350100D02*
Y344600D01*
G01X854200D02*
Y350100D01*
G01X864129Y351493D02*
X864004Y351243D01*
X863921Y350951D01*
Y350618D01*
X864046Y350243D01*
X864254Y349951D01*
X864504Y349743D01*
X864921Y349576D01*
X865296Y349534D01*
X865671Y349618D01*
X865921Y349743D01*
X866171Y349993D01*
X866338Y350284D01*
X866421Y350576D01*
Y350868D01*
X866338Y351159D01*
X866213Y351409D01*
X866046Y351618D01*
G01X866421Y353676D02*
X863921D01*
X864421Y353176D01*
G01X866421D02*
Y354176D01*
G01Y356693D02*
X865879Y356776D01*
X865421Y356901D01*
X865004Y357068D01*
X864546Y357276D01*
X863921Y357609D01*
Y355943D01*
G01X866129Y359168D02*
X866338Y359459D01*
X866421Y359793D01*
X866338Y360126D01*
X866088Y360418D01*
X865713Y360626D01*
X865338Y360709D01*
X864879D01*
X864504Y360626D01*
X864171Y360418D01*
X864004Y360168D01*
X863921Y359876D01*
X864004Y359543D01*
X864171Y359293D01*
X864421Y359126D01*
X864754Y359043D01*
X865046Y359126D01*
X865338Y359334D01*
X865504Y359584D01*
X865546Y359876D01*
X865463Y360209D01*
X865254Y360459D01*
X864879Y360709D01*
G01X848208Y354467D02*
X848083Y354217D01*
X848000Y353925D01*
Y353592D01*
X848125Y353217D01*
X848333Y352925D01*
X848583Y352717D01*
X849000Y352550D01*
X849375Y352508D01*
X849750Y352592D01*
X850000Y352717D01*
X850250Y352967D01*
X850417Y353258D01*
X850500Y353550D01*
Y353842D01*
X850417Y354133D01*
X850292Y354383D01*
X850125Y354592D01*
G01X850500Y356650D02*
X848000D01*
X848500Y356150D01*
G01X850500D02*
Y357150D01*
G01Y359667D02*
X849958Y359750D01*
X849500Y359875D01*
X849083Y360042D01*
X848625Y360250D01*
X848000Y360583D01*
Y358917D01*
G01X849458Y362058D02*
X849167Y362350D01*
X849000Y362600D01*
X848917Y362933D01*
X849000Y363225D01*
X849167Y363433D01*
X849417Y363600D01*
X849708Y363642D01*
X849958Y363600D01*
X850208Y363433D01*
X850417Y363183D01*
X850500Y362892D01*
X850417Y362558D01*
X850167Y362267D01*
X849792Y362100D01*
X849375Y362058D01*
X848833Y362142D01*
X848542Y362267D01*
X848250Y362475D01*
X848042Y362767D01*
X848000Y363058D01*
X848083Y363350D01*
X848292Y363558D01*
G01X845500Y350100D02*
X853500D01*
G01X856908Y354467D02*
X856783Y354217D01*
X856700Y353925D01*
Y353592D01*
X856825Y353217D01*
X857033Y352925D01*
X857283Y352717D01*
X857700Y352550D01*
X858075Y352508D01*
X858450Y352592D01*
X858700Y352717D01*
X858950Y352967D01*
X859117Y353258D01*
X859200Y353550D01*
Y353842D01*
X859117Y354133D01*
X858992Y354383D01*
X858825Y354592D01*
G01X859200Y356650D02*
X856700D01*
X857200Y356150D01*
G01X859200D02*
Y357150D01*
G01Y359667D02*
X858658Y359750D01*
X858200Y359875D01*
X857783Y360042D01*
X857325Y360250D01*
X856700Y360583D01*
Y358917D01*
G01X859200Y362767D02*
X858658Y362850D01*
X858200Y362975D01*
X857783Y363142D01*
X857325Y363350D01*
X856700Y363683D01*
Y362017D01*
G01X854200Y350100D02*
X862200D01*
G01X860499Y535550D02*
Y545550D01*
G01X867499D02*
Y535550D01*
G01Y540550D02*
X860499D01*
G01X870932Y535550D02*
Y545550D01*
X874266D01*
X875599Y545050D01*
X876599Y544383D01*
X877432Y543383D01*
X878099Y542216D01*
X878266Y540550D01*
X878099Y538883D01*
X877432Y537717D01*
X876599Y536716D01*
X875599Y536050D01*
X874266Y535550D01*
X870932D01*
G01X881532D02*
Y545550D01*
X884866D01*
X886199Y545050D01*
X887199Y544383D01*
X888032Y543383D01*
X888699Y542216D01*
X888866Y540550D01*
X888699Y538883D01*
X888032Y537717D01*
X887199Y536716D01*
X886199Y536050D01*
X884866Y535550D01*
X881532D01*
G01X892132Y537550D02*
X893132Y536383D01*
X894465Y535717D01*
X895966Y535550D01*
X897299Y535717D01*
X898632Y536550D01*
X899466Y537550D01*
X899632Y538550D01*
X899299Y539716D01*
X898132Y540550D01*
X896966Y540883D01*
X895466D01*
G01X896966D02*
X897966Y541383D01*
X898799Y542216D01*
X899132Y543217D01*
X898799Y544217D01*
X897966Y545050D01*
X896466Y545550D01*
X894966Y545383D01*
X893466Y544717D01*
G01X901399Y532217D02*
X911399D01*
G01X913666Y545550D02*
Y535550D01*
X920332D01*
G01X930932D02*
X924266D01*
Y545550D01*
X930932D01*
G01X928266Y540717D02*
X924266D01*
G01X934532Y535550D02*
Y545550D01*
X937866D01*
X939199Y545050D01*
X940199Y544383D01*
X941032Y543383D01*
X941699Y542216D01*
X941866Y540550D01*
X941699Y538883D01*
X941032Y537717D01*
X940199Y536716D01*
X939199Y536050D01*
X937866Y535550D01*
X934532D01*
G01X857517Y663000D02*
Y665500D01*
X858558D01*
X858892Y665375D01*
X859100Y665208D01*
X859183Y664875D01*
X859100Y664542D01*
X858850Y664333D01*
X858558Y664208D01*
X857517D01*
G01X858558D02*
X859183Y663000D01*
G01X860533Y663500D02*
X860783Y663208D01*
X861117Y663042D01*
X861492Y663000D01*
X861825Y663042D01*
X862158Y663250D01*
X862367Y663500D01*
X862408Y663750D01*
X862325Y664042D01*
X862033Y664250D01*
X861742Y664333D01*
X861367D01*
G01X861742D02*
X861992Y664458D01*
X862200Y664667D01*
X862283Y664917D01*
X862200Y665167D01*
X861992Y665375D01*
X861617Y665500D01*
X861242Y665458D01*
X860867Y665292D01*
G01X863758Y664042D02*
X864050Y664333D01*
X864300Y664500D01*
X864633Y664583D01*
X864925Y664500D01*
X865133Y664333D01*
X865300Y664083D01*
X865342Y663792D01*
X865300Y663542D01*
X865133Y663292D01*
X864883Y663083D01*
X864592Y663000D01*
X864258Y663083D01*
X863967Y663333D01*
X863800Y663708D01*
X863758Y664125D01*
X863842Y664667D01*
X863967Y664958D01*
X864175Y665250D01*
X864467Y665458D01*
X864758Y665500D01*
X865050Y665417D01*
X865258Y665208D01*
G01X866942Y663292D02*
X867233Y663083D01*
X867567Y663000D01*
X867900Y663083D01*
X868192Y663333D01*
X868400Y663708D01*
X868483Y664083D01*
Y664542D01*
X868400Y664917D01*
X868192Y665250D01*
X867942Y665417D01*
X867650Y665500D01*
X867317Y665417D01*
X867067Y665250D01*
X866900Y665000D01*
X866817Y664667D01*
X866900Y664375D01*
X867108Y664083D01*
X867358Y663917D01*
X867650Y663875D01*
X867983Y663958D01*
X868233Y664167D01*
X868483Y664542D01*
G01X865768Y686581D02*
X863268D01*
Y687622D01*
X863393Y687956D01*
X863560Y688164D01*
X863893Y688247D01*
X864226Y688164D01*
X864435Y687914D01*
X864560Y687622D01*
Y686581D01*
G01Y687622D02*
X865768Y688247D01*
G01Y690514D02*
X863268D01*
X863768Y690014D01*
G01X865768D02*
Y691014D01*
G01X865393Y692697D02*
X865601Y692947D01*
X865726Y693239D01*
X865768Y693614D01*
X865685Y693989D01*
X865518Y694281D01*
X865226Y694489D01*
X864893Y694531D01*
X864560Y694447D01*
X864351Y694239D01*
X864185Y693947D01*
X864143Y693656D01*
X864185Y693364D01*
X864351Y692989D01*
X863268Y693114D01*
Y694239D01*
G01X865768Y696714D02*
X863268D01*
X863768Y696214D01*
G01X865768D02*
Y697214D01*
G01X858446Y684682D02*
Y697682D01*
G01X857517Y667000D02*
Y669500D01*
X858558D01*
X858892Y669375D01*
X859100Y669208D01*
X859183Y668875D01*
X859100Y668542D01*
X858850Y668333D01*
X858558Y668208D01*
X857517D01*
G01X858558D02*
X859183Y667000D01*
G01X861450D02*
Y669500D01*
X860950Y669000D01*
G01Y667000D02*
X861950D01*
G01X863633Y667375D02*
X863883Y667167D01*
X864175Y667042D01*
X864550Y667000D01*
X864925Y667083D01*
X865217Y667250D01*
X865425Y667542D01*
X865467Y667875D01*
X865383Y668208D01*
X865175Y668417D01*
X864883Y668583D01*
X864592Y668625D01*
X864300Y668583D01*
X863925Y668417D01*
X864050Y669500D01*
X865175D01*
G01X867650D02*
X867317Y669417D01*
X867067Y669208D01*
X866900Y668958D01*
X866775Y668625D01*
X866733Y668250D01*
X866775Y667875D01*
X866900Y667542D01*
X867067Y667292D01*
X867317Y667083D01*
X867650Y667000D01*
X867983Y667083D01*
X868233Y667292D01*
X868400Y667542D01*
X868525Y667875D01*
X868567Y668250D01*
X868525Y668625D01*
X868400Y668958D01*
X868233Y669208D01*
X867983Y669417D01*
X867650Y669500D01*
G01X863500Y672017D02*
X861000D01*
Y673058D01*
X861125Y673392D01*
X861292Y673600D01*
X861625Y673683D01*
X861958Y673600D01*
X862167Y673350D01*
X862292Y673058D01*
Y672017D01*
G01Y673058D02*
X863500Y673683D01*
G01Y675950D02*
X861000D01*
X861500Y675450D01*
G01X863500D02*
Y676450D01*
G01X863125Y678133D02*
X863333Y678383D01*
X863458Y678675D01*
X863500Y679050D01*
X863417Y679425D01*
X863250Y679717D01*
X862958Y679925D01*
X862625Y679967D01*
X862292Y679883D01*
X862083Y679675D01*
X861917Y679383D01*
X861875Y679092D01*
X861917Y678800D01*
X862083Y678425D01*
X861000Y678550D01*
Y679675D01*
G01X861417Y681358D02*
X861167Y681608D01*
X861042Y681900D01*
X861000Y682233D01*
X861083Y682650D01*
X861292Y682942D01*
X861542Y683025D01*
X861792Y682983D01*
X862000Y682817D01*
X862417Y681983D01*
X862708Y681608D01*
X863125Y681358D01*
X863500Y681275D01*
Y683025D01*
G01X859500Y704350D02*
X862000D01*
G01X859500Y703392D02*
Y705308D01*
G01X862000Y706617D02*
X859500D01*
Y707617D01*
X859625Y707950D01*
X859917Y708200D01*
X860250Y708283D01*
X860583Y708200D01*
X860833Y707992D01*
X860958Y707617D01*
Y706617D01*
G01X859917Y709758D02*
X859667Y710008D01*
X859542Y710300D01*
X859500Y710633D01*
X859583Y711050D01*
X859792Y711342D01*
X860042Y711425D01*
X860292Y711383D01*
X860500Y711217D01*
X860917Y710383D01*
X861208Y710008D01*
X861625Y709758D01*
X862000Y709675D01*
Y711425D01*
G01Y713650D02*
X861958Y713942D01*
X861833Y714275D01*
X861625Y714483D01*
X861333Y714567D01*
X861042Y714483D01*
X860792Y714233D01*
X860667Y713858D01*
Y713442D01*
X860583Y713192D01*
X860375Y712983D01*
X860083Y712900D01*
X859792Y713025D01*
X859583Y713317D01*
X859500Y713650D01*
X859583Y713983D01*
X859792Y714275D01*
X860083Y714400D01*
X860375Y714317D01*
X860583Y714108D01*
X860667Y713858D01*
Y713442D01*
X860792Y713067D01*
X861042Y712817D01*
X861333Y712733D01*
X861625Y712817D01*
X861833Y713025D01*
X861958Y713358D01*
X862000Y713650D01*
G01X863708Y705267D02*
X863583Y705017D01*
X863500Y704725D01*
Y704392D01*
X863625Y704017D01*
X863833Y703725D01*
X864083Y703517D01*
X864500Y703350D01*
X864875Y703308D01*
X865250Y703392D01*
X865500Y703517D01*
X865750Y703767D01*
X865917Y704058D01*
X866000Y704350D01*
Y704642D01*
X865917Y704933D01*
X865792Y705183D01*
X865625Y705392D01*
G01X866000Y707450D02*
X863500D01*
X864000Y706950D01*
G01X866000D02*
Y707950D01*
G01X865625Y709633D02*
X865833Y709883D01*
X865958Y710175D01*
X866000Y710550D01*
X865917Y710925D01*
X865750Y711217D01*
X865458Y711425D01*
X865125Y711467D01*
X864792Y711383D01*
X864583Y711175D01*
X864417Y710883D01*
X864375Y710592D01*
X864417Y710300D01*
X864583Y709925D01*
X863500Y710050D01*
Y711175D01*
G01X865625Y712733D02*
X865833Y712983D01*
X865958Y713275D01*
X866000Y713650D01*
X865917Y714025D01*
X865750Y714317D01*
X865458Y714525D01*
X865125Y714567D01*
X864792Y714483D01*
X864583Y714275D01*
X864417Y713983D01*
X864375Y713692D01*
X864417Y713400D01*
X864583Y713025D01*
X863500Y713150D01*
Y714275D01*
G01X844696Y699582D02*
Y705082D01*
G01X852696Y699582D02*
X844696D01*
G01X852696Y705082D02*
Y699582D01*
G01X865999Y719567D02*
X863499D01*
Y720608D01*
X863624Y720942D01*
X863791Y721150D01*
X864124Y721233D01*
X864457Y721150D01*
X864666Y720900D01*
X864791Y720608D01*
Y719567D01*
G01Y720608D02*
X865999Y721233D01*
G01Y723500D02*
X863499D01*
X863999Y723000D01*
G01X865999D02*
Y724000D01*
G01X865624Y725683D02*
X865832Y725933D01*
X865957Y726225D01*
X865999Y726600D01*
X865916Y726975D01*
X865749Y727267D01*
X865457Y727475D01*
X865124Y727517D01*
X864791Y727433D01*
X864582Y727225D01*
X864416Y726933D01*
X864374Y726642D01*
X864416Y726350D01*
X864582Y725975D01*
X863499Y726100D01*
Y727225D01*
G01X865999Y730200D02*
X863499D01*
X865291Y728658D01*
Y730742D01*
G01X861499Y718050D02*
Y731050D01*
G01X852696Y717182D02*
Y711682D01*
G01X844696Y717182D02*
X852696D01*
G01X844696Y711682D02*
Y717182D01*
G01X861907Y752517D02*
X861782Y752267D01*
X861699Y751975D01*
Y751642D01*
X861824Y751267D01*
X862032Y750975D01*
X862282Y750767D01*
X862699Y750600D01*
X863074Y750558D01*
X863449Y750642D01*
X863699Y750767D01*
X863949Y751017D01*
X864116Y751308D01*
X864199Y751600D01*
Y751892D01*
X864116Y752183D01*
X863991Y752433D01*
X863824Y752642D01*
G01X864199Y754700D02*
X861699D01*
X862199Y754200D01*
G01X864199D02*
Y755200D01*
G01X863157Y757008D02*
X862866Y757300D01*
X862699Y757550D01*
X862616Y757883D01*
X862699Y758175D01*
X862866Y758383D01*
X863116Y758550D01*
X863407Y758592D01*
X863657Y758550D01*
X863907Y758383D01*
X864116Y758133D01*
X864199Y757842D01*
X864116Y757508D01*
X863866Y757217D01*
X863491Y757050D01*
X863074Y757008D01*
X862532Y757092D01*
X862241Y757217D01*
X861949Y757425D01*
X861741Y757717D01*
X861699Y758008D01*
X861782Y758300D01*
X861991Y758508D01*
G01X863699Y759983D02*
X863991Y760233D01*
X864157Y760567D01*
X864199Y760942D01*
X864157Y761275D01*
X863949Y761608D01*
X863699Y761817D01*
X863449Y761858D01*
X863157Y761775D01*
X862949Y761483D01*
X862866Y761192D01*
Y760817D01*
G01Y761192D02*
X862741Y761442D01*
X862532Y761650D01*
X862282Y761733D01*
X862032Y761650D01*
X861824Y761442D01*
X861699Y761067D01*
X861741Y760692D01*
X861907Y760317D01*
G01X851496Y738782D02*
Y733282D01*
G01Y750882D02*
Y745382D01*
G01X852196Y733282D02*
Y738782D01*
G01X860196Y733282D02*
X852196D01*
G01X860196Y738782D02*
Y733282D01*
G01Y750882D02*
Y745382D01*
G01X852196D02*
Y750882D01*
G01X846204Y755249D02*
X846079Y754999D01*
X845996Y754707D01*
Y754374D01*
X846121Y753999D01*
X846329Y753707D01*
X846579Y753499D01*
X846996Y753332D01*
X847371Y753290D01*
X847746Y753374D01*
X847996Y753499D01*
X848246Y753749D01*
X848413Y754040D01*
X848496Y754332D01*
Y754624D01*
X848413Y754915D01*
X848288Y755165D01*
X848121Y755374D01*
G01X848496Y757432D02*
X845996D01*
X846496Y756932D01*
G01X848496D02*
Y757932D01*
G01X847454Y759740D02*
X847163Y760032D01*
X846996Y760282D01*
X846913Y760615D01*
X846996Y760907D01*
X847163Y761115D01*
X847413Y761282D01*
X847704Y761324D01*
X847954Y761282D01*
X848204Y761115D01*
X848413Y760865D01*
X848496Y760574D01*
X848413Y760240D01*
X848163Y759949D01*
X847788Y759782D01*
X847371Y759740D01*
X846829Y759824D01*
X846538Y759949D01*
X846246Y760157D01*
X846038Y760449D01*
X845996Y760740D01*
X846079Y761032D01*
X846288Y761240D01*
G01X848496Y763632D02*
X845996D01*
X846496Y763132D01*
G01X848496D02*
Y764132D01*
G01X854904Y755249D02*
X854779Y754999D01*
X854696Y754707D01*
Y754374D01*
X854821Y753999D01*
X855029Y753707D01*
X855279Y753499D01*
X855696Y753332D01*
X856071Y753290D01*
X856446Y753374D01*
X856696Y753499D01*
X856946Y753749D01*
X857113Y754040D01*
X857196Y754332D01*
Y754624D01*
X857113Y754915D01*
X856988Y755165D01*
X856821Y755374D01*
G01X857196Y757432D02*
X854696D01*
X855196Y756932D01*
G01X857196D02*
Y757932D01*
G01X856154Y759740D02*
X855863Y760032D01*
X855696Y760282D01*
X855613Y760615D01*
X855696Y760907D01*
X855863Y761115D01*
X856113Y761282D01*
X856404Y761324D01*
X856654Y761282D01*
X856904Y761115D01*
X857113Y760865D01*
X857196Y760574D01*
X857113Y760240D01*
X856863Y759949D01*
X856488Y759782D01*
X856071Y759740D01*
X855529Y759824D01*
X855238Y759949D01*
X854946Y760157D01*
X854738Y760449D01*
X854696Y760740D01*
X854779Y761032D01*
X854988Y761240D01*
G01X855113Y762840D02*
X854863Y763090D01*
X854738Y763382D01*
X854696Y763715D01*
X854779Y764132D01*
X854988Y764424D01*
X855238Y764507D01*
X855488Y764465D01*
X855696Y764299D01*
X856113Y763465D01*
X856404Y763090D01*
X856821Y762840D01*
X857196Y762757D01*
Y764507D01*
G01X852196Y750882D02*
X860196D01*
G01X861999Y937550D02*
Y947550D01*
G01X868999D02*
Y937550D01*
G01Y942550D02*
X861999D01*
G01X872432Y937550D02*
Y947550D01*
X875766D01*
X877099Y947050D01*
X878099Y946383D01*
X878932Y945383D01*
X879599Y944216D01*
X879766Y942550D01*
X879599Y940883D01*
X878932Y939717D01*
X878099Y938716D01*
X877099Y938050D01*
X875766Y937550D01*
X872432D01*
G01X883032D02*
Y947550D01*
X886366D01*
X887699Y947050D01*
X888699Y946383D01*
X889532Y945383D01*
X890199Y944216D01*
X890366Y942550D01*
X890199Y940883D01*
X889532Y939717D01*
X888699Y938716D01*
X887699Y938050D01*
X886366Y937550D01*
X883032D01*
G01X894132Y945883D02*
X895132Y946883D01*
X896299Y947383D01*
X897632Y947550D01*
X899299Y947217D01*
X900466Y946383D01*
X900799Y945383D01*
X900632Y944383D01*
X899966Y943550D01*
X896632Y941883D01*
X895132Y940717D01*
X894132Y939050D01*
X893799Y937550D01*
X900799D01*
G01X902899Y934217D02*
X912899D01*
G01X915166Y947550D02*
Y937550D01*
X921832D01*
G01X932432D02*
X925766D01*
Y947550D01*
X932432D01*
G01X929766Y942717D02*
X925766D01*
G01X936032Y937550D02*
Y947550D01*
X939366D01*
X940699Y947050D01*
X941699Y946383D01*
X942532Y945383D01*
X943199Y944216D01*
X943366Y942550D01*
X943199Y940883D01*
X942532Y939717D01*
X941699Y938716D01*
X940699Y938050D01*
X939366Y937550D01*
X936032D01*
G01X853600Y1053184D02*
X853350Y1053309D01*
X853058Y1053392D01*
X852725D01*
X852350Y1053267D01*
X852058Y1053059D01*
X851850Y1052809D01*
X851683Y1052392D01*
X851641Y1052017D01*
X851725Y1051642D01*
X851850Y1051392D01*
X852100Y1051142D01*
X852391Y1050975D01*
X852683Y1050892D01*
X852975D01*
X853266Y1050975D01*
X853516Y1051100D01*
X853725Y1051267D01*
G01X855783Y1050892D02*
Y1053392D01*
X855283Y1052892D01*
G01Y1050892D02*
X856283D01*
G01X857966Y1051392D02*
X858216Y1051100D01*
X858550Y1050934D01*
X858925Y1050892D01*
X859258Y1050934D01*
X859591Y1051142D01*
X859800Y1051392D01*
X859841Y1051642D01*
X859758Y1051934D01*
X859466Y1052142D01*
X859175Y1052225D01*
X858800D01*
G01X859175D02*
X859425Y1052350D01*
X859633Y1052559D01*
X859716Y1052809D01*
X859633Y1053059D01*
X859425Y1053267D01*
X859050Y1053392D01*
X858675Y1053350D01*
X858300Y1053184D01*
G01X861191Y1051934D02*
X861483Y1052225D01*
X861733Y1052392D01*
X862066Y1052475D01*
X862358Y1052392D01*
X862566Y1052225D01*
X862733Y1051975D01*
X862775Y1051684D01*
X862733Y1051434D01*
X862566Y1051184D01*
X862316Y1050975D01*
X862025Y1050892D01*
X861691Y1050975D01*
X861400Y1051225D01*
X861233Y1051600D01*
X861191Y1052017D01*
X861275Y1052559D01*
X861400Y1052850D01*
X861608Y1053142D01*
X861900Y1053350D01*
X862191Y1053392D01*
X862483Y1053309D01*
X862691Y1053100D01*
G01X853266Y1056842D02*
X853016Y1056967D01*
X852724Y1057050D01*
X852391D01*
X852016Y1056925D01*
X851724Y1056717D01*
X851516Y1056467D01*
X851349Y1056050D01*
X851307Y1055675D01*
X851391Y1055300D01*
X851516Y1055050D01*
X851766Y1054800D01*
X852057Y1054633D01*
X852349Y1054550D01*
X852641D01*
X852932Y1054633D01*
X853182Y1054758D01*
X853391Y1054925D01*
G01X855449Y1054550D02*
Y1057050D01*
X854949Y1056550D01*
G01Y1054550D02*
X855949D01*
G01X857632Y1055050D02*
X857882Y1054758D01*
X858216Y1054592D01*
X858591Y1054550D01*
X858924Y1054592D01*
X859257Y1054800D01*
X859466Y1055050D01*
X859507Y1055300D01*
X859424Y1055592D01*
X859132Y1055800D01*
X858841Y1055883D01*
X858466D01*
G01X858841D02*
X859091Y1056008D01*
X859299Y1056217D01*
X859382Y1056467D01*
X859299Y1056717D01*
X859091Y1056925D01*
X858716Y1057050D01*
X858341Y1057008D01*
X857966Y1056842D01*
G01X861566Y1054550D02*
X861649Y1055092D01*
X861774Y1055550D01*
X861941Y1055967D01*
X862149Y1056425D01*
X862482Y1057050D01*
X860816D01*
G01X864708Y1077267D02*
X864583Y1077017D01*
X864500Y1076725D01*
Y1076392D01*
X864625Y1076017D01*
X864833Y1075725D01*
X865083Y1075517D01*
X865500Y1075350D01*
X865875Y1075308D01*
X866250Y1075392D01*
X866500Y1075517D01*
X866750Y1075767D01*
X866917Y1076058D01*
X867000Y1076350D01*
Y1076642D01*
X866917Y1076933D01*
X866792Y1077183D01*
X866625Y1077392D01*
G01X867000Y1079450D02*
X864500D01*
X865000Y1078950D01*
G01X867000D02*
Y1079950D01*
G01Y1083050D02*
X864500D01*
X866292Y1081508D01*
Y1083592D01*
G01X867000Y1085567D02*
X866458Y1085650D01*
X866000Y1085775D01*
X865583Y1085942D01*
X865125Y1086150D01*
X864500Y1086483D01*
Y1084817D01*
G01X863000Y1075517D02*
X860500D01*
Y1076558D01*
X860625Y1076892D01*
X860792Y1077100D01*
X861125Y1077183D01*
X861458Y1077100D01*
X861667Y1076850D01*
X861792Y1076558D01*
Y1075517D01*
G01Y1076558D02*
X863000Y1077183D01*
G01Y1079450D02*
X860500D01*
X861000Y1078950D01*
G01X863000D02*
Y1079950D01*
G01X862500Y1081633D02*
X862792Y1081883D01*
X862958Y1082217D01*
X863000Y1082592D01*
X862958Y1082925D01*
X862750Y1083258D01*
X862500Y1083467D01*
X862250Y1083508D01*
X861958Y1083425D01*
X861750Y1083133D01*
X861667Y1082842D01*
Y1082467D01*
G01Y1082842D02*
X861542Y1083092D01*
X861333Y1083300D01*
X861083Y1083383D01*
X860833Y1083300D01*
X860625Y1083092D01*
X860500Y1082717D01*
X860542Y1082342D01*
X860708Y1081967D01*
G01X862708Y1084942D02*
X862917Y1085233D01*
X863000Y1085567D01*
X862917Y1085900D01*
X862667Y1086192D01*
X862292Y1086400D01*
X861917Y1086483D01*
X861458D01*
X861083Y1086400D01*
X860750Y1086192D01*
X860583Y1085942D01*
X860500Y1085650D01*
X860583Y1085317D01*
X860750Y1085067D01*
X861000Y1084900D01*
X861333Y1084817D01*
X861625Y1084900D01*
X861917Y1085108D01*
X862083Y1085358D01*
X862125Y1085650D01*
X862042Y1085983D01*
X861833Y1086233D01*
X861458Y1086483D01*
G01X863707Y1110817D02*
X863582Y1110567D01*
X863499Y1110275D01*
Y1109942D01*
X863624Y1109567D01*
X863832Y1109275D01*
X864082Y1109067D01*
X864499Y1108900D01*
X864874Y1108858D01*
X865249Y1108942D01*
X865499Y1109067D01*
X865749Y1109317D01*
X865916Y1109608D01*
X865999Y1109900D01*
Y1110192D01*
X865916Y1110483D01*
X865791Y1110733D01*
X865624Y1110942D01*
G01X865999Y1113000D02*
X863499D01*
X863999Y1112500D01*
G01X865999D02*
Y1113500D01*
G01X865499Y1115183D02*
X865791Y1115433D01*
X865957Y1115767D01*
X865999Y1116142D01*
X865957Y1116475D01*
X865749Y1116808D01*
X865499Y1117017D01*
X865249Y1117058D01*
X864957Y1116975D01*
X864749Y1116683D01*
X864666Y1116392D01*
Y1116017D01*
G01Y1116392D02*
X864541Y1116642D01*
X864332Y1116850D01*
X864082Y1116933D01*
X863832Y1116850D01*
X863624Y1116642D01*
X863499Y1116267D01*
X863541Y1115892D01*
X863707Y1115517D01*
G01X865999Y1119200D02*
X865957Y1119492D01*
X865832Y1119825D01*
X865624Y1120033D01*
X865332Y1120117D01*
X865041Y1120033D01*
X864791Y1119783D01*
X864666Y1119408D01*
Y1118992D01*
X864582Y1118742D01*
X864374Y1118533D01*
X864082Y1118450D01*
X863791Y1118575D01*
X863582Y1118867D01*
X863499Y1119200D01*
X863582Y1119533D01*
X863791Y1119825D01*
X864082Y1119950D01*
X864374Y1119867D01*
X864582Y1119658D01*
X864666Y1119408D01*
Y1118992D01*
X864791Y1118617D01*
X865041Y1118367D01*
X865332Y1118283D01*
X865624Y1118367D01*
X865832Y1118575D01*
X865957Y1118908D01*
X865999Y1119200D01*
G01X858583Y1090192D02*
Y1103192D01*
G01X859208Y1110767D02*
X859083Y1110517D01*
X859000Y1110225D01*
Y1109892D01*
X859125Y1109517D01*
X859333Y1109225D01*
X859583Y1109017D01*
X860000Y1108850D01*
X860375Y1108808D01*
X860750Y1108892D01*
X861000Y1109017D01*
X861250Y1109267D01*
X861417Y1109558D01*
X861500Y1109850D01*
Y1110142D01*
X861417Y1110433D01*
X861292Y1110683D01*
X861125Y1110892D01*
G01X861500Y1112950D02*
X859000D01*
X859500Y1112450D01*
G01X861500D02*
Y1113450D01*
G01X861000Y1115133D02*
X861292Y1115383D01*
X861458Y1115717D01*
X861500Y1116092D01*
X861458Y1116425D01*
X861250Y1116758D01*
X861000Y1116967D01*
X860750Y1117008D01*
X860458Y1116925D01*
X860250Y1116633D01*
X860167Y1116342D01*
Y1115967D01*
G01Y1116342D02*
X860042Y1116592D01*
X859833Y1116800D01*
X859583Y1116883D01*
X859333Y1116800D01*
X859125Y1116592D01*
X859000Y1116217D01*
X859042Y1115842D01*
X859208Y1115467D01*
G01X861208Y1118442D02*
X861417Y1118733D01*
X861500Y1119067D01*
X861417Y1119400D01*
X861167Y1119692D01*
X860792Y1119900D01*
X860417Y1119983D01*
X859958D01*
X859583Y1119900D01*
X859250Y1119692D01*
X859083Y1119442D01*
X859000Y1119150D01*
X859083Y1118817D01*
X859250Y1118567D01*
X859500Y1118400D01*
X859833Y1118317D01*
X860125Y1118400D01*
X860417Y1118608D01*
X860583Y1118858D01*
X860625Y1119150D01*
X860542Y1119483D01*
X860333Y1119733D01*
X859958Y1119983D01*
G01X844413Y1104313D02*
Y1109813D01*
G01X852413Y1104313D02*
X844413D01*
G01X852413Y1109813D02*
Y1104313D01*
G01X866999Y1124067D02*
X864499D01*
Y1125108D01*
X864624Y1125442D01*
X864791Y1125650D01*
X865124Y1125733D01*
X865457Y1125650D01*
X865666Y1125400D01*
X865791Y1125108D01*
Y1124067D01*
G01Y1125108D02*
X866999Y1125733D01*
G01Y1128000D02*
X864499D01*
X864999Y1127500D01*
G01X866999D02*
Y1128500D01*
G01X866499Y1130183D02*
X866791Y1130433D01*
X866957Y1130767D01*
X866999Y1131142D01*
X866957Y1131475D01*
X866749Y1131808D01*
X866499Y1132017D01*
X866249Y1132058D01*
X865957Y1131975D01*
X865749Y1131683D01*
X865666Y1131392D01*
Y1131017D01*
G01Y1131392D02*
X865541Y1131642D01*
X865332Y1131850D01*
X865082Y1131933D01*
X864832Y1131850D01*
X864624Y1131642D01*
X864499Y1131267D01*
X864541Y1130892D01*
X864707Y1130517D01*
G01X866999Y1134200D02*
X866957Y1134492D01*
X866832Y1134825D01*
X866624Y1135033D01*
X866332Y1135117D01*
X866041Y1135033D01*
X865791Y1134783D01*
X865666Y1134408D01*
Y1133992D01*
X865582Y1133742D01*
X865374Y1133533D01*
X865082Y1133450D01*
X864791Y1133575D01*
X864582Y1133867D01*
X864499Y1134200D01*
X864582Y1134533D01*
X864791Y1134825D01*
X865082Y1134950D01*
X865374Y1134867D01*
X865582Y1134658D01*
X865666Y1134408D01*
Y1133992D01*
X865791Y1133617D01*
X866041Y1133367D01*
X866332Y1133283D01*
X866624Y1133367D01*
X866832Y1133575D01*
X866957Y1133908D01*
X866999Y1134200D01*
G01X861999Y1123050D02*
Y1136050D01*
G01X852413Y1121913D02*
Y1116413D01*
G01X844413Y1121913D02*
X852413D01*
G01X844413Y1116413D02*
Y1121913D01*
G01X851533Y1143592D02*
Y1138092D01*
G01Y1155692D02*
Y1150192D01*
G01X852233Y1138092D02*
Y1143592D01*
G01X860233Y1138092D02*
X852233D01*
G01X860233Y1143592D02*
Y1138092D01*
G01Y1155692D02*
Y1150192D01*
G01X852233D02*
Y1155692D01*
G01X861807Y1155817D02*
X861682Y1155567D01*
X861599Y1155275D01*
Y1154942D01*
X861724Y1154567D01*
X861932Y1154275D01*
X862182Y1154067D01*
X862599Y1153900D01*
X862974Y1153858D01*
X863349Y1153942D01*
X863599Y1154067D01*
X863849Y1154317D01*
X864016Y1154608D01*
X864099Y1154900D01*
Y1155192D01*
X864016Y1155483D01*
X863891Y1155733D01*
X863724Y1155942D01*
G01X864099Y1158000D02*
X861599D01*
X862099Y1157500D01*
G01X864099D02*
Y1158500D01*
G01Y1161600D02*
X861599D01*
X863391Y1160058D01*
Y1162142D01*
G01X863057Y1163408D02*
X862766Y1163700D01*
X862599Y1163950D01*
X862516Y1164283D01*
X862599Y1164575D01*
X862766Y1164783D01*
X863016Y1164950D01*
X863307Y1164992D01*
X863557Y1164950D01*
X863807Y1164783D01*
X864016Y1164533D01*
X864099Y1164242D01*
X864016Y1163908D01*
X863766Y1163617D01*
X863391Y1163450D01*
X862974Y1163408D01*
X862432Y1163492D01*
X862141Y1163617D01*
X861849Y1163825D01*
X861641Y1164117D01*
X861599Y1164408D01*
X861682Y1164700D01*
X861891Y1164908D01*
G01X846241Y1160059D02*
X846116Y1159809D01*
X846033Y1159517D01*
Y1159184D01*
X846158Y1158809D01*
X846366Y1158517D01*
X846616Y1158309D01*
X847033Y1158142D01*
X847408Y1158100D01*
X847783Y1158184D01*
X848033Y1158309D01*
X848283Y1158559D01*
X848450Y1158850D01*
X848533Y1159142D01*
Y1159434D01*
X848450Y1159725D01*
X848325Y1159975D01*
X848158Y1160184D01*
G01X848533Y1162242D02*
X846033D01*
X846533Y1161742D01*
G01X848533D02*
Y1162742D01*
G01Y1165842D02*
X846033D01*
X847825Y1164300D01*
Y1166384D01*
G01X848533Y1168942D02*
X846033D01*
X847825Y1167400D01*
Y1169484D01*
G01X854941Y1160059D02*
X854816Y1159809D01*
X854733Y1159517D01*
Y1159184D01*
X854858Y1158809D01*
X855066Y1158517D01*
X855316Y1158309D01*
X855733Y1158142D01*
X856108Y1158100D01*
X856483Y1158184D01*
X856733Y1158309D01*
X856983Y1158559D01*
X857150Y1158850D01*
X857233Y1159142D01*
Y1159434D01*
X857150Y1159725D01*
X857025Y1159975D01*
X856858Y1160184D01*
G01X857233Y1162242D02*
X854733D01*
X855233Y1161742D01*
G01X857233D02*
Y1162742D01*
G01Y1165842D02*
X854733D01*
X856525Y1164300D01*
Y1166384D01*
G01X856858Y1167525D02*
X857066Y1167775D01*
X857191Y1168067D01*
X857233Y1168442D01*
X857150Y1168817D01*
X856983Y1169109D01*
X856691Y1169317D01*
X856358Y1169359D01*
X856025Y1169275D01*
X855816Y1169067D01*
X855650Y1168775D01*
X855608Y1168484D01*
X855650Y1168192D01*
X855816Y1167817D01*
X854733Y1167942D01*
Y1169067D01*
G01X852233Y1155692D02*
X860233D01*
G01X855399Y1350550D02*
X855066Y1350592D01*
X854774Y1350758D01*
X854524Y1351008D01*
X854357Y1351300D01*
X854274Y1351633D01*
Y1351967D01*
X854357Y1352300D01*
X854524Y1352592D01*
X854774Y1352842D01*
X855066Y1353008D01*
X855399Y1353050D01*
X855732Y1353008D01*
X856024Y1352842D01*
X856274Y1352592D01*
X856441Y1352300D01*
X856524Y1351967D01*
Y1351633D01*
X856441Y1351300D01*
X856274Y1351008D01*
X856024Y1350758D01*
X855732Y1350592D01*
X855399Y1350550D01*
G01X855732Y1351217D02*
X856232Y1350550D01*
G01X857582Y1351050D02*
X857832Y1350758D01*
X858166Y1350592D01*
X858541Y1350550D01*
X858874Y1350592D01*
X859207Y1350800D01*
X859416Y1351050D01*
X859457Y1351300D01*
X859374Y1351592D01*
X859082Y1351800D01*
X858791Y1351883D01*
X858416D01*
G01X858791D02*
X859041Y1352008D01*
X859249Y1352217D01*
X859332Y1352467D01*
X859249Y1352717D01*
X859041Y1352925D01*
X858666Y1353050D01*
X858291Y1353008D01*
X857916Y1352842D01*
G01X860682Y1350925D02*
X860932Y1350717D01*
X861224Y1350592D01*
X861599Y1350550D01*
X861974Y1350633D01*
X862266Y1350800D01*
X862474Y1351092D01*
X862516Y1351425D01*
X862432Y1351758D01*
X862224Y1351967D01*
X861932Y1352133D01*
X861641Y1352175D01*
X861349Y1352133D01*
X860974Y1351967D01*
X861099Y1353050D01*
X862224D01*
G01X853199Y1356300D02*
X867199D01*
G01X853199Y1369300D02*
Y1356300D01*
G01X852017Y1376500D02*
Y1379000D01*
X853058D01*
X853392Y1378875D01*
X853600Y1378708D01*
X853683Y1378375D01*
X853600Y1378042D01*
X853350Y1377833D01*
X853058Y1377708D01*
X852017D01*
G01X853058D02*
X853683Y1376500D01*
G01X856450D02*
Y1379000D01*
X854908Y1377208D01*
X856992D01*
G01X859050Y1376500D02*
X859342Y1376542D01*
X859675Y1376667D01*
X859883Y1376875D01*
X859967Y1377167D01*
X859883Y1377458D01*
X859633Y1377708D01*
X859258Y1377833D01*
X858842D01*
X858592Y1377917D01*
X858383Y1378125D01*
X858300Y1378417D01*
X858425Y1378708D01*
X858717Y1378917D01*
X859050Y1379000D01*
X859383Y1378917D01*
X859675Y1378708D01*
X859800Y1378417D01*
X859717Y1378125D01*
X859508Y1377917D01*
X859258Y1377833D01*
X858842D01*
X858467Y1377708D01*
X858217Y1377458D01*
X858133Y1377167D01*
X858217Y1376875D01*
X858425Y1376667D01*
X858758Y1376542D01*
X859050Y1376500D01*
G01X861442Y1376792D02*
X861733Y1376583D01*
X862067Y1376500D01*
X862400Y1376583D01*
X862692Y1376833D01*
X862900Y1377208D01*
X862983Y1377583D01*
Y1378042D01*
X862900Y1378417D01*
X862692Y1378750D01*
X862442Y1378917D01*
X862150Y1379000D01*
X861817Y1378917D01*
X861567Y1378750D01*
X861400Y1378500D01*
X861317Y1378167D01*
X861400Y1377875D01*
X861608Y1377583D01*
X861858Y1377417D01*
X862150Y1377375D01*
X862483Y1377458D01*
X862733Y1377667D01*
X862983Y1378042D01*
G01X856399Y1374200D02*
Y1370200D01*
X863799D01*
G01X867199Y1369300D02*
X853199D01*
G01X850517Y1476500D02*
Y1479000D01*
X851558D01*
X851892Y1478875D01*
X852100Y1478708D01*
X852183Y1478375D01*
X852100Y1478042D01*
X851850Y1477833D01*
X851558Y1477708D01*
X850517D01*
G01X851558D02*
X852183Y1476500D01*
G01X854450D02*
Y1479000D01*
X853950Y1478500D01*
G01Y1476500D02*
X854950D01*
G01X856758Y1478583D02*
X857008Y1478833D01*
X857300Y1478958D01*
X857633Y1479000D01*
X858050Y1478917D01*
X858342Y1478708D01*
X858425Y1478458D01*
X858383Y1478208D01*
X858217Y1478000D01*
X857383Y1477583D01*
X857008Y1477292D01*
X856758Y1476875D01*
X856675Y1476500D01*
X858425D01*
G01X859733Y1477000D02*
X859983Y1476708D01*
X860317Y1476542D01*
X860692Y1476500D01*
X861025Y1476542D01*
X861358Y1476750D01*
X861567Y1477000D01*
X861608Y1477250D01*
X861525Y1477542D01*
X861233Y1477750D01*
X860942Y1477833D01*
X860567D01*
G01X860942D02*
X861192Y1477958D01*
X861400Y1478167D01*
X861483Y1478417D01*
X861400Y1478667D01*
X861192Y1478875D01*
X860817Y1479000D01*
X860442Y1478958D01*
X860067Y1478792D01*
G01X844127Y1494296D02*
Y1490296D01*
X851527D01*
G01X850517Y1472500D02*
Y1475000D01*
X851558D01*
X851892Y1474875D01*
X852100Y1474708D01*
X852183Y1474375D01*
X852100Y1474042D01*
X851850Y1473833D01*
X851558Y1473708D01*
X850517D01*
G01X851558D02*
X852183Y1472500D01*
G01X853533Y1473000D02*
X853783Y1472708D01*
X854117Y1472542D01*
X854492Y1472500D01*
X854825Y1472542D01*
X855158Y1472750D01*
X855367Y1473000D01*
X855408Y1473250D01*
X855325Y1473542D01*
X855033Y1473750D01*
X854742Y1473833D01*
X854367D01*
G01X854742D02*
X854992Y1473958D01*
X855200Y1474167D01*
X855283Y1474417D01*
X855200Y1474667D01*
X854992Y1474875D01*
X854617Y1475000D01*
X854242Y1474958D01*
X853867Y1474792D01*
G01X856633Y1472875D02*
X856883Y1472667D01*
X857175Y1472542D01*
X857550Y1472500D01*
X857925Y1472583D01*
X858217Y1472750D01*
X858425Y1473042D01*
X858467Y1473375D01*
X858383Y1473708D01*
X858175Y1473917D01*
X857883Y1474083D01*
X857592Y1474125D01*
X857300Y1474083D01*
X856925Y1473917D01*
X857050Y1475000D01*
X858175D01*
G01X859733Y1473000D02*
X859983Y1472708D01*
X860317Y1472542D01*
X860692Y1472500D01*
X861025Y1472542D01*
X861358Y1472750D01*
X861567Y1473000D01*
X861608Y1473250D01*
X861525Y1473542D01*
X861233Y1473750D01*
X860942Y1473833D01*
X860567D01*
G01X860942D02*
X861192Y1473958D01*
X861400Y1474167D01*
X861483Y1474417D01*
X861400Y1474667D01*
X861192Y1474875D01*
X860817Y1475000D01*
X860442Y1474958D01*
X860067Y1474792D01*
G01X851500Y1486100D02*
Y1490100D01*
X844100D01*
G01X865000Y1481517D02*
X862500D01*
Y1482558D01*
X862625Y1482892D01*
X862792Y1483100D01*
X863125Y1483183D01*
X863458Y1483100D01*
X863667Y1482850D01*
X863792Y1482558D01*
Y1481517D01*
G01Y1482558D02*
X865000Y1483183D01*
G01Y1485450D02*
X862500D01*
X863000Y1484950D01*
G01X865000D02*
Y1485950D01*
G01X862917Y1487758D02*
X862667Y1488008D01*
X862542Y1488300D01*
X862500Y1488633D01*
X862583Y1489050D01*
X862792Y1489342D01*
X863042Y1489425D01*
X863292Y1489383D01*
X863500Y1489217D01*
X863917Y1488383D01*
X864208Y1488008D01*
X864625Y1487758D01*
X865000Y1487675D01*
Y1489425D01*
G01X864625Y1490733D02*
X864833Y1490983D01*
X864958Y1491275D01*
X865000Y1491650D01*
X864917Y1492025D01*
X864750Y1492317D01*
X864458Y1492525D01*
X864125Y1492567D01*
X863792Y1492483D01*
X863583Y1492275D01*
X863417Y1491983D01*
X863375Y1491692D01*
X863417Y1491400D01*
X863583Y1491025D01*
X862500Y1491150D01*
Y1492275D01*
G01X865499Y1496067D02*
X862999D01*
Y1497108D01*
X863124Y1497442D01*
X863291Y1497650D01*
X863624Y1497733D01*
X863957Y1497650D01*
X864166Y1497400D01*
X864291Y1497108D01*
Y1496067D01*
G01Y1497108D02*
X865499Y1497733D01*
G01Y1500000D02*
X862999D01*
X863499Y1499500D01*
G01X865499D02*
Y1500500D01*
G01X863416Y1502308D02*
X863166Y1502558D01*
X863041Y1502850D01*
X862999Y1503183D01*
X863082Y1503600D01*
X863291Y1503892D01*
X863541Y1503975D01*
X863791Y1503933D01*
X863999Y1503767D01*
X864416Y1502933D01*
X864707Y1502558D01*
X865124Y1502308D01*
X865499Y1502225D01*
Y1503975D01*
G01Y1506200D02*
X862999D01*
X863499Y1505700D01*
G01X865499D02*
Y1506700D01*
G01X860327Y1495096D02*
Y1508096D01*
G01X846827Y1508996D02*
Y1514496D01*
G01X854827Y1508996D02*
X846827D01*
G01X854827Y1514496D02*
Y1508996D01*
G01X864827Y1527796D02*
Y1540796D01*
G01X862708Y1515267D02*
X862583Y1515017D01*
X862500Y1514725D01*
Y1514392D01*
X862625Y1514017D01*
X862833Y1513725D01*
X863083Y1513517D01*
X863500Y1513350D01*
X863875Y1513308D01*
X864250Y1513392D01*
X864500Y1513517D01*
X864750Y1513767D01*
X864917Y1514058D01*
X865000Y1514350D01*
Y1514642D01*
X864917Y1514933D01*
X864792Y1515183D01*
X864625Y1515392D01*
G01X865000Y1517450D02*
X862500D01*
X863000Y1516950D01*
G01X865000D02*
Y1517950D01*
G01X862917Y1519758D02*
X862667Y1520008D01*
X862542Y1520300D01*
X862500Y1520633D01*
X862583Y1521050D01*
X862792Y1521342D01*
X863042Y1521425D01*
X863292Y1521383D01*
X863500Y1521217D01*
X863917Y1520383D01*
X864208Y1520008D01*
X864625Y1519758D01*
X865000Y1519675D01*
Y1521425D01*
G01X864500Y1522733D02*
X864792Y1522983D01*
X864958Y1523317D01*
X865000Y1523692D01*
X864958Y1524025D01*
X864750Y1524358D01*
X864500Y1524567D01*
X864250Y1524608D01*
X863958Y1524525D01*
X863750Y1524233D01*
X863667Y1523942D01*
Y1523567D01*
G01Y1523942D02*
X863542Y1524192D01*
X863333Y1524400D01*
X863083Y1524483D01*
X862833Y1524400D01*
X862625Y1524192D01*
X862500Y1523817D01*
X862542Y1523442D01*
X862708Y1523067D01*
G01X854827Y1526596D02*
Y1521096D01*
G01X846827Y1526596D02*
X854827D01*
G01X846827Y1521096D02*
Y1526596D01*
G01X845500Y1547500D02*
Y1542000D01*
G01Y1559600D02*
Y1554100D01*
G01X846200Y1542000D02*
Y1547500D01*
G01X854200Y1542000D02*
X846200D01*
G01X854200Y1547500D02*
Y1542000D01*
G01Y1559600D02*
Y1554100D01*
G01X846200D02*
Y1559600D01*
G01X854900Y1542000D02*
Y1547500D01*
G01X862900Y1542000D02*
X854900D01*
G01X862900Y1547500D02*
Y1542000D01*
G01Y1559600D02*
Y1554100D01*
G01X854900D02*
Y1559600D01*
G01X864908Y1558367D02*
X864783Y1558117D01*
X864700Y1557825D01*
Y1557492D01*
X864825Y1557117D01*
X865033Y1556825D01*
X865283Y1556617D01*
X865700Y1556450D01*
X866075Y1556408D01*
X866450Y1556492D01*
X866700Y1556617D01*
X866950Y1556867D01*
X867117Y1557158D01*
X867200Y1557450D01*
Y1557742D01*
X867117Y1558033D01*
X866992Y1558283D01*
X866825Y1558492D01*
G01X867200Y1560550D02*
X864700D01*
X865200Y1560050D01*
G01X867200D02*
Y1561050D01*
G01X866700Y1562733D02*
X866992Y1562983D01*
X867158Y1563317D01*
X867200Y1563692D01*
X867158Y1564025D01*
X866950Y1564358D01*
X866700Y1564567D01*
X866450Y1564608D01*
X866158Y1564525D01*
X865950Y1564233D01*
X865867Y1563942D01*
Y1563567D01*
G01Y1563942D02*
X865742Y1564192D01*
X865533Y1564400D01*
X865283Y1564483D01*
X865033Y1564400D01*
X864825Y1564192D01*
X864700Y1563817D01*
X864742Y1563442D01*
X864908Y1563067D01*
G01X864700Y1566750D02*
X864783Y1566417D01*
X864992Y1566167D01*
X865242Y1566000D01*
X865575Y1565875D01*
X865950Y1565833D01*
X866325Y1565875D01*
X866658Y1566000D01*
X866908Y1566167D01*
X867117Y1566417D01*
X867200Y1566750D01*
X867117Y1567083D01*
X866908Y1567333D01*
X866658Y1567500D01*
X866325Y1567625D01*
X865950Y1567667D01*
X865575Y1567625D01*
X865242Y1567500D01*
X864992Y1567333D01*
X864783Y1567083D01*
X864700Y1566750D01*
G01X848908Y1563467D02*
X848783Y1563217D01*
X848700Y1562925D01*
Y1562592D01*
X848825Y1562217D01*
X849033Y1561925D01*
X849283Y1561717D01*
X849700Y1561550D01*
X850075Y1561508D01*
X850450Y1561592D01*
X850700Y1561717D01*
X850950Y1561967D01*
X851117Y1562258D01*
X851200Y1562550D01*
Y1562842D01*
X851117Y1563133D01*
X850992Y1563383D01*
X850825Y1563592D01*
G01X851200Y1565650D02*
X848700D01*
X849200Y1565150D01*
G01X851200D02*
Y1566150D01*
G01X849117Y1567958D02*
X848867Y1568208D01*
X848742Y1568500D01*
X848700Y1568833D01*
X848783Y1569250D01*
X848992Y1569542D01*
X849242Y1569625D01*
X849492Y1569583D01*
X849700Y1569417D01*
X850117Y1568583D01*
X850408Y1568208D01*
X850825Y1567958D01*
X851200Y1567875D01*
Y1569625D01*
G01Y1571850D02*
X851158Y1572142D01*
X851033Y1572475D01*
X850825Y1572683D01*
X850533Y1572767D01*
X850242Y1572683D01*
X849992Y1572433D01*
X849867Y1572058D01*
Y1571642D01*
X849783Y1571392D01*
X849575Y1571183D01*
X849283Y1571100D01*
X848992Y1571225D01*
X848783Y1571517D01*
X848700Y1571850D01*
X848783Y1572183D01*
X848992Y1572475D01*
X849283Y1572600D01*
X849575Y1572517D01*
X849783Y1572308D01*
X849867Y1572058D01*
Y1571642D01*
X849992Y1571267D01*
X850242Y1571017D01*
X850533Y1570933D01*
X850825Y1571017D01*
X851033Y1571225D01*
X851158Y1571558D01*
X851200Y1571850D01*
G01X846200Y1559600D02*
X854200D01*
G01X857608Y1563467D02*
X857483Y1563217D01*
X857400Y1562925D01*
Y1562592D01*
X857525Y1562217D01*
X857733Y1561925D01*
X857983Y1561717D01*
X858400Y1561550D01*
X858775Y1561508D01*
X859150Y1561592D01*
X859400Y1561717D01*
X859650Y1561967D01*
X859817Y1562258D01*
X859900Y1562550D01*
Y1562842D01*
X859817Y1563133D01*
X859692Y1563383D01*
X859525Y1563592D01*
G01X859900Y1565650D02*
X857400D01*
X857900Y1565150D01*
G01X859900D02*
Y1566150D01*
G01X857817Y1567958D02*
X857567Y1568208D01*
X857442Y1568500D01*
X857400Y1568833D01*
X857483Y1569250D01*
X857692Y1569542D01*
X857942Y1569625D01*
X858192Y1569583D01*
X858400Y1569417D01*
X858817Y1568583D01*
X859108Y1568208D01*
X859525Y1567958D01*
X859900Y1567875D01*
Y1569625D01*
G01X859608Y1571142D02*
X859817Y1571433D01*
X859900Y1571767D01*
X859817Y1572100D01*
X859567Y1572392D01*
X859192Y1572600D01*
X858817Y1572683D01*
X858358D01*
X857983Y1572600D01*
X857650Y1572392D01*
X857483Y1572142D01*
X857400Y1571850D01*
X857483Y1571517D01*
X857650Y1571267D01*
X857900Y1571100D01*
X858233Y1571017D01*
X858525Y1571100D01*
X858817Y1571308D01*
X858983Y1571558D01*
X859025Y1571850D01*
X858942Y1572183D01*
X858733Y1572433D01*
X858358Y1572683D01*
G01X854900Y1559600D02*
X862900D01*
G01X851067Y1699500D02*
Y1702000D01*
X852067D01*
X852400Y1701875D01*
X852650Y1701583D01*
X852733Y1701250D01*
X852650Y1700917D01*
X852442Y1700667D01*
X852067Y1700542D01*
X851067D01*
G01X854167Y1702000D02*
Y1699500D01*
X855833D01*
G01X858017D02*
X858100Y1700042D01*
X858225Y1700500D01*
X858392Y1700917D01*
X858600Y1701375D01*
X858933Y1702000D01*
X857267D01*
G01X863500Y1742000D02*
Y1752000D01*
G01X870500D02*
Y1742000D01*
G01Y1747000D02*
X863500D01*
G01X873933Y1742000D02*
Y1752000D01*
X877267D01*
X878600Y1751500D01*
X879600Y1750833D01*
X880433Y1749833D01*
X881100Y1748666D01*
X881267Y1747000D01*
X881100Y1745333D01*
X880433Y1744167D01*
X879600Y1743166D01*
X878600Y1742500D01*
X877267Y1742000D01*
X873933D01*
G01X884533D02*
Y1752000D01*
X887867D01*
X889200Y1751500D01*
X890200Y1750833D01*
X891033Y1749833D01*
X891700Y1748666D01*
X891867Y1747000D01*
X891700Y1745333D01*
X891033Y1744167D01*
X890200Y1743166D01*
X889200Y1742500D01*
X887867Y1742000D01*
X884533D01*
G01X898800Y1752000D02*
X897466Y1751667D01*
X896467Y1750833D01*
X895800Y1749833D01*
X895300Y1748500D01*
X895133Y1747000D01*
X895300Y1745500D01*
X895800Y1744167D01*
X896467Y1743166D01*
X897466Y1742333D01*
X898800Y1742000D01*
X900133Y1742333D01*
X901133Y1743166D01*
X901800Y1744167D01*
X902300Y1745500D01*
X902467Y1747000D01*
X902300Y1748500D01*
X901800Y1749833D01*
X901133Y1750833D01*
X900133Y1751667D01*
X898800Y1752000D01*
G01X904400Y1738667D02*
X914400D01*
G01X916667Y1752000D02*
Y1742000D01*
X923333D01*
G01X933933D02*
X927267D01*
Y1752000D01*
X933933D01*
G01X931267Y1747167D02*
X927267D01*
G01X937533Y1742000D02*
Y1752000D01*
X940867D01*
X942200Y1751500D01*
X943200Y1750833D01*
X944033Y1749833D01*
X944700Y1748666D01*
X944867Y1747000D01*
X944700Y1745333D01*
X944033Y1744167D01*
X943200Y1743166D01*
X942200Y1742500D01*
X940867Y1742000D01*
X937533D01*
G01X846081Y1847905D02*
X845831Y1848030D01*
X845539Y1848113D01*
X845206D01*
X844831Y1847988D01*
X844539Y1847780D01*
X844331Y1847530D01*
X844164Y1847113D01*
X844122Y1846738D01*
X844206Y1846363D01*
X844331Y1846113D01*
X844581Y1845863D01*
X844872Y1845696D01*
X845164Y1845613D01*
X845456D01*
X845747Y1845696D01*
X845997Y1845821D01*
X846206Y1845988D01*
G01X848264Y1845613D02*
Y1848113D01*
X847764Y1847613D01*
G01Y1845613D02*
X848764D01*
G01X851364Y1848113D02*
X851031Y1848030D01*
X850781Y1847821D01*
X850614Y1847571D01*
X850489Y1847238D01*
X850447Y1846863D01*
X850489Y1846488D01*
X850614Y1846155D01*
X850781Y1845905D01*
X851031Y1845696D01*
X851364Y1845613D01*
X851697Y1845696D01*
X851947Y1845905D01*
X852114Y1846155D01*
X852239Y1846488D01*
X852281Y1846863D01*
X852239Y1847238D01*
X852114Y1847571D01*
X851947Y1847821D01*
X851697Y1848030D01*
X851364Y1848113D01*
G01X854464D02*
X854131Y1848030D01*
X853881Y1847821D01*
X853714Y1847571D01*
X853589Y1847238D01*
X853547Y1846863D01*
X853589Y1846488D01*
X853714Y1846155D01*
X853881Y1845905D01*
X854131Y1845696D01*
X854464Y1845613D01*
X854797Y1845696D01*
X855047Y1845905D01*
X855214Y1846155D01*
X855339Y1846488D01*
X855381Y1846863D01*
X855339Y1847238D01*
X855214Y1847571D01*
X855047Y1847821D01*
X854797Y1848030D01*
X854464Y1848113D01*
G01X846081Y1851405D02*
X845831Y1851530D01*
X845539Y1851613D01*
X845206D01*
X844831Y1851488D01*
X844539Y1851280D01*
X844331Y1851030D01*
X844164Y1850613D01*
X844122Y1850238D01*
X844206Y1849863D01*
X844331Y1849613D01*
X844581Y1849363D01*
X844872Y1849196D01*
X845164Y1849113D01*
X845456D01*
X845747Y1849196D01*
X845997Y1849321D01*
X846206Y1849488D01*
G01X848264Y1849113D02*
Y1851613D01*
X847764Y1851113D01*
G01Y1849113D02*
X848764D01*
G01X851364Y1851613D02*
X851031Y1851530D01*
X850781Y1851321D01*
X850614Y1851071D01*
X850489Y1850738D01*
X850447Y1850363D01*
X850489Y1849988D01*
X850614Y1849655D01*
X850781Y1849405D01*
X851031Y1849196D01*
X851364Y1849113D01*
X851697Y1849196D01*
X851947Y1849405D01*
X852114Y1849655D01*
X852239Y1849988D01*
X852281Y1850363D01*
X852239Y1850738D01*
X852114Y1851071D01*
X851947Y1851321D01*
X851697Y1851530D01*
X851364Y1851613D01*
G01X853547Y1849613D02*
X853797Y1849321D01*
X854131Y1849155D01*
X854506Y1849113D01*
X854839Y1849155D01*
X855172Y1849363D01*
X855381Y1849613D01*
X855422Y1849863D01*
X855339Y1850155D01*
X855047Y1850363D01*
X854756Y1850446D01*
X854381D01*
G01X854756D02*
X855006Y1850571D01*
X855214Y1850780D01*
X855297Y1851030D01*
X855214Y1851280D01*
X855006Y1851488D01*
X854631Y1851613D01*
X854256Y1851571D01*
X853881Y1851405D01*
G01X857081Y1864405D02*
X856831Y1864530D01*
X856539Y1864613D01*
X856206D01*
X855831Y1864488D01*
X855539Y1864280D01*
X855331Y1864030D01*
X855164Y1863613D01*
X855122Y1863238D01*
X855206Y1862863D01*
X855331Y1862613D01*
X855581Y1862363D01*
X855872Y1862196D01*
X856164Y1862113D01*
X856456D01*
X856747Y1862196D01*
X856997Y1862321D01*
X857206Y1862488D01*
G01X859264Y1862113D02*
Y1864613D01*
X858764Y1864113D01*
G01Y1862113D02*
X859764D01*
G01X862364Y1864613D02*
X862031Y1864530D01*
X861781Y1864321D01*
X861614Y1864071D01*
X861489Y1863738D01*
X861447Y1863363D01*
X861489Y1862988D01*
X861614Y1862655D01*
X861781Y1862405D01*
X862031Y1862196D01*
X862364Y1862113D01*
X862697Y1862196D01*
X862947Y1862405D01*
X863114Y1862655D01*
X863239Y1862988D01*
X863281Y1863363D01*
X863239Y1863738D01*
X863114Y1864071D01*
X862947Y1864321D01*
X862697Y1864530D01*
X862364Y1864613D01*
G01X865964Y1862113D02*
Y1864613D01*
X864422Y1862821D01*
X866506D01*
G01X857081Y1867905D02*
X856831Y1868030D01*
X856539Y1868113D01*
X856206D01*
X855831Y1867988D01*
X855539Y1867780D01*
X855331Y1867530D01*
X855164Y1867113D01*
X855122Y1866738D01*
X855206Y1866363D01*
X855331Y1866113D01*
X855581Y1865863D01*
X855872Y1865696D01*
X856164Y1865613D01*
X856456D01*
X856747Y1865696D01*
X856997Y1865821D01*
X857206Y1865988D01*
G01X859264Y1865613D02*
Y1868113D01*
X858764Y1867613D01*
G01Y1865613D02*
X859764D01*
G01X862364Y1868113D02*
X862031Y1868030D01*
X861781Y1867821D01*
X861614Y1867571D01*
X861489Y1867238D01*
X861447Y1866863D01*
X861489Y1866488D01*
X861614Y1866155D01*
X861781Y1865905D01*
X862031Y1865696D01*
X862364Y1865613D01*
X862697Y1865696D01*
X862947Y1865905D01*
X863114Y1866155D01*
X863239Y1866488D01*
X863281Y1866863D01*
X863239Y1867238D01*
X863114Y1867571D01*
X862947Y1867821D01*
X862697Y1868030D01*
X862364Y1868113D01*
G01X864547Y1865988D02*
X864797Y1865780D01*
X865089Y1865655D01*
X865464Y1865613D01*
X865839Y1865696D01*
X866131Y1865863D01*
X866339Y1866155D01*
X866381Y1866488D01*
X866297Y1866821D01*
X866089Y1867030D01*
X865797Y1867196D01*
X865506Y1867238D01*
X865214Y1867196D01*
X864839Y1867030D01*
X864964Y1868113D01*
X866089D01*
G01X852517Y1882000D02*
Y1884500D01*
X853558D01*
X853892Y1884375D01*
X854100Y1884208D01*
X854183Y1883875D01*
X854100Y1883542D01*
X853850Y1883333D01*
X853558Y1883208D01*
X852517D01*
G01X853558D02*
X854183Y1882000D01*
G01X856450D02*
Y1884500D01*
X855950Y1884000D01*
G01Y1882000D02*
X856950D01*
G01X859550Y1884500D02*
X859217Y1884417D01*
X858967Y1884208D01*
X858800Y1883958D01*
X858675Y1883625D01*
X858633Y1883250D01*
X858675Y1882875D01*
X858800Y1882542D01*
X858967Y1882292D01*
X859217Y1882083D01*
X859550Y1882000D01*
X859883Y1882083D01*
X860133Y1882292D01*
X860300Y1882542D01*
X860425Y1882875D01*
X860467Y1883250D01*
X860425Y1883625D01*
X860300Y1883958D01*
X860133Y1884208D01*
X859883Y1884417D01*
X859550Y1884500D01*
G01X861858Y1883042D02*
X862150Y1883333D01*
X862400Y1883500D01*
X862733Y1883583D01*
X863025Y1883500D01*
X863233Y1883333D01*
X863400Y1883083D01*
X863442Y1882792D01*
X863400Y1882542D01*
X863233Y1882292D01*
X862983Y1882083D01*
X862692Y1882000D01*
X862358Y1882083D01*
X862067Y1882333D01*
X861900Y1882708D01*
X861858Y1883125D01*
X861942Y1883667D01*
X862067Y1883958D01*
X862275Y1884250D01*
X862567Y1884458D01*
X862858Y1884500D01*
X863150Y1884417D01*
X863358Y1884208D01*
G01X852517Y1878000D02*
Y1880500D01*
X853558D01*
X853892Y1880375D01*
X854100Y1880208D01*
X854183Y1879875D01*
X854100Y1879542D01*
X853850Y1879333D01*
X853558Y1879208D01*
X852517D01*
G01X853558D02*
X854183Y1878000D01*
G01X855533Y1878500D02*
X855783Y1878208D01*
X856117Y1878042D01*
X856492Y1878000D01*
X856825Y1878042D01*
X857158Y1878250D01*
X857367Y1878500D01*
X857408Y1878750D01*
X857325Y1879042D01*
X857033Y1879250D01*
X856742Y1879333D01*
X856367D01*
G01X856742D02*
X856992Y1879458D01*
X857200Y1879667D01*
X857283Y1879917D01*
X857200Y1880167D01*
X856992Y1880375D01*
X856617Y1880500D01*
X856242Y1880458D01*
X855867Y1880292D01*
G01X860050Y1878000D02*
Y1880500D01*
X858508Y1878708D01*
X860592D01*
G01X861733Y1878500D02*
X861983Y1878208D01*
X862317Y1878042D01*
X862692Y1878000D01*
X863025Y1878042D01*
X863358Y1878250D01*
X863567Y1878500D01*
X863608Y1878750D01*
X863525Y1879042D01*
X863233Y1879250D01*
X862942Y1879333D01*
X862567D01*
G01X862942D02*
X863192Y1879458D01*
X863400Y1879667D01*
X863483Y1879917D01*
X863400Y1880167D01*
X863192Y1880375D01*
X862817Y1880500D01*
X862442Y1880458D01*
X862067Y1880292D01*
G01X851999Y1891850D02*
Y1895850D01*
X844599D01*
G01X865500Y1889017D02*
X863000D01*
Y1890058D01*
X863125Y1890392D01*
X863292Y1890600D01*
X863625Y1890683D01*
X863958Y1890600D01*
X864167Y1890350D01*
X864292Y1890058D01*
Y1889017D01*
G01Y1890058D02*
X865500Y1890683D01*
G01Y1892950D02*
X863000D01*
X863500Y1892450D01*
G01X865500D02*
Y1893450D01*
G01Y1896050D02*
X863000D01*
X863500Y1895550D01*
G01X865500D02*
Y1896550D01*
G01Y1899150D02*
X863000D01*
X863500Y1898650D01*
G01X865500D02*
Y1899650D01*
G01X843999Y1881550D02*
Y1895550D01*
G01X865500Y1903017D02*
X863000D01*
Y1904058D01*
X863125Y1904392D01*
X863292Y1904600D01*
X863625Y1904683D01*
X863958Y1904600D01*
X864167Y1904350D01*
X864292Y1904058D01*
Y1903017D01*
G01Y1904058D02*
X865500Y1904683D01*
G01Y1906950D02*
X863000D01*
X863500Y1906450D01*
G01X865500D02*
Y1907450D01*
G01X863000Y1910050D02*
X863083Y1909717D01*
X863292Y1909467D01*
X863542Y1909300D01*
X863875Y1909175D01*
X864250Y1909133D01*
X864625Y1909175D01*
X864958Y1909300D01*
X865208Y1909467D01*
X865417Y1909717D01*
X865500Y1910050D01*
X865417Y1910383D01*
X865208Y1910633D01*
X864958Y1910800D01*
X864625Y1910925D01*
X864250Y1910967D01*
X863875Y1910925D01*
X863542Y1910800D01*
X863292Y1910633D01*
X863083Y1910383D01*
X863000Y1910050D01*
G01Y1913150D02*
X863083Y1912817D01*
X863292Y1912567D01*
X863542Y1912400D01*
X863875Y1912275D01*
X864250Y1912233D01*
X864625Y1912275D01*
X864958Y1912400D01*
X865208Y1912567D01*
X865417Y1912817D01*
X865500Y1913150D01*
X865417Y1913483D01*
X865208Y1913733D01*
X864958Y1913900D01*
X864625Y1914025D01*
X864250Y1914067D01*
X863875Y1914025D01*
X863542Y1913900D01*
X863292Y1913733D01*
X863083Y1913483D01*
X863000Y1913150D01*
G01X860564Y1900813D02*
Y1913813D01*
G01X844614Y1900113D02*
Y1896113D01*
X852014D01*
G01X863499Y1934050D02*
Y1947050D01*
G01X861208Y1922267D02*
X861083Y1922017D01*
X861000Y1921725D01*
Y1921392D01*
X861125Y1921017D01*
X861333Y1920725D01*
X861583Y1920517D01*
X862000Y1920350D01*
X862375Y1920308D01*
X862750Y1920392D01*
X863000Y1920517D01*
X863250Y1920767D01*
X863417Y1921058D01*
X863500Y1921350D01*
Y1921642D01*
X863417Y1921933D01*
X863292Y1922183D01*
X863125Y1922392D01*
G01X863500Y1924450D02*
X861000D01*
X861500Y1923950D01*
G01X863500D02*
Y1924950D01*
G01X861000Y1927550D02*
X861083Y1927217D01*
X861292Y1926967D01*
X861542Y1926800D01*
X861875Y1926675D01*
X862250Y1926633D01*
X862625Y1926675D01*
X862958Y1926800D01*
X863208Y1926967D01*
X863417Y1927217D01*
X863500Y1927550D01*
X863417Y1927883D01*
X863208Y1928133D01*
X862958Y1928300D01*
X862625Y1928425D01*
X862250Y1928467D01*
X861875Y1928425D01*
X861542Y1928300D01*
X861292Y1928133D01*
X861083Y1927883D01*
X861000Y1927550D01*
G01X863500Y1930567D02*
X862958Y1930650D01*
X862500Y1930775D01*
X862083Y1930942D01*
X861625Y1931150D01*
X861000Y1931483D01*
Y1929817D01*
G01X846314Y1914813D02*
Y1920313D01*
G01X854314Y1914813D02*
X846314D01*
G01X854314Y1920313D02*
Y1914813D01*
G01Y1932413D02*
Y1926913D01*
G01X846314Y1932413D02*
X854314D01*
G01X846314Y1926913D02*
Y1932413D01*
G01X844400Y1956200D02*
Y1950700D01*
G01X845100D02*
Y1956200D01*
G01X853100Y1950700D02*
X845100D01*
G01X853100Y1956200D02*
Y1950700D01*
G01X853800D02*
Y1956200D01*
G01X861800Y1950700D02*
X853800D01*
G01X861800Y1956200D02*
Y1950700D01*
G01X863893Y1968604D02*
X863768Y1968354D01*
X863685Y1968062D01*
Y1967729D01*
X863810Y1967354D01*
X864018Y1967062D01*
X864268Y1966854D01*
X864685Y1966687D01*
X865060Y1966645D01*
X865435Y1966729D01*
X865685Y1966854D01*
X865935Y1967104D01*
X866102Y1967395D01*
X866185Y1967687D01*
Y1967979D01*
X866102Y1968270D01*
X865977Y1968520D01*
X865810Y1968729D01*
G01X866185Y1970787D02*
X863685D01*
X864185Y1970287D01*
G01X866185D02*
Y1971287D01*
G01Y1973887D02*
X863685D01*
X864185Y1973387D01*
G01X866185D02*
Y1974387D01*
G01X865810Y1976070D02*
X866018Y1976320D01*
X866143Y1976612D01*
X866185Y1976987D01*
X866102Y1977362D01*
X865935Y1977654D01*
X865643Y1977862D01*
X865310Y1977904D01*
X864977Y1977820D01*
X864768Y1977612D01*
X864602Y1977320D01*
X864560Y1977029D01*
X864602Y1976737D01*
X864768Y1976362D01*
X863685Y1976487D01*
Y1977612D01*
G01X844400Y1968300D02*
Y1962800D01*
G01X847808Y1972167D02*
X847683Y1971917D01*
X847600Y1971625D01*
Y1971292D01*
X847725Y1970917D01*
X847933Y1970625D01*
X848183Y1970417D01*
X848600Y1970250D01*
X848975Y1970208D01*
X849350Y1970292D01*
X849600Y1970417D01*
X849850Y1970667D01*
X850017Y1970958D01*
X850100Y1971250D01*
Y1971542D01*
X850017Y1971833D01*
X849892Y1972083D01*
X849725Y1972292D01*
G01X850100Y1974350D02*
X847600D01*
X848100Y1973850D01*
G01X850100D02*
Y1974850D01*
G01Y1977450D02*
X847600D01*
X848100Y1976950D01*
G01X850100D02*
Y1977950D01*
G01X849600Y1979633D02*
X849892Y1979883D01*
X850058Y1980217D01*
X850100Y1980592D01*
X850058Y1980925D01*
X849850Y1981258D01*
X849600Y1981467D01*
X849350Y1981508D01*
X849058Y1981425D01*
X848850Y1981133D01*
X848767Y1980842D01*
Y1980467D01*
G01Y1980842D02*
X848642Y1981092D01*
X848433Y1981300D01*
X848183Y1981383D01*
X847933Y1981300D01*
X847725Y1981092D01*
X847600Y1980717D01*
X847642Y1980342D01*
X847808Y1979967D01*
G01X853100Y1968300D02*
Y1962800D01*
G01X845100Y1968300D02*
X853100D01*
G01X845100Y1962800D02*
Y1968300D01*
G01X856508Y1972167D02*
X856383Y1971917D01*
X856300Y1971625D01*
Y1971292D01*
X856425Y1970917D01*
X856633Y1970625D01*
X856883Y1970417D01*
X857300Y1970250D01*
X857675Y1970208D01*
X858050Y1970292D01*
X858300Y1970417D01*
X858550Y1970667D01*
X858717Y1970958D01*
X858800Y1971250D01*
Y1971542D01*
X858717Y1971833D01*
X858592Y1972083D01*
X858425Y1972292D01*
G01X858800Y1974350D02*
X856300D01*
X856800Y1973850D01*
G01X858800D02*
Y1974850D01*
G01Y1977450D02*
X856300D01*
X856800Y1976950D01*
G01X858800D02*
Y1977950D01*
G01Y1981050D02*
X856300D01*
X858092Y1979508D01*
Y1981592D01*
G01X861800Y1968300D02*
Y1962800D01*
G01X853800Y1968300D02*
X861800D01*
G01X853800Y1962800D02*
Y1968300D01*
G01X873499Y107850D02*
X891499D01*
G01X873499Y119050D02*
Y107850D01*
G01X870999D02*
Y119050D01*
G01X873499Y135050D02*
Y146250D01*
G01X870999D02*
Y135050D01*
G01X869528Y161924D02*
Y157924D01*
X876928D01*
G01X873499Y146250D02*
X891499D01*
G01X869528Y165924D02*
Y161924D01*
X876928D01*
G01X872969Y185817D02*
Y347017D01*
X886569D01*
Y359967D01*
X904769D01*
Y347017D01*
X933669D01*
Y336667D01*
X926969D01*
Y196167D01*
X933669D01*
Y185817D01*
X904769D01*
Y172867D01*
X886569D01*
Y185817D01*
X872969D01*
G01X869667Y251975D02*
X869875Y252308D01*
X870000Y252683D01*
Y253017D01*
X869875Y253350D01*
X869667Y253600D01*
X869375Y253725D01*
X869083Y253642D01*
X868833Y253433D01*
X868667Y253058D01*
X868583Y252558D01*
X868417Y252267D01*
X868125Y252142D01*
X867833Y252225D01*
X867625Y252433D01*
X867500Y252725D01*
Y253017D01*
X867583Y253308D01*
X867792Y253558D01*
G01X870000Y255033D02*
X867500D01*
G01Y256617D02*
X869042Y255033D01*
G01X870000Y256867D02*
X868333Y255742D01*
G01X867500Y259050D02*
X870000D01*
G01X867500Y258092D02*
Y260008D01*
G01X869625Y261233D02*
X869833Y261483D01*
X869958Y261775D01*
X870000Y262150D01*
X869917Y262525D01*
X869750Y262817D01*
X869458Y263025D01*
X869125Y263067D01*
X868792Y262983D01*
X868583Y262775D01*
X868417Y262483D01*
X868375Y262192D01*
X868417Y261900D01*
X868583Y261525D01*
X867500Y261650D01*
Y262775D01*
G01X866208Y271767D02*
X866083Y271517D01*
X866000Y271225D01*
Y270892D01*
X866125Y270517D01*
X866333Y270225D01*
X866583Y270017D01*
X867000Y269850D01*
X867375Y269808D01*
X867750Y269892D01*
X868000Y270017D01*
X868250Y270267D01*
X868417Y270558D01*
X868500Y270850D01*
Y271142D01*
X868417Y271433D01*
X868292Y271683D01*
X868125Y271892D01*
G01X868500Y273950D02*
X866000D01*
X866500Y273450D01*
G01X868500D02*
Y274450D01*
G01Y276967D02*
X867958Y277050D01*
X867500Y277175D01*
X867083Y277342D01*
X866625Y277550D01*
X866000Y277883D01*
Y276217D01*
G01X868500Y280150D02*
X868458Y280442D01*
X868333Y280775D01*
X868125Y280983D01*
X867833Y281067D01*
X867542Y280983D01*
X867292Y280733D01*
X867167Y280358D01*
Y279942D01*
X867083Y279692D01*
X866875Y279483D01*
X866583Y279400D01*
X866292Y279525D01*
X866083Y279817D01*
X866000Y280150D01*
X866083Y280483D01*
X866292Y280775D01*
X866583Y280900D01*
X866875Y280817D01*
X867083Y280608D01*
X867167Y280358D01*
Y279942D01*
X867292Y279567D01*
X867542Y279317D01*
X867833Y279233D01*
X868125Y279317D01*
X868333Y279525D01*
X868458Y279858D01*
X868500Y280150D01*
G01X866707Y303817D02*
X866582Y303567D01*
X866499Y303275D01*
Y302942D01*
X866624Y302567D01*
X866832Y302275D01*
X867082Y302067D01*
X867499Y301900D01*
X867874Y301858D01*
X868249Y301942D01*
X868499Y302067D01*
X868749Y302317D01*
X868916Y302608D01*
X868999Y302900D01*
Y303192D01*
X868916Y303483D01*
X868791Y303733D01*
X868624Y303942D01*
G01X868999Y306000D02*
X866499D01*
X866999Y305500D01*
G01X868999D02*
Y306500D01*
G01Y309017D02*
X868457Y309100D01*
X867999Y309225D01*
X867582Y309392D01*
X867124Y309600D01*
X866499Y309933D01*
Y308267D01*
G01X866916Y311408D02*
X866666Y311658D01*
X866541Y311950D01*
X866499Y312283D01*
X866582Y312700D01*
X866791Y312992D01*
X867041Y313075D01*
X867291Y313033D01*
X867499Y312867D01*
X867916Y312033D01*
X868207Y311658D01*
X868624Y311408D01*
X868999Y311325D01*
Y313075D01*
G01X868499Y317567D02*
X865999D01*
Y318608D01*
X866124Y318942D01*
X866291Y319150D01*
X866624Y319233D01*
X866957Y319150D01*
X867166Y318900D01*
X867291Y318608D01*
Y317567D01*
G01Y318608D02*
X868499Y319233D01*
G01Y321500D02*
X865999D01*
X866499Y321000D01*
G01X868499D02*
Y322000D01*
G01X867457Y323808D02*
X867166Y324100D01*
X866999Y324350D01*
X866916Y324683D01*
X866999Y324975D01*
X867166Y325183D01*
X867416Y325350D01*
X867707Y325392D01*
X867957Y325350D01*
X868207Y325183D01*
X868416Y324933D01*
X868499Y324642D01*
X868416Y324308D01*
X868166Y324017D01*
X867791Y323850D01*
X867374Y323808D01*
X866832Y323892D01*
X866541Y324017D01*
X866249Y324225D01*
X866041Y324517D01*
X865999Y324808D01*
X866082Y325100D01*
X866291Y325308D01*
G01X867999Y326783D02*
X868291Y327033D01*
X868457Y327367D01*
X868499Y327742D01*
X868457Y328075D01*
X868249Y328408D01*
X867999Y328617D01*
X867749Y328658D01*
X867457Y328575D01*
X867249Y328283D01*
X867166Y327992D01*
Y327617D01*
G01Y327992D02*
X867041Y328242D01*
X866832Y328450D01*
X866582Y328533D01*
X866332Y328450D01*
X866124Y328242D01*
X865999Y327867D01*
X866041Y327492D01*
X866207Y327117D01*
G01X869215Y572335D02*
Y574835D01*
X870256D01*
X870590Y574710D01*
X870798Y574543D01*
X870881Y574210D01*
X870798Y573877D01*
X870548Y573668D01*
X870256Y573543D01*
X869215D01*
G01X870256D02*
X870881Y572335D01*
G01X873148D02*
Y574835D01*
X872648Y574335D01*
G01Y572335D02*
X873648D01*
G01X876748D02*
Y574835D01*
X875206Y573043D01*
X877290D01*
G01X878431Y572835D02*
X878681Y572543D01*
X879015Y572377D01*
X879390Y572335D01*
X879723Y572377D01*
X880056Y572585D01*
X880265Y572835D01*
X880306Y573085D01*
X880223Y573377D01*
X879931Y573585D01*
X879640Y573668D01*
X879265D01*
G01X879640D02*
X879890Y573793D01*
X880098Y574002D01*
X880181Y574252D01*
X880098Y574502D01*
X879890Y574710D01*
X879515Y574835D01*
X879140Y574793D01*
X878765Y574627D01*
G01X881299Y572550D02*
Y568550D01*
X888699D01*
G01X868200Y562154D02*
Y564654D01*
X869241D01*
X869575Y564529D01*
X869783Y564362D01*
X869866Y564029D01*
X869783Y563696D01*
X869533Y563487D01*
X869241Y563362D01*
X868200D01*
G01X869241D02*
X869866Y562154D01*
G01X872133D02*
Y564654D01*
X871633Y564154D01*
G01Y562154D02*
X872633D01*
G01X875733D02*
Y564654D01*
X874191Y562862D01*
X876275D01*
G01X877416Y562529D02*
X877666Y562321D01*
X877958Y562196D01*
X878333Y562154D01*
X878708Y562237D01*
X879000Y562404D01*
X879208Y562696D01*
X879250Y563029D01*
X879166Y563362D01*
X878958Y563571D01*
X878666Y563737D01*
X878375Y563779D01*
X878083Y563737D01*
X877708Y563571D01*
X877833Y564654D01*
X878958D01*
G01X881299Y567050D02*
Y563050D01*
X888699D01*
G01X872969Y591329D02*
Y752529D01*
X886569D01*
Y765479D01*
X904769D01*
Y752529D01*
X933669D01*
Y742179D01*
X926969D01*
Y601679D01*
X933669D01*
Y591329D01*
X904769D01*
Y578379D01*
X886569D01*
Y591329D01*
X872969D01*
G01X865208Y673767D02*
X865083Y673517D01*
X865000Y673225D01*
Y672892D01*
X865125Y672517D01*
X865333Y672225D01*
X865583Y672017D01*
X866000Y671850D01*
X866375Y671808D01*
X866750Y671892D01*
X867000Y672017D01*
X867250Y672267D01*
X867417Y672558D01*
X867500Y672850D01*
Y673142D01*
X867417Y673433D01*
X867292Y673683D01*
X867125Y673892D01*
G01X867500Y675950D02*
X865000D01*
X865500Y675450D01*
G01X867500D02*
Y676450D01*
G01X867125Y678133D02*
X867333Y678383D01*
X867458Y678675D01*
X867500Y679050D01*
X867417Y679425D01*
X867250Y679717D01*
X866958Y679925D01*
X866625Y679967D01*
X866292Y679883D01*
X866083Y679675D01*
X865917Y679383D01*
X865875Y679092D01*
X865917Y678800D01*
X866083Y678425D01*
X865000Y678550D01*
Y679675D01*
G01X866458Y681358D02*
X866167Y681650D01*
X866000Y681900D01*
X865917Y682233D01*
X866000Y682525D01*
X866167Y682733D01*
X866417Y682900D01*
X866708Y682942D01*
X866958Y682900D01*
X867208Y682733D01*
X867417Y682483D01*
X867500Y682192D01*
X867417Y681858D01*
X867167Y681567D01*
X866792Y681400D01*
X866375Y681358D01*
X865833Y681442D01*
X865542Y681567D01*
X865250Y681775D01*
X865042Y682067D01*
X865000Y682358D01*
X865083Y682650D01*
X865292Y682858D01*
G01X867708Y705267D02*
X867583Y705017D01*
X867500Y704725D01*
Y704392D01*
X867625Y704017D01*
X867833Y703725D01*
X868083Y703517D01*
X868500Y703350D01*
X868875Y703308D01*
X869250Y703392D01*
X869500Y703517D01*
X869750Y703767D01*
X869917Y704058D01*
X870000Y704350D01*
Y704642D01*
X869917Y704933D01*
X869792Y705183D01*
X869625Y705392D01*
G01X870000Y707450D02*
X867500D01*
X868000Y706950D01*
G01X870000D02*
Y707950D01*
G01X869625Y709633D02*
X869833Y709883D01*
X869958Y710175D01*
X870000Y710550D01*
X869917Y710925D01*
X869750Y711217D01*
X869458Y711425D01*
X869125Y711467D01*
X868792Y711383D01*
X868583Y711175D01*
X868417Y710883D01*
X868375Y710592D01*
X868417Y710300D01*
X868583Y709925D01*
X867500Y710050D01*
Y711175D01*
G01X870000Y714150D02*
X867500D01*
X869292Y712608D01*
Y714692D01*
G01X866165Y969625D02*
Y972125D01*
X867206D01*
X867540Y972000D01*
X867748Y971833D01*
X867831Y971500D01*
X867748Y971167D01*
X867498Y970958D01*
X867206Y970833D01*
X866165D01*
G01X867206D02*
X867831Y969625D01*
G01X870098D02*
Y972125D01*
X869598Y971625D01*
G01Y969625D02*
X870598D01*
G01X872406Y971708D02*
X872656Y971958D01*
X872948Y972083D01*
X873281Y972125D01*
X873698Y972042D01*
X873990Y971833D01*
X874073Y971583D01*
X874031Y971333D01*
X873865Y971125D01*
X873031Y970708D01*
X872656Y970417D01*
X872406Y970000D01*
X872323Y969625D01*
X874073D01*
G01X875590Y969917D02*
X875881Y969708D01*
X876215Y969625D01*
X876548Y969708D01*
X876840Y969958D01*
X877048Y970333D01*
X877131Y970708D01*
Y971167D01*
X877048Y971542D01*
X876840Y971875D01*
X876590Y972042D01*
X876298Y972125D01*
X875965Y972042D01*
X875715Y971875D01*
X875548Y971625D01*
X875465Y971292D01*
X875548Y971000D01*
X875756Y970708D01*
X876006Y970542D01*
X876298Y970500D01*
X876631Y970583D01*
X876881Y970792D01*
X877131Y971167D01*
G01X881133Y977892D02*
Y973892D01*
X888533D01*
G01X866165Y965625D02*
Y968125D01*
X867206D01*
X867540Y968000D01*
X867748Y967833D01*
X867831Y967500D01*
X867748Y967167D01*
X867498Y966958D01*
X867206Y966833D01*
X866165D01*
G01X867206D02*
X867831Y965625D01*
G01X870098D02*
Y968125D01*
X869598Y967625D01*
G01Y965625D02*
X870598D01*
G01X872281Y966125D02*
X872531Y965833D01*
X872865Y965667D01*
X873240Y965625D01*
X873573Y965667D01*
X873906Y965875D01*
X874115Y966125D01*
X874156Y966375D01*
X874073Y966667D01*
X873781Y966875D01*
X873490Y966958D01*
X873115D01*
G01X873490D02*
X873740Y967083D01*
X873948Y967292D01*
X874031Y967542D01*
X873948Y967792D01*
X873740Y968000D01*
X873365Y968125D01*
X872990Y968083D01*
X872615Y967917D01*
G01X876298Y965625D02*
Y968125D01*
X875798Y967625D01*
G01Y965625D02*
X876798D01*
G01X881133Y973892D02*
Y969892D01*
X888533D01*
G01X872969Y996841D02*
Y1158041D01*
X886569D01*
Y1170991D01*
X904769D01*
Y1158041D01*
X933669D01*
Y1147691D01*
X926969D01*
Y1007191D01*
X933669D01*
Y996841D01*
X904769D01*
Y983891D01*
X886569D01*
Y996841D01*
X872969D01*
G01X867989Y1091535D02*
X865489D01*
Y1092576D01*
X865614Y1092910D01*
X865781Y1093118D01*
X866114Y1093201D01*
X866447Y1093118D01*
X866656Y1092868D01*
X866781Y1092576D01*
Y1091535D01*
G01Y1092576D02*
X867989Y1093201D01*
G01Y1095468D02*
X865489D01*
X865989Y1094968D01*
G01X867989D02*
Y1095968D01*
G01X867489Y1097651D02*
X867781Y1097901D01*
X867947Y1098235D01*
X867989Y1098610D01*
X867947Y1098943D01*
X867739Y1099276D01*
X867489Y1099485D01*
X867239Y1099526D01*
X866947Y1099443D01*
X866739Y1099151D01*
X866656Y1098860D01*
Y1098485D01*
G01Y1098860D02*
X866531Y1099110D01*
X866322Y1099318D01*
X866072Y1099401D01*
X865822Y1099318D01*
X865614Y1099110D01*
X865489Y1098735D01*
X865531Y1098360D01*
X865697Y1097985D01*
G01X867989Y1102168D02*
X865489D01*
X867281Y1100626D01*
Y1102710D01*
G01X873516Y1336050D02*
Y1338550D01*
X874557D01*
X874891Y1338425D01*
X875099Y1338258D01*
X875182Y1337925D01*
X875099Y1337592D01*
X874849Y1337383D01*
X874557Y1337258D01*
X873516D01*
G01X874557D02*
X875182Y1336050D01*
G01X877449D02*
Y1338550D01*
X876949Y1338050D01*
G01Y1336050D02*
X877949D01*
G01X880549D02*
Y1338550D01*
X880049Y1338050D01*
G01Y1336050D02*
X881049D01*
G01X884149D02*
Y1338550D01*
X882607Y1336758D01*
X884691D01*
G01X873516Y1340050D02*
Y1342550D01*
X874557D01*
X874891Y1342425D01*
X875099Y1342258D01*
X875182Y1341925D01*
X875099Y1341592D01*
X874849Y1341383D01*
X874557Y1341258D01*
X873516D01*
G01X874557D02*
X875182Y1340050D01*
G01X877449D02*
Y1342550D01*
X876949Y1342050D01*
G01Y1340050D02*
X877949D01*
G01X880549D02*
Y1342550D01*
X880049Y1342050D01*
G01Y1340050D02*
X881049D01*
G01X882857Y1341092D02*
X883149Y1341383D01*
X883399Y1341550D01*
X883732Y1341633D01*
X884024Y1341550D01*
X884232Y1341383D01*
X884399Y1341133D01*
X884441Y1340842D01*
X884399Y1340592D01*
X884232Y1340342D01*
X883982Y1340133D01*
X883691Y1340050D01*
X883357Y1340133D01*
X883066Y1340383D01*
X882899Y1340758D01*
X882857Y1341175D01*
X882941Y1341717D01*
X883066Y1342008D01*
X883274Y1342300D01*
X883566Y1342508D01*
X883857Y1342550D01*
X884149Y1342467D01*
X884357Y1342258D01*
G01X875199Y1357550D02*
Y1361550D01*
X867799D01*
G01X873344Y1352796D02*
Y1355296D01*
X874385D01*
X874719Y1355171D01*
X874927Y1355004D01*
X875010Y1354671D01*
X874927Y1354338D01*
X874677Y1354129D01*
X874385Y1354004D01*
X873344D01*
G01X874385D02*
X875010Y1352796D01*
G01X877277D02*
Y1355296D01*
X876777Y1354796D01*
G01Y1352796D02*
X877777D01*
G01X880377D02*
Y1355296D01*
X879877Y1354796D01*
G01Y1352796D02*
X880877D01*
G01X882560Y1353171D02*
X882810Y1352963D01*
X883102Y1352838D01*
X883477Y1352796D01*
X883852Y1352879D01*
X884144Y1353046D01*
X884352Y1353338D01*
X884394Y1353671D01*
X884310Y1354004D01*
X884102Y1354213D01*
X883810Y1354379D01*
X883519Y1354421D01*
X883227Y1354379D01*
X882852Y1354213D01*
X882977Y1355296D01*
X884102D01*
G01X873344Y1348796D02*
Y1351296D01*
X874385D01*
X874719Y1351171D01*
X874927Y1351004D01*
X875010Y1350671D01*
X874927Y1350338D01*
X874677Y1350129D01*
X874385Y1350004D01*
X873344D01*
G01X874385D02*
X875010Y1348796D01*
G01X877277D02*
Y1351296D01*
X876777Y1350796D01*
G01Y1348796D02*
X877777D01*
G01X880377D02*
Y1351296D01*
X879877Y1350796D01*
G01Y1348796D02*
X880877D01*
G01X883394D02*
X883477Y1349338D01*
X883602Y1349796D01*
X883769Y1350213D01*
X883977Y1350671D01*
X884310Y1351296D01*
X882644D01*
G01X873516Y1344050D02*
Y1346550D01*
X874557D01*
X874891Y1346425D01*
X875099Y1346258D01*
X875182Y1345925D01*
X875099Y1345592D01*
X874849Y1345383D01*
X874557Y1345258D01*
X873516D01*
G01X874557D02*
X875182Y1344050D01*
G01X877449D02*
Y1346550D01*
X876949Y1346050D01*
G01Y1344050D02*
X877949D01*
G01X880549D02*
Y1346550D01*
X880049Y1346050D01*
G01Y1344050D02*
X881049D01*
G01X883649D02*
X883941Y1344092D01*
X884274Y1344217D01*
X884482Y1344425D01*
X884566Y1344717D01*
X884482Y1345008D01*
X884232Y1345258D01*
X883857Y1345383D01*
X883441D01*
X883191Y1345467D01*
X882982Y1345675D01*
X882899Y1345967D01*
X883024Y1346258D01*
X883316Y1346467D01*
X883649Y1346550D01*
X883982Y1346467D01*
X884274Y1346258D01*
X884399Y1345967D01*
X884316Y1345675D01*
X884107Y1345467D01*
X883857Y1345383D01*
X883441D01*
X883066Y1345258D01*
X882816Y1345008D01*
X882732Y1344717D01*
X882816Y1344425D01*
X883024Y1344217D01*
X883357Y1344092D01*
X883649Y1344050D01*
G01X875199Y1361550D02*
Y1365550D01*
X867799D01*
G01X867199Y1356300D02*
Y1369300D01*
G01X868127Y1381796D02*
Y1377796D01*
X875527D01*
G01X868127D02*
Y1373796D01*
X875527D01*
G01X875199Y1365550D02*
Y1369550D01*
X867799D01*
G01X872969Y1402353D02*
Y1563553D01*
X886569D01*
Y1576503D01*
X904769D01*
Y1563553D01*
X933669D01*
Y1553203D01*
X926969D01*
Y1412703D01*
X933669D01*
Y1402353D01*
X904769D01*
Y1389403D01*
X886569D01*
Y1402353D01*
X872969D01*
G01X866708Y1483267D02*
X866583Y1483017D01*
X866500Y1482725D01*
Y1482392D01*
X866625Y1482017D01*
X866833Y1481725D01*
X867083Y1481517D01*
X867500Y1481350D01*
X867875Y1481308D01*
X868250Y1481392D01*
X868500Y1481517D01*
X868750Y1481767D01*
X868917Y1482058D01*
X869000Y1482350D01*
Y1482642D01*
X868917Y1482933D01*
X868792Y1483183D01*
X868625Y1483392D01*
G01X869000Y1485450D02*
X866500D01*
X867000Y1484950D01*
G01X869000D02*
Y1485950D01*
G01X868500Y1487633D02*
X868792Y1487883D01*
X868958Y1488217D01*
X869000Y1488592D01*
X868958Y1488925D01*
X868750Y1489258D01*
X868500Y1489467D01*
X868250Y1489508D01*
X867958Y1489425D01*
X867750Y1489133D01*
X867667Y1488842D01*
Y1488467D01*
G01Y1488842D02*
X867542Y1489092D01*
X867333Y1489300D01*
X867083Y1489383D01*
X866833Y1489300D01*
X866625Y1489092D01*
X866500Y1488717D01*
X866542Y1488342D01*
X866708Y1487967D01*
G01X869000Y1491650D02*
X866500D01*
X867000Y1491150D01*
G01X869000D02*
Y1492150D01*
G01X867207Y1515317D02*
X867082Y1515067D01*
X866999Y1514775D01*
Y1514442D01*
X867124Y1514067D01*
X867332Y1513775D01*
X867582Y1513567D01*
X867999Y1513400D01*
X868374Y1513358D01*
X868749Y1513442D01*
X868999Y1513567D01*
X869249Y1513817D01*
X869416Y1514108D01*
X869499Y1514400D01*
Y1514692D01*
X869416Y1514983D01*
X869291Y1515233D01*
X869124Y1515442D01*
G01X869499Y1517500D02*
X866999D01*
X867499Y1517000D01*
G01X869499D02*
Y1518000D01*
G01X867416Y1519808D02*
X867166Y1520058D01*
X867041Y1520350D01*
X866999Y1520683D01*
X867082Y1521100D01*
X867291Y1521392D01*
X867541Y1521475D01*
X867791Y1521433D01*
X867999Y1521267D01*
X868416Y1520433D01*
X868707Y1520058D01*
X869124Y1519808D01*
X869499Y1519725D01*
Y1521475D01*
G01X867416Y1522908D02*
X867166Y1523158D01*
X867041Y1523450D01*
X866999Y1523783D01*
X867082Y1524200D01*
X867291Y1524492D01*
X867541Y1524575D01*
X867791Y1524533D01*
X867999Y1524367D01*
X868416Y1523533D01*
X868707Y1523158D01*
X869124Y1522908D01*
X869499Y1522825D01*
Y1524575D01*
G01X868999Y1529567D02*
X866499D01*
Y1530608D01*
X866624Y1530942D01*
X866791Y1531150D01*
X867124Y1531233D01*
X867457Y1531150D01*
X867666Y1530900D01*
X867791Y1530608D01*
Y1529567D01*
G01Y1530608D02*
X868999Y1531233D01*
G01Y1533500D02*
X866499D01*
X866999Y1533000D01*
G01X868999D02*
Y1534000D01*
G01X866916Y1535808D02*
X866666Y1536058D01*
X866541Y1536350D01*
X866499Y1536683D01*
X866582Y1537100D01*
X866791Y1537392D01*
X867041Y1537475D01*
X867291Y1537433D01*
X867499Y1537267D01*
X867916Y1536433D01*
X868207Y1536058D01*
X868624Y1535808D01*
X868999Y1535725D01*
Y1537475D01*
G01Y1540200D02*
X866499D01*
X868291Y1538658D01*
Y1540742D01*
G01X870000Y1693517D02*
X867500D01*
Y1694517D01*
X867625Y1694850D01*
X867917Y1695100D01*
X868250Y1695183D01*
X868583Y1695100D01*
X868833Y1694892D01*
X868958Y1694517D01*
Y1693517D01*
G01X867708Y1698367D02*
X867583Y1698117D01*
X867500Y1697825D01*
Y1697492D01*
X867625Y1697117D01*
X867833Y1696825D01*
X868083Y1696617D01*
X868500Y1696450D01*
X868875Y1696408D01*
X869250Y1696492D01*
X869500Y1696617D01*
X869750Y1696867D01*
X869917Y1697158D01*
X870000Y1697450D01*
Y1697742D01*
X869917Y1698033D01*
X869792Y1698283D01*
X869625Y1698492D01*
G01X870000Y1701050D02*
X867500D01*
X869292Y1699508D01*
Y1701592D01*
G01X870000Y1703650D02*
X867500D01*
X868000Y1703150D01*
G01X870000D02*
Y1704150D01*
G01X877017Y1684000D02*
Y1686500D01*
X878017D01*
X878350Y1686375D01*
X878600Y1686083D01*
X878683Y1685750D01*
X878600Y1685417D01*
X878392Y1685167D01*
X878017Y1685042D01*
X877017D01*
G01X880117Y1684000D02*
Y1686500D01*
X881158D01*
X881492Y1686375D01*
X881700Y1686208D01*
X881783Y1685875D01*
X881700Y1685542D01*
X881450Y1685333D01*
X881158Y1685208D01*
X880117D01*
G01X881158D02*
X881783Y1684000D01*
G01X883133Y1684375D02*
X883383Y1684167D01*
X883675Y1684042D01*
X884050Y1684000D01*
X884425Y1684083D01*
X884717Y1684250D01*
X884925Y1684542D01*
X884967Y1684875D01*
X884883Y1685208D01*
X884675Y1685417D01*
X884383Y1685583D01*
X884092Y1685625D01*
X883800Y1685583D01*
X883425Y1685417D01*
X883550Y1686500D01*
X884675D01*
G01X886358Y1685042D02*
X886650Y1685333D01*
X886900Y1685500D01*
X887233Y1685583D01*
X887525Y1685500D01*
X887733Y1685333D01*
X887900Y1685083D01*
X887942Y1684792D01*
X887900Y1684542D01*
X887733Y1684292D01*
X887483Y1684083D01*
X887192Y1684000D01*
X886858Y1684083D01*
X886567Y1684333D01*
X886400Y1684708D01*
X886358Y1685125D01*
X886442Y1685667D01*
X886567Y1685958D01*
X886775Y1686250D01*
X887067Y1686458D01*
X887358Y1686500D01*
X887650Y1686417D01*
X887858Y1686208D01*
G01X876983Y1690500D02*
Y1688708D01*
X877150Y1688333D01*
X877483Y1688083D01*
X877900Y1688000D01*
X878317Y1688083D01*
X878650Y1688333D01*
X878817Y1688708D01*
Y1690500D01*
G01X880083Y1688375D02*
X880333Y1688167D01*
X880625Y1688042D01*
X881000Y1688000D01*
X881375Y1688083D01*
X881667Y1688250D01*
X881875Y1688542D01*
X881917Y1688875D01*
X881833Y1689208D01*
X881625Y1689417D01*
X881333Y1689583D01*
X881042Y1689625D01*
X880750Y1689583D01*
X880375Y1689417D01*
X880500Y1690500D01*
X881625D01*
G01X884600Y1688000D02*
Y1690500D01*
X883058Y1688708D01*
X885142D01*
G01X876401Y1722950D02*
Y1718950D01*
X883801D01*
G01X883901Y1722950D02*
Y1718950D01*
X891301D01*
G01X873600Y1709199D02*
X872000Y1707599D01*
G01Y1710799D02*
X873600Y1709199D01*
G01X872000Y1711499D02*
Y1706899D01*
G01X886500Y1711499D02*
X872000D01*
G01Y1706899D02*
X886500D01*
G01X886000Y1731300D02*
X891500D01*
Y1723300D01*
X885900D01*
G01X873900Y1731300D02*
Y1723300D01*
X879400D01*
G01X873900Y1731300D02*
X879400D01*
G01X885800Y1731600D02*
Y1736800D01*
X875000D01*
G01X868117Y1784800D02*
Y1787300D01*
X869158D01*
X869492Y1787175D01*
X869700Y1787008D01*
X869783Y1786675D01*
X869700Y1786342D01*
X869450Y1786133D01*
X869158Y1786008D01*
X868117D01*
G01X869158D02*
X869783Y1784800D01*
G01X872050D02*
Y1787300D01*
X871550Y1786800D01*
G01Y1784800D02*
X872550D01*
G01X875150Y1787300D02*
X874817Y1787217D01*
X874567Y1787008D01*
X874400Y1786758D01*
X874275Y1786425D01*
X874233Y1786050D01*
X874275Y1785675D01*
X874400Y1785342D01*
X874567Y1785092D01*
X874817Y1784883D01*
X875150Y1784800D01*
X875483Y1784883D01*
X875733Y1785092D01*
X875900Y1785342D01*
X876025Y1785675D01*
X876067Y1786050D01*
X876025Y1786425D01*
X875900Y1786758D01*
X875733Y1787008D01*
X875483Y1787217D01*
X875150Y1787300D01*
G01X877458Y1786883D02*
X877708Y1787133D01*
X878000Y1787258D01*
X878333Y1787300D01*
X878750Y1787217D01*
X879042Y1787008D01*
X879125Y1786758D01*
X879083Y1786508D01*
X878917Y1786300D01*
X878083Y1785883D01*
X877708Y1785592D01*
X877458Y1785175D01*
X877375Y1784800D01*
X879125D01*
G01X880900Y1788300D02*
Y1784300D01*
X888300D01*
G01X868081Y1780713D02*
Y1783213D01*
X869122D01*
X869456Y1783088D01*
X869664Y1782921D01*
X869747Y1782588D01*
X869664Y1782255D01*
X869414Y1782046D01*
X869122Y1781921D01*
X868081D01*
G01X869122D02*
X869747Y1780713D01*
G01X872014D02*
Y1783213D01*
X871514Y1782713D01*
G01Y1780713D02*
X872514D01*
G01X875114Y1783213D02*
X874781Y1783130D01*
X874531Y1782921D01*
X874364Y1782671D01*
X874239Y1782338D01*
X874197Y1781963D01*
X874239Y1781588D01*
X874364Y1781255D01*
X874531Y1781005D01*
X874781Y1780796D01*
X875114Y1780713D01*
X875447Y1780796D01*
X875697Y1781005D01*
X875864Y1781255D01*
X875989Y1781588D01*
X876031Y1781963D01*
X875989Y1782338D01*
X875864Y1782671D01*
X875697Y1782921D01*
X875447Y1783130D01*
X875114Y1783213D01*
G01X878714Y1780713D02*
Y1783213D01*
X877172Y1781421D01*
X879256D01*
G01X880864Y1784213D02*
Y1780213D01*
X888264D01*
G01X872969Y1807865D02*
Y1969065D01*
X886569D01*
Y1982015D01*
X904769D01*
Y1969065D01*
X933669D01*
Y1958715D01*
X926969D01*
Y1818215D01*
X933669D01*
Y1807865D01*
X904769D01*
Y1794915D01*
X886569D01*
Y1807865D01*
X872969D01*
G01X867208Y1890767D02*
X867083Y1890517D01*
X867000Y1890225D01*
Y1889892D01*
X867125Y1889517D01*
X867333Y1889225D01*
X867583Y1889017D01*
X868000Y1888850D01*
X868375Y1888808D01*
X868750Y1888892D01*
X869000Y1889017D01*
X869250Y1889267D01*
X869417Y1889558D01*
X869500Y1889850D01*
Y1890142D01*
X869417Y1890433D01*
X869292Y1890683D01*
X869125Y1890892D01*
G01X869500Y1892950D02*
X867000D01*
X867500Y1892450D01*
G01X869500D02*
Y1893450D01*
G01X867000Y1896050D02*
X867083Y1895717D01*
X867292Y1895467D01*
X867542Y1895300D01*
X867875Y1895175D01*
X868250Y1895133D01*
X868625Y1895175D01*
X868958Y1895300D01*
X869208Y1895467D01*
X869417Y1895717D01*
X869500Y1896050D01*
X869417Y1896383D01*
X869208Y1896633D01*
X868958Y1896800D01*
X868625Y1896925D01*
X868250Y1896967D01*
X867875Y1896925D01*
X867542Y1896800D01*
X867292Y1896633D01*
X867083Y1896383D01*
X867000Y1896050D01*
G01X869500Y1899150D02*
X869458Y1899442D01*
X869333Y1899775D01*
X869125Y1899983D01*
X868833Y1900067D01*
X868542Y1899983D01*
X868292Y1899733D01*
X868167Y1899358D01*
Y1898942D01*
X868083Y1898692D01*
X867875Y1898483D01*
X867583Y1898400D01*
X867292Y1898525D01*
X867083Y1898817D01*
X867000Y1899150D01*
X867083Y1899483D01*
X867292Y1899775D01*
X867583Y1899900D01*
X867875Y1899817D01*
X868083Y1899608D01*
X868167Y1899358D01*
Y1898942D01*
X868292Y1898567D01*
X868542Y1898317D01*
X868833Y1898233D01*
X869125Y1898317D01*
X869333Y1898525D01*
X869458Y1898858D01*
X869500Y1899150D01*
G01X865207Y1922317D02*
X865082Y1922067D01*
X864999Y1921775D01*
Y1921442D01*
X865124Y1921067D01*
X865332Y1920775D01*
X865582Y1920567D01*
X865999Y1920400D01*
X866374Y1920358D01*
X866749Y1920442D01*
X866999Y1920567D01*
X867249Y1920817D01*
X867416Y1921108D01*
X867499Y1921400D01*
Y1921692D01*
X867416Y1921983D01*
X867291Y1922233D01*
X867124Y1922442D01*
G01X867499Y1924500D02*
X864999D01*
X865499Y1924000D01*
G01X867499D02*
Y1925000D01*
G01X864999Y1927600D02*
X865082Y1927267D01*
X865291Y1927017D01*
X865541Y1926850D01*
X865874Y1926725D01*
X866249Y1926683D01*
X866624Y1926725D01*
X866957Y1926850D01*
X867207Y1927017D01*
X867416Y1927267D01*
X867499Y1927600D01*
X867416Y1927933D01*
X867207Y1928183D01*
X866957Y1928350D01*
X866624Y1928475D01*
X866249Y1928517D01*
X865874Y1928475D01*
X865541Y1928350D01*
X865291Y1928183D01*
X865082Y1927933D01*
X864999Y1927600D01*
G01X866457Y1929908D02*
X866166Y1930200D01*
X865999Y1930450D01*
X865916Y1930783D01*
X865999Y1931075D01*
X866166Y1931283D01*
X866416Y1931450D01*
X866707Y1931492D01*
X866957Y1931450D01*
X867207Y1931283D01*
X867416Y1931033D01*
X867499Y1930742D01*
X867416Y1930408D01*
X867166Y1930117D01*
X866791Y1929950D01*
X866374Y1929908D01*
X865832Y1929992D01*
X865541Y1930117D01*
X865249Y1930325D01*
X865041Y1930617D01*
X864999Y1930908D01*
X865082Y1931200D01*
X865291Y1931408D01*
G01X868000Y1935517D02*
X865500D01*
Y1936558D01*
X865625Y1936892D01*
X865792Y1937100D01*
X866125Y1937183D01*
X866458Y1937100D01*
X866667Y1936850D01*
X866792Y1936558D01*
Y1935517D01*
G01Y1936558D02*
X868000Y1937183D01*
G01Y1939450D02*
X865500D01*
X866000Y1938950D01*
G01X868000D02*
Y1939950D01*
G01Y1942550D02*
X865500D01*
X866000Y1942050D01*
G01X868000D02*
Y1943050D01*
G01X865500Y1945650D02*
X865583Y1945317D01*
X865792Y1945067D01*
X866042Y1944900D01*
X866375Y1944775D01*
X866750Y1944733D01*
X867125Y1944775D01*
X867458Y1944900D01*
X867708Y1945067D01*
X867917Y1945317D01*
X868000Y1945650D01*
X867917Y1945983D01*
X867708Y1946233D01*
X867458Y1946400D01*
X867125Y1946525D01*
X866750Y1946567D01*
X866375Y1946525D01*
X866042Y1946400D01*
X865792Y1946233D01*
X865583Y1945983D01*
X865500Y1945650D01*
G01X906499Y59617D02*
X903999D01*
Y60617D01*
X904124Y60950D01*
X904416Y61200D01*
X904749Y61283D01*
X905082Y61200D01*
X905332Y60992D01*
X905457Y60617D01*
Y59617D01*
G01X904207Y64467D02*
X904082Y64217D01*
X903999Y63925D01*
Y63592D01*
X904124Y63217D01*
X904332Y62925D01*
X904582Y62717D01*
X904999Y62550D01*
X905374Y62508D01*
X905749Y62592D01*
X905999Y62717D01*
X906249Y62967D01*
X906416Y63258D01*
X906499Y63550D01*
Y63842D01*
X906416Y64133D01*
X906291Y64383D01*
X906124Y64592D01*
G01X906499Y66567D02*
X905957Y66650D01*
X905499Y66775D01*
X905082Y66942D01*
X904624Y67150D01*
X903999Y67483D01*
Y65817D01*
G01X901999Y56567D02*
X899499D01*
Y57567D01*
X899624Y57900D01*
X899916Y58150D01*
X900249Y58233D01*
X900582Y58150D01*
X900832Y57942D01*
X900957Y57567D01*
Y56567D01*
G01X901999Y59667D02*
X899499D01*
Y60708D01*
X899624Y61042D01*
X899791Y61250D01*
X900124Y61333D01*
X900457Y61250D01*
X900666Y61000D01*
X900791Y60708D01*
Y59667D01*
G01Y60708D02*
X901999Y61333D01*
G01Y64100D02*
X899499D01*
X901291Y62558D01*
Y64642D01*
G01X901707Y65992D02*
X901916Y66283D01*
X901999Y66617D01*
X901916Y66950D01*
X901666Y67242D01*
X901291Y67450D01*
X900916Y67533D01*
X900457D01*
X900082Y67450D01*
X899749Y67242D01*
X899582Y66992D01*
X899499Y66700D01*
X899582Y66367D01*
X899749Y66117D01*
X899999Y65950D01*
X900332Y65867D01*
X900624Y65950D01*
X900916Y66158D01*
X901082Y66408D01*
X901124Y66700D01*
X901041Y67033D01*
X900832Y67283D01*
X900457Y67533D01*
G01X899566Y69550D02*
Y72050D01*
X900566D01*
X900899Y71925D01*
X901149Y71633D01*
X901232Y71300D01*
X901149Y70967D01*
X900941Y70717D01*
X900566Y70592D01*
X899566D01*
G01X902666Y69550D02*
Y72050D01*
X903707D01*
X904041Y71925D01*
X904249Y71758D01*
X904332Y71425D01*
X904249Y71092D01*
X903999Y70883D01*
X903707Y70758D01*
X902666D01*
G01X903707D02*
X904332Y69550D01*
G01X906599D02*
X906891Y69592D01*
X907224Y69717D01*
X907432Y69925D01*
X907516Y70217D01*
X907432Y70508D01*
X907182Y70758D01*
X906807Y70883D01*
X906391D01*
X906141Y70967D01*
X905932Y71175D01*
X905849Y71467D01*
X905974Y71758D01*
X906266Y71967D01*
X906599Y72050D01*
X906932Y71967D01*
X907224Y71758D01*
X907349Y71467D01*
X907266Y71175D01*
X907057Y70967D01*
X906807Y70883D01*
X906391D01*
X906016Y70758D01*
X905766Y70508D01*
X905682Y70217D01*
X905766Y69925D01*
X905974Y69717D01*
X906307Y69592D01*
X906599Y69550D01*
G01X899566Y73550D02*
Y76050D01*
X900566D01*
X900899Y75925D01*
X901149Y75633D01*
X901232Y75300D01*
X901149Y74967D01*
X900941Y74717D01*
X900566Y74592D01*
X899566D01*
G01X902666Y73550D02*
Y76050D01*
X903707D01*
X904041Y75925D01*
X904249Y75758D01*
X904332Y75425D01*
X904249Y75092D01*
X903999Y74883D01*
X903707Y74758D01*
X902666D01*
G01X903707D02*
X904332Y73550D01*
G01X905891Y73842D02*
X906182Y73633D01*
X906516Y73550D01*
X906849Y73633D01*
X907141Y73883D01*
X907349Y74258D01*
X907432Y74633D01*
Y75092D01*
X907349Y75467D01*
X907141Y75800D01*
X906891Y75967D01*
X906599Y76050D01*
X906266Y75967D01*
X906016Y75800D01*
X905849Y75550D01*
X905766Y75217D01*
X905849Y74925D01*
X906057Y74633D01*
X906307Y74467D01*
X906599Y74425D01*
X906932Y74508D01*
X907182Y74717D01*
X907432Y75092D01*
G01X899516Y77550D02*
Y80050D01*
X900516D01*
X900849Y79925D01*
X901099Y79633D01*
X901182Y79300D01*
X901099Y78967D01*
X900891Y78717D01*
X900516Y78592D01*
X899516D01*
G01X902616Y77550D02*
Y80050D01*
X903657D01*
X903991Y79925D01*
X904199Y79758D01*
X904282Y79425D01*
X904199Y79092D01*
X903949Y78883D01*
X903657Y78758D01*
X902616D01*
G01X903657D02*
X904282Y77550D01*
G01X906549D02*
Y80050D01*
X906049Y79550D01*
G01Y77550D02*
X907049D01*
G01X908732Y77925D02*
X908982Y77717D01*
X909274Y77592D01*
X909649Y77550D01*
X910024Y77633D01*
X910316Y77800D01*
X910524Y78092D01*
X910566Y78425D01*
X910482Y78758D01*
X910274Y78967D01*
X909982Y79133D01*
X909691Y79175D01*
X909399Y79133D01*
X909024Y78967D01*
X909149Y80050D01*
X910274D01*
G01X898499Y82850D02*
X902499D01*
Y90250D01*
G01X888549Y94950D02*
Y92450D01*
G01X887591Y94950D02*
X889507D01*
G01X890816Y92450D02*
Y94950D01*
X891816D01*
X892149Y94825D01*
X892399Y94533D01*
X892482Y94200D01*
X892399Y93867D01*
X892191Y93617D01*
X891816Y93492D01*
X890816D01*
G01X893957Y94533D02*
X894207Y94783D01*
X894499Y94908D01*
X894832Y94950D01*
X895249Y94867D01*
X895541Y94658D01*
X895624Y94408D01*
X895582Y94158D01*
X895416Y93950D01*
X894582Y93533D01*
X894207Y93242D01*
X893957Y92825D01*
X893874Y92450D01*
X895624D01*
G01X897057Y94533D02*
X897307Y94783D01*
X897599Y94908D01*
X897932Y94950D01*
X898349Y94867D01*
X898641Y94658D01*
X898724Y94408D01*
X898682Y94158D01*
X898516Y93950D01*
X897682Y93533D01*
X897307Y93242D01*
X897057Y92825D01*
X896974Y92450D01*
X898724D01*
G01X907699Y105050D02*
Y109050D01*
X900299D01*
G01Y101050D02*
Y97050D01*
X907699D01*
G01Y101050D02*
Y105050D01*
X900299D01*
G01X888303Y104929D02*
Y102429D01*
G01X887345Y104929D02*
X889261D01*
G01X890570Y102429D02*
Y104929D01*
X891570D01*
X891903Y104804D01*
X892153Y104512D01*
X892236Y104179D01*
X892153Y103846D01*
X891945Y103596D01*
X891570Y103471D01*
X890570D01*
G01X894503Y102429D02*
Y104929D01*
X894003Y104429D01*
G01Y102429D02*
X895003D01*
G01X896895Y102721D02*
X897186Y102512D01*
X897520Y102429D01*
X897853Y102512D01*
X898145Y102762D01*
X898353Y103137D01*
X898436Y103512D01*
Y103971D01*
X898353Y104346D01*
X898145Y104679D01*
X897895Y104846D01*
X897603Y104929D01*
X897270Y104846D01*
X897020Y104679D01*
X896853Y104429D01*
X896770Y104096D01*
X896853Y103804D01*
X897061Y103512D01*
X897311Y103346D01*
X897603Y103304D01*
X897936Y103387D01*
X898186Y103596D01*
X898436Y103971D01*
G01X891499Y107850D02*
Y119050D01*
G01X907066Y129050D02*
Y131550D01*
X908066D01*
X908399Y131425D01*
X908649Y131133D01*
X908732Y130800D01*
X908649Y130467D01*
X908441Y130217D01*
X908066Y130092D01*
X907066D01*
G01X911916Y131342D02*
X911666Y131467D01*
X911374Y131550D01*
X911041D01*
X910666Y131425D01*
X910374Y131217D01*
X910166Y130967D01*
X909999Y130550D01*
X909957Y130175D01*
X910041Y129800D01*
X910166Y129550D01*
X910416Y129300D01*
X910707Y129133D01*
X910999Y129050D01*
X911291D01*
X911582Y129133D01*
X911832Y129258D01*
X912041Y129425D01*
G01X914099Y129050D02*
X914391Y129092D01*
X914724Y129217D01*
X914932Y129425D01*
X915016Y129717D01*
X914932Y130008D01*
X914682Y130258D01*
X914307Y130383D01*
X913891D01*
X913641Y130467D01*
X913432Y130675D01*
X913349Y130967D01*
X913474Y131258D01*
X913766Y131467D01*
X914099Y131550D01*
X914432Y131467D01*
X914724Y131258D01*
X914849Y130967D01*
X914766Y130675D01*
X914557Y130467D01*
X914307Y130383D01*
X913891D01*
X913516Y130258D01*
X913266Y130008D01*
X913182Y129717D01*
X913266Y129425D01*
X913474Y129217D01*
X913807Y129092D01*
X914099Y129050D01*
G01X899066Y118550D02*
Y121050D01*
X900066D01*
X900399Y120925D01*
X900649Y120633D01*
X900732Y120300D01*
X900649Y119967D01*
X900441Y119717D01*
X900066Y119592D01*
X899066D01*
G01X902166Y118550D02*
Y121050D01*
X903207D01*
X903541Y120925D01*
X903749Y120758D01*
X903832Y120425D01*
X903749Y120092D01*
X903499Y119883D01*
X903207Y119758D01*
X902166D01*
G01X903207D02*
X903832Y118550D01*
G01X906599D02*
Y121050D01*
X905057Y119258D01*
X907141D01*
G01X892999Y122250D02*
Y127750D01*
G01X900999Y122250D02*
X892999D01*
G01X900999Y127750D02*
Y122250D01*
G01Y139850D02*
Y134350D01*
G01X892999D02*
Y139850D01*
G01X905499Y136117D02*
X902999D01*
Y137117D01*
X903124Y137450D01*
X903416Y137700D01*
X903749Y137783D01*
X904082Y137700D01*
X904332Y137492D01*
X904457Y137117D01*
Y136117D01*
G01X905499Y139217D02*
X902999D01*
Y140258D01*
X903124Y140592D01*
X903291Y140800D01*
X903624Y140883D01*
X903957Y140800D01*
X904166Y140550D01*
X904291Y140258D01*
Y139217D01*
G01Y140258D02*
X905499Y140883D01*
G01X904457Y142358D02*
X904166Y142650D01*
X903999Y142900D01*
X903916Y143233D01*
X903999Y143525D01*
X904166Y143733D01*
X904416Y143900D01*
X904707Y143942D01*
X904957Y143900D01*
X905207Y143733D01*
X905416Y143483D01*
X905499Y143192D01*
X905416Y142858D01*
X905166Y142567D01*
X904791Y142400D01*
X904374Y142358D01*
X903832Y142442D01*
X903541Y142567D01*
X903249Y142775D01*
X903041Y143067D01*
X902999Y143358D01*
X903082Y143650D01*
X903291Y143858D01*
G01X901499Y126350D02*
X905499D01*
Y133750D01*
G01X891499Y146250D02*
Y135050D01*
G01X901999Y142067D02*
X899499D01*
Y143067D01*
X899624Y143400D01*
X899916Y143650D01*
X900249Y143733D01*
X900582Y143650D01*
X900832Y143442D01*
X900957Y143067D01*
Y142067D01*
G01X899707Y146917D02*
X899582Y146667D01*
X899499Y146375D01*
Y146042D01*
X899624Y145667D01*
X899832Y145375D01*
X900082Y145167D01*
X900499Y145000D01*
X900874Y144958D01*
X901249Y145042D01*
X901499Y145167D01*
X901749Y145417D01*
X901916Y145708D01*
X901999Y146000D01*
Y146292D01*
X901916Y146583D01*
X901791Y146833D01*
X901624Y147042D01*
G01X901999Y149100D02*
X899499D01*
X899999Y148600D01*
G01X901999D02*
Y149600D01*
G01X899916Y151408D02*
X899666Y151658D01*
X899541Y151950D01*
X899499Y152283D01*
X899582Y152700D01*
X899791Y152992D01*
X900041Y153075D01*
X900291Y153033D01*
X900499Y152867D01*
X900916Y152033D01*
X901207Y151658D01*
X901624Y151408D01*
X901999Y151325D01*
Y153075D01*
G01X892999Y139850D02*
X900999D01*
G01X890517Y170563D02*
Y168063D01*
X892183D01*
G01X895283D02*
X893617D01*
Y170563D01*
X895283D01*
G01X894617Y169355D02*
X893617D01*
G01X896633Y168063D02*
Y170563D01*
X897467D01*
X897800Y170438D01*
X898050Y170271D01*
X898258Y170021D01*
X898425Y169730D01*
X898467Y169313D01*
X898425Y168896D01*
X898258Y168605D01*
X898050Y168355D01*
X897800Y168188D01*
X897467Y168063D01*
X896633D01*
G01X899733Y168438D02*
X899983Y168230D01*
X900275Y168105D01*
X900650Y168063D01*
X901025Y168146D01*
X901317Y168313D01*
X901525Y168605D01*
X901567Y168938D01*
X901483Y169271D01*
X901275Y169480D01*
X900983Y169646D01*
X900692Y169688D01*
X900400Y169646D01*
X900025Y169480D01*
X900150Y170563D01*
X901275D01*
G01X901369Y165847D02*
Y158247D01*
X889969D01*
Y165847D01*
X901369D01*
G01X907296Y175854D02*
Y178354D01*
X908337D01*
X908671Y178229D01*
X908879Y178062D01*
X908962Y177729D01*
X908879Y177396D01*
X908629Y177187D01*
X908337Y177062D01*
X907296D01*
G01X908337D02*
X908962Y175854D01*
G01X911229D02*
Y178354D01*
X910729Y177854D01*
G01Y175854D02*
X911729D01*
G01X913412Y176229D02*
X913662Y176021D01*
X913954Y175896D01*
X914329Y175854D01*
X914704Y175937D01*
X914996Y176104D01*
X915204Y176396D01*
X915246Y176729D01*
X915162Y177062D01*
X914954Y177271D01*
X914662Y177437D01*
X914371Y177479D01*
X914079Y177437D01*
X913704Y177271D01*
X913829Y178354D01*
X914954D01*
G01X917429Y175854D02*
X917721Y175896D01*
X918054Y176021D01*
X918262Y176229D01*
X918346Y176521D01*
X918262Y176812D01*
X918012Y177062D01*
X917637Y177187D01*
X917221D01*
X916971Y177271D01*
X916762Y177479D01*
X916679Y177771D01*
X916804Y178062D01*
X917096Y178271D01*
X917429Y178354D01*
X917762Y178271D01*
X918054Y178062D01*
X918179Y177771D01*
X918096Y177479D01*
X917887Y177271D01*
X917637Y177187D01*
X917221D01*
X916846Y177062D01*
X916596Y176812D01*
X916512Y176521D01*
X916596Y176229D01*
X916804Y176021D01*
X917137Y175896D01*
X917429Y175854D01*
G01X907296Y171854D02*
Y174354D01*
X908337D01*
X908671Y174229D01*
X908879Y174062D01*
X908962Y173729D01*
X908879Y173396D01*
X908629Y173187D01*
X908337Y173062D01*
X907296D01*
G01X908337D02*
X908962Y171854D01*
G01X911229D02*
Y174354D01*
X910729Y173854D01*
G01Y171854D02*
X911729D01*
G01X913537Y172896D02*
X913829Y173187D01*
X914079Y173354D01*
X914412Y173437D01*
X914704Y173354D01*
X914912Y173187D01*
X915079Y172937D01*
X915121Y172646D01*
X915079Y172396D01*
X914912Y172146D01*
X914662Y171937D01*
X914371Y171854D01*
X914037Y171937D01*
X913746Y172187D01*
X913579Y172562D01*
X913537Y172979D01*
X913621Y173521D01*
X913746Y173812D01*
X913954Y174104D01*
X914246Y174312D01*
X914537Y174354D01*
X914829Y174271D01*
X915037Y174062D01*
G01X917429Y174354D02*
X917096Y174271D01*
X916846Y174062D01*
X916679Y173812D01*
X916554Y173479D01*
X916512Y173104D01*
X916554Y172729D01*
X916679Y172396D01*
X916846Y172146D01*
X917096Y171937D01*
X917429Y171854D01*
X917762Y171937D01*
X918012Y172146D01*
X918179Y172396D01*
X918304Y172729D01*
X918346Y173104D01*
X918304Y173479D01*
X918179Y173812D01*
X918012Y174062D01*
X917762Y174271D01*
X917429Y174354D01*
G01X907067Y179980D02*
Y182480D01*
X908108D01*
X908442Y182355D01*
X908650Y182188D01*
X908733Y181855D01*
X908650Y181522D01*
X908400Y181313D01*
X908108Y181188D01*
X907067D01*
G01X908108D02*
X908733Y179980D01*
G01X911000D02*
Y182480D01*
X910500Y181980D01*
G01Y179980D02*
X911500D01*
G01X913183Y180355D02*
X913433Y180147D01*
X913725Y180022D01*
X914100Y179980D01*
X914475Y180063D01*
X914767Y180230D01*
X914975Y180522D01*
X915017Y180855D01*
X914933Y181188D01*
X914725Y181397D01*
X914433Y181563D01*
X914142Y181605D01*
X913850Y181563D01*
X913475Y181397D01*
X913600Y182480D01*
X914725D01*
G01X916408Y181022D02*
X916700Y181313D01*
X916950Y181480D01*
X917283Y181563D01*
X917575Y181480D01*
X917783Y181313D01*
X917950Y181063D01*
X917992Y180772D01*
X917950Y180522D01*
X917783Y180272D01*
X917533Y180063D01*
X917242Y179980D01*
X916908Y180063D01*
X916617Y180313D01*
X916450Y180688D01*
X916408Y181105D01*
X916492Y181647D01*
X916617Y181938D01*
X916825Y182230D01*
X917117Y182438D01*
X917408Y182480D01*
X917700Y182397D01*
X917908Y182188D01*
G01X890918Y555493D02*
Y552993D01*
X892584D01*
G01X895684D02*
X894018D01*
Y555493D01*
X895684D01*
G01X895018Y554285D02*
X894018D01*
G01X897034Y552993D02*
Y555493D01*
X897868D01*
X898201Y555368D01*
X898451Y555201D01*
X898659Y554951D01*
X898826Y554660D01*
X898868Y554243D01*
X898826Y553826D01*
X898659Y553535D01*
X898451Y553285D01*
X898201Y553118D01*
X897868Y552993D01*
X897034D01*
G01X901551D02*
Y555493D01*
X900009Y553701D01*
X902093D01*
G01X901369Y571359D02*
Y563759D01*
X889969D01*
Y571359D01*
X901369D01*
G01X903246Y572882D02*
Y568882D01*
X910646D01*
G01X907463Y579882D02*
Y582382D01*
X908504D01*
X908838Y582257D01*
X909046Y582090D01*
X909129Y581757D01*
X909046Y581424D01*
X908796Y581215D01*
X908504Y581090D01*
X907463D01*
G01X908504D02*
X909129Y579882D01*
G01X911396D02*
Y582382D01*
X910896Y581882D01*
G01Y579882D02*
X911896D01*
G01X914996D02*
Y582382D01*
X913454Y580590D01*
X915538D01*
G01X918096Y579882D02*
Y582382D01*
X916554Y580590D01*
X918638D01*
G01X903246Y568882D02*
Y564882D01*
X910646D01*
G01X907463Y575882D02*
Y578382D01*
X908504D01*
X908838Y578257D01*
X909046Y578090D01*
X909129Y577757D01*
X909046Y577424D01*
X908796Y577215D01*
X908504Y577090D01*
X907463D01*
G01X908504D02*
X909129Y575882D01*
G01X911396D02*
Y578382D01*
X910896Y577882D01*
G01Y575882D02*
X911896D01*
G01X914996D02*
Y578382D01*
X913454Y576590D01*
X915538D01*
G01X916804Y576924D02*
X917096Y577215D01*
X917346Y577382D01*
X917679Y577465D01*
X917971Y577382D01*
X918179Y577215D01*
X918346Y576965D01*
X918388Y576674D01*
X918346Y576424D01*
X918179Y576174D01*
X917929Y575965D01*
X917638Y575882D01*
X917304Y575965D01*
X917013Y576215D01*
X916846Y576590D01*
X916804Y577007D01*
X916888Y577549D01*
X917013Y577840D01*
X917221Y578132D01*
X917513Y578340D01*
X917804Y578382D01*
X918096Y578299D01*
X918304Y578090D01*
G01X903246Y564882D02*
Y560882D01*
X910646D01*
G01X907463Y583882D02*
Y586382D01*
X908504D01*
X908838Y586257D01*
X909046Y586090D01*
X909129Y585757D01*
X909046Y585424D01*
X908796Y585215D01*
X908504Y585090D01*
X907463D01*
G01X908504D02*
X909129Y583882D01*
G01X911396D02*
Y586382D01*
X910896Y585882D01*
G01Y583882D02*
X911896D01*
G01X914996D02*
Y586382D01*
X913454Y584590D01*
X915538D01*
G01X916804Y585965D02*
X917054Y586215D01*
X917346Y586340D01*
X917679Y586382D01*
X918096Y586299D01*
X918388Y586090D01*
X918471Y585840D01*
X918429Y585590D01*
X918263Y585382D01*
X917429Y584965D01*
X917054Y584674D01*
X916804Y584257D01*
X916721Y583882D01*
X918471D01*
G01X890990Y960037D02*
Y957537D01*
X892656D01*
G01X895756D02*
X894090D01*
Y960037D01*
X895756D01*
G01X895090Y958829D02*
X894090D01*
G01X897106Y957537D02*
Y960037D01*
X897940D01*
X898273Y959912D01*
X898523Y959745D01*
X898731Y959495D01*
X898898Y959204D01*
X898940Y958787D01*
X898898Y958370D01*
X898731Y958079D01*
X898523Y957829D01*
X898273Y957662D01*
X897940Y957537D01*
X897106D01*
G01X900206Y958037D02*
X900456Y957745D01*
X900790Y957579D01*
X901165Y957537D01*
X901498Y957579D01*
X901831Y957787D01*
X902040Y958037D01*
X902081Y958287D01*
X901998Y958579D01*
X901706Y958787D01*
X901415Y958870D01*
X901040D01*
G01X901415D02*
X901665Y958995D01*
X901873Y959204D01*
X901956Y959454D01*
X901873Y959704D01*
X901665Y959912D01*
X901290Y960037D01*
X900915Y959995D01*
X900540Y959829D01*
G01X901369Y976871D02*
Y969271D01*
X889969D01*
Y976871D01*
X901369D01*
G01X903133Y976392D02*
Y972392D01*
X910533D01*
G01X903133D02*
Y968392D01*
X910533D01*
G01X903133D02*
Y964392D01*
X910533D01*
G01X892017Y1371063D02*
Y1368563D01*
X893683D01*
G01X896783D02*
X895117D01*
Y1371063D01*
X896783D01*
G01X896117Y1369855D02*
X895117D01*
G01X898133Y1368563D02*
Y1371063D01*
X898967D01*
X899300Y1370938D01*
X899550Y1370771D01*
X899758Y1370521D01*
X899925Y1370230D01*
X899967Y1369813D01*
X899925Y1369396D01*
X899758Y1369105D01*
X899550Y1368855D01*
X899300Y1368688D01*
X898967Y1368563D01*
X898133D01*
G01X901358Y1370646D02*
X901608Y1370896D01*
X901900Y1371021D01*
X902233Y1371063D01*
X902650Y1370980D01*
X902942Y1370771D01*
X903025Y1370521D01*
X902983Y1370271D01*
X902817Y1370063D01*
X901983Y1369646D01*
X901608Y1369355D01*
X901358Y1368938D01*
X901275Y1368563D01*
X903025D01*
G01X901369Y1382383D02*
Y1374783D01*
X889969D01*
Y1382383D01*
X901369D01*
G01X905466Y1696017D02*
X902966D01*
Y1697017D01*
X903091Y1697350D01*
X903383Y1697600D01*
X903716Y1697683D01*
X904049Y1697600D01*
X904299Y1697392D01*
X904424Y1697017D01*
Y1696017D01*
G01X903174Y1700867D02*
X903049Y1700617D01*
X902966Y1700325D01*
Y1699992D01*
X903091Y1699617D01*
X903299Y1699325D01*
X903549Y1699117D01*
X903966Y1698950D01*
X904341Y1698908D01*
X904716Y1698992D01*
X904966Y1699117D01*
X905216Y1699367D01*
X905383Y1699658D01*
X905466Y1699950D01*
Y1700242D01*
X905383Y1700533D01*
X905258Y1700783D01*
X905091Y1700992D01*
G01X905466Y1703550D02*
X902966D01*
X904758Y1702008D01*
Y1704092D01*
G01X903383Y1705358D02*
X903133Y1705608D01*
X903008Y1705900D01*
X902966Y1706233D01*
X903049Y1706650D01*
X903258Y1706942D01*
X903508Y1707025D01*
X903758Y1706983D01*
X903966Y1706817D01*
X904383Y1705983D01*
X904674Y1705608D01*
X905091Y1705358D01*
X905466Y1705275D01*
Y1707025D01*
G01X901166Y1695917D02*
X898666D01*
Y1696917D01*
X898791Y1697250D01*
X899083Y1697500D01*
X899416Y1697583D01*
X899749Y1697500D01*
X899999Y1697292D01*
X900124Y1696917D01*
Y1695917D01*
G01X901166Y1699017D02*
X898666D01*
Y1700058D01*
X898791Y1700392D01*
X898958Y1700600D01*
X899291Y1700683D01*
X899624Y1700600D01*
X899833Y1700350D01*
X899958Y1700058D01*
Y1699017D01*
G01Y1700058D02*
X901166Y1700683D01*
G01X900791Y1702033D02*
X900999Y1702283D01*
X901124Y1702575D01*
X901166Y1702950D01*
X901083Y1703325D01*
X900916Y1703617D01*
X900624Y1703825D01*
X900291Y1703867D01*
X899958Y1703783D01*
X899749Y1703575D01*
X899583Y1703283D01*
X899541Y1702992D01*
X899583Y1702700D01*
X899749Y1702325D01*
X898666Y1702450D01*
Y1703575D01*
G01X900791Y1705133D02*
X900999Y1705383D01*
X901124Y1705675D01*
X901166Y1706050D01*
X901083Y1706425D01*
X900916Y1706717D01*
X900624Y1706925D01*
X900291Y1706967D01*
X899958Y1706883D01*
X899749Y1706675D01*
X899583Y1706383D01*
X899541Y1706092D01*
X899583Y1705800D01*
X899749Y1705425D01*
X898666Y1705550D01*
Y1706675D01*
G01X891700Y1710100D02*
X887700D01*
Y1702700D01*
G01X900417Y1714800D02*
Y1717300D01*
X901417D01*
X901750Y1717175D01*
X902000Y1716883D01*
X902083Y1716550D01*
X902000Y1716217D01*
X901792Y1715967D01*
X901417Y1715842D01*
X900417D01*
G01X903517Y1714800D02*
Y1717300D01*
X904558D01*
X904892Y1717175D01*
X905100Y1717008D01*
X905183Y1716675D01*
X905100Y1716342D01*
X904850Y1716133D01*
X904558Y1716008D01*
X903517D01*
G01X904558D02*
X905183Y1714800D01*
G01X906533Y1715175D02*
X906783Y1714967D01*
X907075Y1714842D01*
X907450Y1714800D01*
X907825Y1714883D01*
X908117Y1715050D01*
X908325Y1715342D01*
X908367Y1715675D01*
X908283Y1716008D01*
X908075Y1716217D01*
X907783Y1716383D01*
X907492Y1716425D01*
X907200Y1716383D01*
X906825Y1716217D01*
X906950Y1717300D01*
X908075D01*
G01X911050Y1714800D02*
Y1717300D01*
X909508Y1715508D01*
X911592D01*
G01X886500Y1706899D02*
Y1711499D01*
G01X893517Y1724500D02*
Y1727000D01*
X894517D01*
X894850Y1726875D01*
X895100Y1726583D01*
X895183Y1726250D01*
X895100Y1725917D01*
X894892Y1725667D01*
X894517Y1725542D01*
X893517D01*
G01X896617Y1724500D02*
Y1727000D01*
X897658D01*
X897992Y1726875D01*
X898200Y1726708D01*
X898283Y1726375D01*
X898200Y1726042D01*
X897950Y1725833D01*
X897658Y1725708D01*
X896617D01*
G01X897658D02*
X898283Y1724500D01*
G01X899633Y1724875D02*
X899883Y1724667D01*
X900175Y1724542D01*
X900550Y1724500D01*
X900925Y1724583D01*
X901217Y1724750D01*
X901425Y1725042D01*
X901467Y1725375D01*
X901383Y1725708D01*
X901175Y1725917D01*
X900883Y1726083D01*
X900592Y1726125D01*
X900300Y1726083D01*
X899925Y1725917D01*
X900050Y1727000D01*
X901175D01*
G01X902858Y1726583D02*
X903108Y1726833D01*
X903400Y1726958D01*
X903733Y1727000D01*
X904150Y1726917D01*
X904442Y1726708D01*
X904525Y1726458D01*
X904483Y1726208D01*
X904317Y1726000D01*
X903483Y1725583D01*
X903108Y1725292D01*
X902858Y1724875D01*
X902775Y1724500D01*
X904525D01*
G01X907517D02*
Y1727000D01*
X908517D01*
X908850Y1726875D01*
X909100Y1726583D01*
X909183Y1726250D01*
X909100Y1725917D01*
X908892Y1725667D01*
X908517Y1725542D01*
X907517D01*
G01X910617Y1724500D02*
Y1727000D01*
X911658D01*
X911992Y1726875D01*
X912200Y1726708D01*
X912283Y1726375D01*
X912200Y1726042D01*
X911950Y1725833D01*
X911658Y1725708D01*
X910617D01*
G01X911658D02*
X912283Y1724500D01*
G01X913633Y1724875D02*
X913883Y1724667D01*
X914175Y1724542D01*
X914550Y1724500D01*
X914925Y1724583D01*
X915217Y1724750D01*
X915425Y1725042D01*
X915467Y1725375D01*
X915383Y1725708D01*
X915175Y1725917D01*
X914883Y1726083D01*
X914592Y1726125D01*
X914300Y1726083D01*
X913925Y1725917D01*
X914050Y1727000D01*
X915175D01*
G01X916733Y1725000D02*
X916983Y1724708D01*
X917317Y1724542D01*
X917692Y1724500D01*
X918025Y1724542D01*
X918358Y1724750D01*
X918567Y1725000D01*
X918608Y1725250D01*
X918525Y1725542D01*
X918233Y1725750D01*
X917942Y1725833D01*
X917567D01*
G01X917942D02*
X918192Y1725958D01*
X918400Y1726167D01*
X918483Y1726417D01*
X918400Y1726667D01*
X918192Y1726875D01*
X917817Y1727000D01*
X917442Y1726958D01*
X917067Y1726792D01*
G01X896017Y1730500D02*
Y1733000D01*
X897017D01*
X897350Y1732875D01*
X897600Y1732583D01*
X897683Y1732250D01*
X897600Y1731917D01*
X897392Y1731667D01*
X897017Y1731542D01*
X896017D01*
G01X900867Y1732792D02*
X900617Y1732917D01*
X900325Y1733000D01*
X899992D01*
X899617Y1732875D01*
X899325Y1732667D01*
X899117Y1732417D01*
X898950Y1732000D01*
X898908Y1731625D01*
X898992Y1731250D01*
X899117Y1731000D01*
X899367Y1730750D01*
X899658Y1730583D01*
X899950Y1730500D01*
X900242D01*
X900533Y1730583D01*
X900783Y1730708D01*
X900992Y1730875D01*
G01X903550Y1730500D02*
Y1733000D01*
X902008Y1731208D01*
X904092D01*
G01X906150Y1733000D02*
X905817Y1732917D01*
X905567Y1732708D01*
X905400Y1732458D01*
X905275Y1732125D01*
X905233Y1731750D01*
X905275Y1731375D01*
X905400Y1731042D01*
X905567Y1730792D01*
X905817Y1730583D01*
X906150Y1730500D01*
X906483Y1730583D01*
X906733Y1730792D01*
X906900Y1731042D01*
X907025Y1731375D01*
X907067Y1731750D01*
X907025Y1732125D01*
X906900Y1732458D01*
X906733Y1732708D01*
X906483Y1732917D01*
X906150Y1733000D01*
G01X888017Y1734000D02*
Y1736500D01*
X889017D01*
X889350Y1736375D01*
X889600Y1736083D01*
X889683Y1735750D01*
X889600Y1735417D01*
X889392Y1735167D01*
X889017Y1735042D01*
X888017D01*
G01X891117Y1734000D02*
Y1736500D01*
X892158D01*
X892492Y1736375D01*
X892700Y1736208D01*
X892783Y1735875D01*
X892700Y1735542D01*
X892450Y1735333D01*
X892158Y1735208D01*
X891117D01*
G01X892158D02*
X892783Y1734000D01*
G01X894258Y1735042D02*
X894550Y1735333D01*
X894800Y1735500D01*
X895133Y1735583D01*
X895425Y1735500D01*
X895633Y1735333D01*
X895800Y1735083D01*
X895842Y1734792D01*
X895800Y1734542D01*
X895633Y1734292D01*
X895383Y1734083D01*
X895092Y1734000D01*
X894758Y1734083D01*
X894467Y1734333D01*
X894300Y1734708D01*
X894258Y1735125D01*
X894342Y1735667D01*
X894467Y1735958D01*
X894675Y1736250D01*
X894967Y1736458D01*
X895258Y1736500D01*
X895550Y1736417D01*
X895758Y1736208D01*
G01X897233Y1734500D02*
X897483Y1734208D01*
X897817Y1734042D01*
X898192Y1734000D01*
X898525Y1734042D01*
X898858Y1734250D01*
X899067Y1734500D01*
X899108Y1734750D01*
X899025Y1735042D01*
X898733Y1735250D01*
X898442Y1735333D01*
X898067D01*
G01X898442D02*
X898692Y1735458D01*
X898900Y1735667D01*
X898983Y1735917D01*
X898900Y1736167D01*
X898692Y1736375D01*
X898317Y1736500D01*
X897942Y1736458D01*
X897567Y1736292D01*
G01X889517Y1769063D02*
Y1766563D01*
X891183D01*
G01X894283D02*
X892617D01*
Y1769063D01*
X894283D01*
G01X893617Y1767855D02*
X892617D01*
G01X895633Y1766563D02*
Y1769063D01*
X896467D01*
X896800Y1768938D01*
X897050Y1768771D01*
X897258Y1768521D01*
X897425Y1768230D01*
X897467Y1767813D01*
X897425Y1767396D01*
X897258Y1767105D01*
X897050Y1766855D01*
X896800Y1766688D01*
X896467Y1766563D01*
X895633D01*
G01X899650D02*
Y1769063D01*
X899150Y1768563D01*
G01Y1766563D02*
X900150D01*
G01X901369Y1787894D02*
Y1780294D01*
X889969D01*
Y1787894D01*
X901369D01*
G01X902864Y1787613D02*
Y1783613D01*
X910264D01*
G01X902864D02*
Y1779613D01*
X910264D01*
G01X902864D02*
Y1775613D01*
X910264D01*
G01X920641Y51539D02*
Y54039D01*
X921641D01*
X921974Y53914D01*
X922224Y53622D01*
X922307Y53289D01*
X922224Y52956D01*
X922016Y52706D01*
X921641Y52581D01*
X920641D01*
G01X923741Y54039D02*
Y51539D01*
X925407D01*
G01X927674D02*
Y54039D01*
X927174Y53539D01*
G01Y51539D02*
X928174D01*
G01X912199Y39450D02*
X934799D01*
G01X912199Y49650D02*
Y39450D01*
G01X934799Y49650D02*
X912199D01*
G01Y39450D02*
X934799D01*
G01X912199Y49650D02*
Y39450D01*
G01X934799Y49650D02*
X912199D01*
G01X910499Y59617D02*
X907999D01*
Y60617D01*
X908124Y60950D01*
X908416Y61200D01*
X908749Y61283D01*
X909082Y61200D01*
X909332Y60992D01*
X909457Y60617D01*
Y59617D01*
G01X908207Y64467D02*
X908082Y64217D01*
X907999Y63925D01*
Y63592D01*
X908124Y63217D01*
X908332Y62925D01*
X908582Y62717D01*
X908999Y62550D01*
X909374Y62508D01*
X909749Y62592D01*
X909999Y62717D01*
X910249Y62967D01*
X910416Y63258D01*
X910499Y63550D01*
Y63842D01*
X910416Y64133D01*
X910291Y64383D01*
X910124Y64592D01*
G01X910207Y65942D02*
X910416Y66233D01*
X910499Y66567D01*
X910416Y66900D01*
X910166Y67192D01*
X909791Y67400D01*
X909416Y67483D01*
X908957D01*
X908582Y67400D01*
X908249Y67192D01*
X908082Y66942D01*
X907999Y66650D01*
X908082Y66317D01*
X908249Y66067D01*
X908499Y65900D01*
X908832Y65817D01*
X909124Y65900D01*
X909416Y66108D01*
X909582Y66358D01*
X909624Y66650D01*
X909541Y66983D01*
X909332Y67233D01*
X908957Y67483D01*
G01X924566Y67050D02*
Y69550D01*
X925566D01*
X925899Y69425D01*
X926149Y69133D01*
X926232Y68800D01*
X926149Y68467D01*
X925941Y68217D01*
X925566Y68092D01*
X924566D01*
G01X927582Y69550D02*
Y67758D01*
X927749Y67383D01*
X928082Y67133D01*
X928499Y67050D01*
X928916Y67133D01*
X929249Y67383D01*
X929416Y67758D01*
Y69550D01*
G01X931599Y67050D02*
Y69550D01*
X931099Y69050D01*
G01Y67050D02*
X932099D01*
G01X914649Y76550D02*
Y71550D01*
X919649D01*
G01X915656Y77676D02*
X912656D01*
G01X915656Y87519D02*
X913656D01*
G01X929999Y115567D02*
X927499D01*
Y116567D01*
X927624Y116900D01*
X927916Y117150D01*
X928249Y117233D01*
X928582Y117150D01*
X928832Y116942D01*
X928957Y116567D01*
Y115567D01*
G01X927707Y120417D02*
X927582Y120167D01*
X927499Y119875D01*
Y119542D01*
X927624Y119167D01*
X927832Y118875D01*
X928082Y118667D01*
X928499Y118500D01*
X928874Y118458D01*
X929249Y118542D01*
X929499Y118667D01*
X929749Y118917D01*
X929916Y119208D01*
X929999Y119500D01*
Y119792D01*
X929916Y120083D01*
X929791Y120333D01*
X929624Y120542D01*
G01X929999Y122600D02*
X927499D01*
X927999Y122100D01*
G01X929999D02*
Y123100D01*
G01X929499Y124783D02*
X929791Y125033D01*
X929957Y125367D01*
X929999Y125742D01*
X929957Y126075D01*
X929749Y126408D01*
X929499Y126617D01*
X929249Y126658D01*
X928957Y126575D01*
X928749Y126283D01*
X928666Y125992D01*
Y125617D01*
G01Y125992D02*
X928541Y126242D01*
X928332Y126450D01*
X928082Y126533D01*
X927832Y126450D01*
X927624Y126242D01*
X927499Y125867D01*
X927541Y125492D01*
X927707Y125117D01*
G01X925999Y115567D02*
X923499D01*
Y116567D01*
X923624Y116900D01*
X923916Y117150D01*
X924249Y117233D01*
X924582Y117150D01*
X924832Y116942D01*
X924957Y116567D01*
Y115567D01*
G01X925999Y118667D02*
X923499D01*
Y119708D01*
X923624Y120042D01*
X923791Y120250D01*
X924124Y120333D01*
X924457Y120250D01*
X924666Y120000D01*
X924791Y119708D01*
Y118667D01*
G01Y119708D02*
X925999Y120333D01*
G01Y122600D02*
X923499D01*
X923999Y122100D01*
G01X925999D02*
Y123100D01*
G01Y126200D02*
X923499D01*
X925291Y124658D01*
Y126742D01*
G01X922499Y106350D02*
X926499D01*
Y113750D01*
G01X920999Y115617D02*
X918499D01*
Y116617D01*
X918624Y116950D01*
X918916Y117200D01*
X919249Y117283D01*
X919582Y117200D01*
X919832Y116992D01*
X919957Y116617D01*
Y115617D01*
G01X920999Y118717D02*
X918499D01*
Y119758D01*
X918624Y120092D01*
X918791Y120300D01*
X919124Y120383D01*
X919457Y120300D01*
X919666Y120050D01*
X919791Y119758D01*
Y118717D01*
G01Y119758D02*
X920999Y120383D01*
G01X918916Y121858D02*
X918666Y122108D01*
X918541Y122400D01*
X918499Y122733D01*
X918582Y123150D01*
X918791Y123442D01*
X919041Y123525D01*
X919291Y123483D01*
X919499Y123317D01*
X919916Y122483D01*
X920207Y122108D01*
X920624Y121858D01*
X920999Y121775D01*
Y123525D01*
G01X922499Y113750D02*
X918499D01*
Y106350D01*
G01X916999Y115617D02*
X914499D01*
Y116617D01*
X914624Y116950D01*
X914916Y117200D01*
X915249Y117283D01*
X915582Y117200D01*
X915832Y116992D01*
X915957Y116617D01*
Y115617D01*
G01X916999Y118717D02*
X914499D01*
Y119758D01*
X914624Y120092D01*
X914791Y120300D01*
X915124Y120383D01*
X915457Y120300D01*
X915666Y120050D01*
X915791Y119758D01*
Y118717D01*
G01Y119758D02*
X916999Y120383D01*
G01X916499Y121733D02*
X916791Y121983D01*
X916957Y122317D01*
X916999Y122692D01*
X916957Y123025D01*
X916749Y123358D01*
X916499Y123567D01*
X916249Y123608D01*
X915957Y123525D01*
X915749Y123233D01*
X915666Y122942D01*
Y122567D01*
G01Y122942D02*
X915541Y123192D01*
X915332Y123400D01*
X915082Y123483D01*
X914832Y123400D01*
X914624Y123192D01*
X914499Y122817D01*
X914541Y122442D01*
X914707Y122067D01*
G01X914499Y106350D02*
X918499D01*
Y113750D01*
G01X912999Y115617D02*
X910499D01*
Y116617D01*
X910624Y116950D01*
X910916Y117200D01*
X911249Y117283D01*
X911582Y117200D01*
X911832Y116992D01*
X911957Y116617D01*
Y115617D01*
G01X912999Y118717D02*
X910499D01*
Y119758D01*
X910624Y120092D01*
X910791Y120300D01*
X911124Y120383D01*
X911457Y120300D01*
X911666Y120050D01*
X911791Y119758D01*
Y118717D01*
G01Y119758D02*
X912999Y120383D01*
G01X912624Y121733D02*
X912832Y121983D01*
X912957Y122275D01*
X912999Y122650D01*
X912916Y123025D01*
X912749Y123317D01*
X912457Y123525D01*
X912124Y123567D01*
X911791Y123483D01*
X911582Y123275D01*
X911416Y122983D01*
X911374Y122692D01*
X911416Y122400D01*
X911582Y122025D01*
X910499Y122150D01*
Y123275D01*
G01X914499Y113750D02*
X910499D01*
Y106350D01*
G01X924016Y152550D02*
Y155050D01*
X925057D01*
X925391Y154925D01*
X925599Y154758D01*
X925682Y154425D01*
X925599Y154092D01*
X925349Y153883D01*
X925057Y153758D01*
X924016D01*
G01X925057D02*
X925682Y152550D01*
G01X928449D02*
Y155050D01*
X926907Y153258D01*
X928991D01*
G01X930341Y152842D02*
X930632Y152633D01*
X930966Y152550D01*
X931299Y152633D01*
X931591Y152883D01*
X931799Y153258D01*
X931882Y153633D01*
Y154092D01*
X931799Y154467D01*
X931591Y154800D01*
X931341Y154967D01*
X931049Y155050D01*
X930716Y154967D01*
X930466Y154800D01*
X930299Y154550D01*
X930216Y154217D01*
X930299Y153925D01*
X930507Y153633D01*
X930757Y153467D01*
X931049Y153425D01*
X931382Y153508D01*
X931632Y153717D01*
X931882Y154092D01*
G01X933357Y154633D02*
X933607Y154883D01*
X933899Y155008D01*
X934232Y155050D01*
X934649Y154967D01*
X934941Y154758D01*
X935024Y154508D01*
X934982Y154258D01*
X934816Y154050D01*
X933982Y153633D01*
X933607Y153342D01*
X933357Y152925D01*
X933274Y152550D01*
X935024D01*
G01X920528Y170424D02*
Y166424D01*
X927928D01*
G01X920528D02*
Y162424D01*
X927928D01*
G01X920299Y174550D02*
Y170550D01*
X927699D01*
G01X933099Y156500D02*
Y160500D01*
X925699D01*
G01X909516Y552050D02*
Y554550D01*
X910557D01*
X910891Y554425D01*
X911099Y554258D01*
X911182Y553925D01*
X911099Y553592D01*
X910849Y553383D01*
X910557Y553258D01*
X909516D01*
G01X910557D02*
X911182Y552050D01*
G01X913949D02*
Y554550D01*
X912407Y552758D01*
X914491D01*
G01X915841Y552342D02*
X916132Y552133D01*
X916466Y552050D01*
X916799Y552133D01*
X917091Y552383D01*
X917299Y552758D01*
X917382Y553133D01*
Y553592D01*
X917299Y553967D01*
X917091Y554300D01*
X916841Y554467D01*
X916549Y554550D01*
X916216Y554467D01*
X915966Y554300D01*
X915799Y554050D01*
X915716Y553717D01*
X915799Y553425D01*
X916007Y553133D01*
X916257Y552967D01*
X916549Y552925D01*
X916882Y553008D01*
X917132Y553217D01*
X917382Y553592D01*
G01X919649Y552050D02*
Y554550D01*
X919149Y554050D01*
G01Y552050D02*
X920149D01*
G01X918099Y555800D02*
Y559800D01*
X910699D01*
G01X911299Y560400D02*
X925299D01*
G01X911299Y573400D02*
Y560400D01*
G01X925299Y573400D02*
X911299D01*
G01X925299Y560400D02*
Y573400D01*
G01X910016Y956550D02*
Y959050D01*
X911057D01*
X911391Y958925D01*
X911599Y958758D01*
X911682Y958425D01*
X911599Y958092D01*
X911349Y957883D01*
X911057Y957758D01*
X910016D01*
G01X911057D02*
X911682Y956550D01*
G01X914449D02*
Y959050D01*
X912907Y957258D01*
X914991D01*
G01X916341Y956842D02*
X916632Y956633D01*
X916966Y956550D01*
X917299Y956633D01*
X917591Y956883D01*
X917799Y957258D01*
X917882Y957633D01*
Y958092D01*
X917799Y958467D01*
X917591Y958800D01*
X917341Y958967D01*
X917049Y959050D01*
X916716Y958967D01*
X916466Y958800D01*
X916299Y958550D01*
X916216Y958217D01*
X916299Y957925D01*
X916507Y957633D01*
X916757Y957467D01*
X917049Y957425D01*
X917382Y957508D01*
X917632Y957717D01*
X917882Y958092D01*
G01X920149Y959050D02*
X919816Y958967D01*
X919566Y958758D01*
X919399Y958508D01*
X919274Y958175D01*
X919232Y957800D01*
X919274Y957425D01*
X919399Y957092D01*
X919566Y956842D01*
X919816Y956633D01*
X920149Y956550D01*
X920482Y956633D01*
X920732Y956842D01*
X920899Y957092D01*
X921024Y957425D01*
X921066Y957800D01*
X921024Y958175D01*
X920899Y958508D01*
X920732Y958758D01*
X920482Y958967D01*
X920149Y959050D01*
G01X918599Y960100D02*
Y964100D01*
X911199D01*
G01X907850Y980392D02*
Y982892D01*
X908891D01*
X909225Y982767D01*
X909433Y982600D01*
X909516Y982267D01*
X909433Y981934D01*
X909183Y981725D01*
X908891Y981600D01*
X907850D01*
G01X908891D02*
X909516Y980392D01*
G01X911783D02*
Y982892D01*
X911283Y982392D01*
G01Y980392D02*
X912283D01*
G01X913966Y980892D02*
X914216Y980600D01*
X914550Y980434D01*
X914925Y980392D01*
X915258Y980434D01*
X915591Y980642D01*
X915800Y980892D01*
X915841Y981142D01*
X915758Y981434D01*
X915466Y981642D01*
X915175Y981725D01*
X914800D01*
G01X915175D02*
X915425Y981850D01*
X915633Y982059D01*
X915716Y982309D01*
X915633Y982559D01*
X915425Y982767D01*
X915050Y982892D01*
X914675Y982850D01*
X914300Y982684D01*
G01X917191Y982475D02*
X917441Y982725D01*
X917733Y982850D01*
X918066Y982892D01*
X918483Y982809D01*
X918775Y982600D01*
X918858Y982350D01*
X918816Y982100D01*
X918650Y981892D01*
X917816Y981475D01*
X917441Y981184D01*
X917191Y980767D01*
X917108Y980392D01*
X918858D01*
G01X928341Y974830D02*
X928008Y974872D01*
X927716Y975038D01*
X927466Y975288D01*
X927299Y975580D01*
X927216Y975913D01*
Y976247D01*
X927299Y976580D01*
X927466Y976872D01*
X927716Y977122D01*
X928008Y977288D01*
X928341Y977330D01*
X928674Y977288D01*
X928966Y977122D01*
X929216Y976872D01*
X929383Y976580D01*
X929466Y976247D01*
Y975913D01*
X929383Y975580D01*
X929216Y975288D01*
X928966Y975038D01*
X928674Y974872D01*
X928341Y974830D01*
G01X928674Y975497D02*
X929174Y974830D01*
G01X930524Y975330D02*
X930774Y975038D01*
X931108Y974872D01*
X931483Y974830D01*
X931816Y974872D01*
X932149Y975080D01*
X932358Y975330D01*
X932399Y975580D01*
X932316Y975872D01*
X932024Y976080D01*
X931733Y976163D01*
X931358D01*
G01X931733D02*
X931983Y976288D01*
X932191Y976497D01*
X932274Y976747D01*
X932191Y976997D01*
X931983Y977205D01*
X931608Y977330D01*
X931233Y977288D01*
X930858Y977122D01*
G01X933749Y975872D02*
X934041Y976163D01*
X934291Y976330D01*
X934624Y976413D01*
X934916Y976330D01*
X935124Y976163D01*
X935291Y975913D01*
X935333Y975622D01*
X935291Y975372D01*
X935124Y975122D01*
X934874Y974913D01*
X934583Y974830D01*
X934249Y974913D01*
X933958Y975163D01*
X933791Y975538D01*
X933749Y975955D01*
X933833Y976497D01*
X933958Y976788D01*
X934166Y977080D01*
X934458Y977288D01*
X934749Y977330D01*
X935041Y977247D01*
X935249Y977038D01*
G01X911299Y964600D02*
X925299D01*
G01X911299Y977600D02*
Y964600D01*
G01X925299Y977600D02*
X911299D01*
G01X925299Y964600D02*
Y977600D01*
G01X907850Y988392D02*
Y990892D01*
X908891D01*
X909225Y990767D01*
X909433Y990600D01*
X909516Y990267D01*
X909433Y989934D01*
X909183Y989725D01*
X908891Y989600D01*
X907850D01*
G01X908891D02*
X909516Y988392D01*
G01X911783D02*
Y990892D01*
X911283Y990392D01*
G01Y988392D02*
X912283D01*
G01X914091Y990475D02*
X914341Y990725D01*
X914633Y990850D01*
X914966Y990892D01*
X915383Y990809D01*
X915675Y990600D01*
X915758Y990350D01*
X915716Y990100D01*
X915550Y989892D01*
X914716Y989475D01*
X914341Y989184D01*
X914091Y988767D01*
X914008Y988392D01*
X915758D01*
G01X917983D02*
X918275Y988434D01*
X918608Y988559D01*
X918816Y988767D01*
X918900Y989059D01*
X918816Y989350D01*
X918566Y989600D01*
X918191Y989725D01*
X917775D01*
X917525Y989809D01*
X917316Y990017D01*
X917233Y990309D01*
X917358Y990600D01*
X917650Y990809D01*
X917983Y990892D01*
X918316Y990809D01*
X918608Y990600D01*
X918733Y990309D01*
X918650Y990017D01*
X918441Y989809D01*
X918191Y989725D01*
X917775D01*
X917400Y989600D01*
X917150Y989350D01*
X917066Y989059D01*
X917150Y988767D01*
X917358Y988559D01*
X917691Y988434D01*
X917983Y988392D01*
G01X907850Y984392D02*
Y986892D01*
X908891D01*
X909225Y986767D01*
X909433Y986600D01*
X909516Y986267D01*
X909433Y985934D01*
X909183Y985725D01*
X908891Y985600D01*
X907850D01*
G01X908891D02*
X909516Y984392D01*
G01X911783D02*
Y986892D01*
X911283Y986392D01*
G01Y984392D02*
X912283D01*
G01X913966Y984892D02*
X914216Y984600D01*
X914550Y984434D01*
X914925Y984392D01*
X915258Y984434D01*
X915591Y984642D01*
X915800Y984892D01*
X915841Y985142D01*
X915758Y985434D01*
X915466Y985642D01*
X915175Y985725D01*
X914800D01*
G01X915175D02*
X915425Y985850D01*
X915633Y986059D01*
X915716Y986309D01*
X915633Y986559D01*
X915425Y986767D01*
X915050Y986892D01*
X914675Y986850D01*
X914300Y986684D01*
G01X917983Y986892D02*
X917650Y986809D01*
X917400Y986600D01*
X917233Y986350D01*
X917108Y986017D01*
X917066Y985642D01*
X917108Y985267D01*
X917233Y984934D01*
X917400Y984684D01*
X917650Y984475D01*
X917983Y984392D01*
X918316Y984475D01*
X918566Y984684D01*
X918733Y984934D01*
X918858Y985267D01*
X918900Y985642D01*
X918858Y986017D01*
X918733Y986350D01*
X918566Y986600D01*
X918316Y986809D01*
X917983Y986892D01*
G01X914499Y1373550D02*
Y1383550D01*
G01X921499D02*
Y1373550D01*
G01Y1378550D02*
X914499D01*
G01X924932Y1373550D02*
Y1383550D01*
X928266D01*
X929599Y1383050D01*
X930599Y1382383D01*
X931432Y1381383D01*
X932099Y1380216D01*
X932266Y1378550D01*
X932099Y1376883D01*
X931432Y1375717D01*
X930599Y1374716D01*
X929599Y1374050D01*
X928266Y1373550D01*
X924932D01*
G01X935532D02*
Y1383550D01*
X938866D01*
X940199Y1383050D01*
X941199Y1382383D01*
X942032Y1381383D01*
X942699Y1380216D01*
X942866Y1378550D01*
X942699Y1376883D01*
X942032Y1375717D01*
X941199Y1374716D01*
X940199Y1374050D01*
X938866Y1373550D01*
X935532D01*
G01X949799D02*
Y1383550D01*
X947799Y1381550D01*
G01Y1373550D02*
X951799D01*
G01X955399Y1370217D02*
X965399D01*
G01X967666Y1383550D02*
Y1373550D01*
X974332D01*
G01X984932D02*
X978266D01*
Y1383550D01*
X984932D01*
G01X982266Y1378717D02*
X978266D01*
G01X988532Y1373550D02*
Y1383550D01*
X991866D01*
X993199Y1383050D01*
X994199Y1382383D01*
X995032Y1381383D01*
X995699Y1380216D01*
X995866Y1378550D01*
X995699Y1376883D01*
X995032Y1375717D01*
X994199Y1374716D01*
X993199Y1374050D01*
X991866Y1373550D01*
X988532D01*
G01X908217Y1764100D02*
Y1766600D01*
X909258D01*
X909592Y1766475D01*
X909800Y1766308D01*
X909883Y1765975D01*
X909800Y1765642D01*
X909550Y1765433D01*
X909258Y1765308D01*
X908217D01*
G01X909258D02*
X909883Y1764100D01*
G01X912650D02*
Y1766600D01*
X911108Y1764808D01*
X913192D01*
G01X915250Y1764100D02*
X915542Y1764142D01*
X915875Y1764267D01*
X916083Y1764475D01*
X916167Y1764767D01*
X916083Y1765058D01*
X915833Y1765308D01*
X915458Y1765433D01*
X915042D01*
X914792Y1765517D01*
X914583Y1765725D01*
X914500Y1766017D01*
X914625Y1766308D01*
X914917Y1766517D01*
X915250Y1766600D01*
X915583Y1766517D01*
X915875Y1766308D01*
X916000Y1766017D01*
X915917Y1765725D01*
X915708Y1765517D01*
X915458Y1765433D01*
X915042D01*
X914667Y1765308D01*
X914417Y1765058D01*
X914333Y1764767D01*
X914417Y1764475D01*
X914625Y1764267D01*
X914958Y1764142D01*
X915250Y1764100D01*
G01X918350D02*
X918642Y1764142D01*
X918975Y1764267D01*
X919183Y1764475D01*
X919267Y1764767D01*
X919183Y1765058D01*
X918933Y1765308D01*
X918558Y1765433D01*
X918142D01*
X917892Y1765517D01*
X917683Y1765725D01*
X917600Y1766017D01*
X917725Y1766308D01*
X918017Y1766517D01*
X918350Y1766600D01*
X918683Y1766517D01*
X918975Y1766308D01*
X919100Y1766017D01*
X919017Y1765725D01*
X918808Y1765517D01*
X918558Y1765433D01*
X918142D01*
X917767Y1765308D01*
X917517Y1765058D01*
X917433Y1764767D01*
X917517Y1764475D01*
X917725Y1764267D01*
X918058Y1764142D01*
X918350Y1764100D01*
G01X918099Y1769700D02*
Y1773700D01*
X910699D01*
G01X929499Y1780450D02*
X929457Y1780117D01*
X929291Y1779825D01*
X929041Y1779575D01*
X928749Y1779408D01*
X928416Y1779325D01*
X928082D01*
X927749Y1779408D01*
X927457Y1779575D01*
X927207Y1779825D01*
X927041Y1780117D01*
X926999Y1780450D01*
X927041Y1780783D01*
X927207Y1781075D01*
X927457Y1781325D01*
X927749Y1781492D01*
X928082Y1781575D01*
X928416D01*
X928749Y1781492D01*
X929041Y1781325D01*
X929291Y1781075D01*
X929457Y1780783D01*
X929499Y1780450D01*
G01X928832Y1780783D02*
X929499Y1781283D01*
G01X928999Y1782633D02*
X929291Y1782883D01*
X929457Y1783217D01*
X929499Y1783592D01*
X929457Y1783925D01*
X929249Y1784258D01*
X928999Y1784467D01*
X928749Y1784508D01*
X928457Y1784425D01*
X928249Y1784133D01*
X928166Y1783842D01*
Y1783467D01*
G01Y1783842D02*
X928041Y1784092D01*
X927832Y1784300D01*
X927582Y1784383D01*
X927332Y1784300D01*
X927124Y1784092D01*
X926999Y1783717D01*
X927041Y1783342D01*
X927207Y1782967D01*
G01X929499Y1787150D02*
X926999D01*
X928791Y1785608D01*
Y1787692D01*
G01X910799Y1774500D02*
X924799D01*
G01X910799Y1787500D02*
Y1774500D01*
G01X924799D02*
Y1787500D01*
G01X908581Y1802713D02*
Y1805213D01*
X909622D01*
X909956Y1805088D01*
X910164Y1804921D01*
X910247Y1804588D01*
X910164Y1804255D01*
X909914Y1804046D01*
X909622Y1803921D01*
X908581D01*
G01X909622D02*
X910247Y1802713D01*
G01X912514D02*
Y1805213D01*
X912014Y1804713D01*
G01Y1802713D02*
X913014D01*
G01X915614Y1805213D02*
X915281Y1805130D01*
X915031Y1804921D01*
X914864Y1804671D01*
X914739Y1804338D01*
X914697Y1803963D01*
X914739Y1803588D01*
X914864Y1803255D01*
X915031Y1803005D01*
X915281Y1802796D01*
X915614Y1802713D01*
X915947Y1802796D01*
X916197Y1803005D01*
X916364Y1803255D01*
X916489Y1803588D01*
X916531Y1803963D01*
X916489Y1804338D01*
X916364Y1804671D01*
X916197Y1804921D01*
X915947Y1805130D01*
X915614Y1805213D01*
G01X918714Y1802713D02*
Y1805213D01*
X918214Y1804713D01*
G01Y1802713D02*
X919214D01*
G01X908581Y1798713D02*
Y1801213D01*
X909622D01*
X909956Y1801088D01*
X910164Y1800921D01*
X910247Y1800588D01*
X910164Y1800255D01*
X909914Y1800046D01*
X909622Y1799921D01*
X908581D01*
G01X909622D02*
X910247Y1798713D01*
G01X912514D02*
Y1801213D01*
X912014Y1800713D01*
G01Y1798713D02*
X913014D01*
G01X915614Y1801213D02*
X915281Y1801130D01*
X915031Y1800921D01*
X914864Y1800671D01*
X914739Y1800338D01*
X914697Y1799963D01*
X914739Y1799588D01*
X914864Y1799255D01*
X915031Y1799005D01*
X915281Y1798796D01*
X915614Y1798713D01*
X915947Y1798796D01*
X916197Y1799005D01*
X916364Y1799255D01*
X916489Y1799588D01*
X916531Y1799963D01*
X916489Y1800338D01*
X916364Y1800671D01*
X916197Y1800921D01*
X915947Y1801130D01*
X915614Y1801213D01*
G01X917797Y1799213D02*
X918047Y1798921D01*
X918381Y1798755D01*
X918756Y1798713D01*
X919089Y1798755D01*
X919422Y1798963D01*
X919631Y1799213D01*
X919672Y1799463D01*
X919589Y1799755D01*
X919297Y1799963D01*
X919006Y1800046D01*
X918631D01*
G01X919006D02*
X919256Y1800171D01*
X919464Y1800380D01*
X919547Y1800630D01*
X919464Y1800880D01*
X919256Y1801088D01*
X918881Y1801213D01*
X918506Y1801171D01*
X918131Y1801005D01*
G01X908581Y1794713D02*
Y1797213D01*
X909622D01*
X909956Y1797088D01*
X910164Y1796921D01*
X910247Y1796588D01*
X910164Y1796255D01*
X909914Y1796046D01*
X909622Y1795921D01*
X908581D01*
G01X909622D02*
X910247Y1794713D01*
G01X912514D02*
Y1797213D01*
X912014Y1796713D01*
G01Y1794713D02*
X913014D01*
G01X915614Y1797213D02*
X915281Y1797130D01*
X915031Y1796921D01*
X914864Y1796671D01*
X914739Y1796338D01*
X914697Y1795963D01*
X914739Y1795588D01*
X914864Y1795255D01*
X915031Y1795005D01*
X915281Y1794796D01*
X915614Y1794713D01*
X915947Y1794796D01*
X916197Y1795005D01*
X916364Y1795255D01*
X916489Y1795588D01*
X916531Y1795963D01*
X916489Y1796338D01*
X916364Y1796671D01*
X916197Y1796921D01*
X915947Y1797130D01*
X915614Y1797213D01*
G01X917797Y1795088D02*
X918047Y1794880D01*
X918339Y1794755D01*
X918714Y1794713D01*
X919089Y1794796D01*
X919381Y1794963D01*
X919589Y1795255D01*
X919631Y1795588D01*
X919547Y1795921D01*
X919339Y1796130D01*
X919047Y1796296D01*
X918756Y1796338D01*
X918464Y1796296D01*
X918089Y1796130D01*
X918214Y1797213D01*
X919339D01*
G01X924799Y1787500D02*
X910799D01*
G01X934799Y39450D02*
Y49650D01*
G01Y39450D02*
Y49650D01*
G01X937349Y71550D02*
X942349D01*
Y76550D01*
G01Y94550D02*
Y99550D01*
X937349D01*
G01X941342Y91456D02*
X944342D01*
G01X941342Y81613D02*
X943342D01*
G01X933999Y115567D02*
X931499D01*
Y116567D01*
X931624Y116900D01*
X931916Y117150D01*
X932249Y117233D01*
X932582Y117150D01*
X932832Y116942D01*
X932957Y116567D01*
Y115567D01*
G01X933999Y118667D02*
X931499D01*
Y119708D01*
X931624Y120042D01*
X931791Y120250D01*
X932124Y120333D01*
X932457Y120250D01*
X932666Y120000D01*
X932791Y119708D01*
Y118667D01*
G01Y119708D02*
X933999Y120333D01*
G01Y122600D02*
X931499D01*
X931999Y122100D01*
G01X933999D02*
Y123100D01*
G01Y125700D02*
X931499D01*
X931999Y125200D01*
G01X933999D02*
Y126200D01*
G01X930499Y106350D02*
X934499D01*
Y113750D01*
G01X937999Y115567D02*
X935499D01*
Y116567D01*
X935624Y116900D01*
X935916Y117150D01*
X936249Y117233D01*
X936582Y117150D01*
X936832Y116942D01*
X936957Y116567D01*
Y115567D01*
G01X937999Y118667D02*
X935499D01*
Y119708D01*
X935624Y120042D01*
X935791Y120250D01*
X936124Y120333D01*
X936457Y120250D01*
X936666Y120000D01*
X936791Y119708D01*
Y118667D01*
G01Y119708D02*
X937999Y120333D01*
G01Y122600D02*
X935499D01*
X935999Y122100D01*
G01X937999D02*
Y123100D01*
G01X935916Y124908D02*
X935666Y125158D01*
X935541Y125450D01*
X935499Y125783D01*
X935582Y126200D01*
X935791Y126492D01*
X936041Y126575D01*
X936291Y126533D01*
X936499Y126367D01*
X936916Y125533D01*
X937207Y125158D01*
X937624Y124908D01*
X937999Y124825D01*
Y126575D01*
G01X938499Y113750D02*
X934499D01*
Y106350D01*
G01X942499D02*
X946499D01*
Y113750D01*
G01X941999Y115567D02*
X939499D01*
Y116567D01*
X939624Y116900D01*
X939916Y117150D01*
X940249Y117233D01*
X940582Y117150D01*
X940832Y116942D01*
X940957Y116567D01*
Y115567D01*
G01X941999Y118667D02*
X939499D01*
Y119708D01*
X939624Y120042D01*
X939791Y120250D01*
X940124Y120333D01*
X940457Y120250D01*
X940666Y120000D01*
X940791Y119708D01*
Y118667D01*
G01Y119708D02*
X941999Y120333D01*
G01Y122600D02*
X939499D01*
X939999Y122100D01*
G01X941999D02*
Y123100D01*
G01X940957Y124908D02*
X940666Y125200D01*
X940499Y125450D01*
X940416Y125783D01*
X940499Y126075D01*
X940666Y126283D01*
X940916Y126450D01*
X941207Y126492D01*
X941457Y126450D01*
X941707Y126283D01*
X941916Y126033D01*
X941999Y125742D01*
X941916Y125408D01*
X941666Y125117D01*
X941291Y124950D01*
X940874Y124908D01*
X940332Y124992D01*
X940041Y125117D01*
X939749Y125325D01*
X939541Y125617D01*
X939499Y125908D01*
X939582Y126200D01*
X939791Y126408D01*
G01X938499Y106350D02*
X942499D01*
Y113750D01*
G01X950499D02*
X946499D01*
Y106350D01*
G01X947499Y123117D02*
X944999D01*
Y124117D01*
X945124Y124450D01*
X945416Y124700D01*
X945749Y124783D01*
X946082Y124700D01*
X946332Y124492D01*
X946457Y124117D01*
Y123117D01*
G01X946249Y127300D02*
Y128133D01*
X946999D01*
X947249Y127883D01*
X947416Y127592D01*
X947499Y127175D01*
X947416Y126758D01*
X947249Y126467D01*
X946999Y126217D01*
X946707Y126050D01*
X946374Y125967D01*
X946082D01*
X945832Y126050D01*
X945541Y126217D01*
X945291Y126467D01*
X945124Y126717D01*
X944999Y127050D01*
Y127342D01*
X945082Y127675D01*
X945249Y127925D01*
G01X947499Y130150D02*
X944999D01*
X945499Y129650D01*
G01X947499D02*
Y130650D01*
G01X934584Y176959D02*
X934251Y177001D01*
X933959Y177167D01*
X933709Y177417D01*
X933542Y177709D01*
X933459Y178042D01*
Y178376D01*
X933542Y178709D01*
X933709Y179001D01*
X933959Y179251D01*
X934251Y179417D01*
X934584Y179459D01*
X934917Y179417D01*
X935209Y179251D01*
X935459Y179001D01*
X935626Y178709D01*
X935709Y178376D01*
Y178042D01*
X935626Y177709D01*
X935459Y177417D01*
X935209Y177167D01*
X934917Y177001D01*
X934584Y176959D01*
G01X934917Y177626D02*
X935417Y176959D01*
G01X936767Y177459D02*
X937017Y177167D01*
X937351Y177001D01*
X937726Y176959D01*
X938059Y177001D01*
X938392Y177209D01*
X938601Y177459D01*
X938642Y177709D01*
X938559Y178001D01*
X938267Y178209D01*
X937976Y178292D01*
X937601D01*
G01X937976D02*
X938226Y178417D01*
X938434Y178626D01*
X938517Y178876D01*
X938434Y179126D01*
X938226Y179334D01*
X937851Y179459D01*
X937476Y179417D01*
X937101Y179251D01*
G01X940784Y176959D02*
X941076Y177001D01*
X941409Y177126D01*
X941617Y177334D01*
X941701Y177626D01*
X941617Y177917D01*
X941367Y178167D01*
X940992Y178292D01*
X940576D01*
X940326Y178376D01*
X940117Y178584D01*
X940034Y178876D01*
X940159Y179167D01*
X940451Y179376D01*
X940784Y179459D01*
X941117Y179376D01*
X941409Y179167D01*
X941534Y178876D01*
X941451Y178584D01*
X941242Y178376D01*
X940992Y178292D01*
X940576D01*
X940201Y178167D01*
X939951Y177917D01*
X939867Y177626D01*
X939951Y177334D01*
X940159Y177126D01*
X940492Y177001D01*
X940784Y176959D01*
G01X928799Y161200D02*
X942799D01*
G01X928799Y174200D02*
Y161200D01*
G01X942799Y174200D02*
X928799D01*
G01X942799Y161200D02*
Y174200D01*
G01X940499Y184050D02*
Y194050D01*
G01X947499D02*
Y184050D01*
G01Y189050D02*
X940499D01*
G01X950932Y184050D02*
Y194050D01*
X954266D01*
X955599Y193550D01*
X956599Y192883D01*
X957432Y191883D01*
X958099Y190716D01*
X958266Y189050D01*
X958099Y187383D01*
X957432Y186217D01*
X956599Y185216D01*
X955599Y184550D01*
X954266Y184050D01*
X950932D01*
G01X961532D02*
Y194050D01*
X964866D01*
X966199Y193550D01*
X967199Y192883D01*
X968032Y191883D01*
X968699Y190716D01*
X968866Y189050D01*
X968699Y187383D01*
X968032Y186217D01*
X967199Y185216D01*
X966199Y184550D01*
X964866Y184050D01*
X961532D01*
G01X977799D02*
Y194050D01*
X971632Y186883D01*
X979966D01*
G01X981399Y180717D02*
X991399D01*
G01X993666Y194050D02*
Y184050D01*
X1000332D01*
G01X1010932D02*
X1004266D01*
Y194050D01*
X1010932D01*
G01X1008266Y189217D02*
X1004266D01*
G01X1014532Y184050D02*
Y194050D01*
X1017866D01*
X1019199Y193550D01*
X1020199Y192883D01*
X1021032Y191883D01*
X1021699Y190716D01*
X1021866Y189050D01*
X1021699Y187383D01*
X1021032Y186217D01*
X1020199Y185216D01*
X1019199Y184550D01*
X1017866Y184050D01*
X1014532D01*
G01X937265Y283650D02*
X947265D01*
G01Y276650D02*
X937265D01*
G01X942265D02*
Y283650D01*
G01X937265Y273217D02*
X947265D01*
Y269883D01*
X946765Y268550D01*
X946098Y267550D01*
X945098Y266717D01*
X943931Y266050D01*
X942265Y265883D01*
X940598Y266050D01*
X939432Y266717D01*
X938431Y267550D01*
X937765Y268550D01*
X937265Y269883D01*
Y273217D01*
G01Y262617D02*
X947265D01*
Y259283D01*
X946765Y257950D01*
X946098Y256950D01*
X945098Y256117D01*
X943931Y255450D01*
X942265Y255283D01*
X940598Y255450D01*
X939432Y256117D01*
X938431Y256950D01*
X937765Y257950D01*
X937265Y259283D01*
Y262617D01*
G01Y246350D02*
X947265D01*
X940098Y252517D01*
Y244183D01*
G01X931725Y558099D02*
X931683Y557766D01*
X931517Y557474D01*
X931267Y557224D01*
X930975Y557057D01*
X930642Y556974D01*
X930308D01*
X929975Y557057D01*
X929683Y557224D01*
X929433Y557474D01*
X929267Y557766D01*
X929225Y558099D01*
X929267Y558432D01*
X929433Y558724D01*
X929683Y558974D01*
X929975Y559141D01*
X930308Y559224D01*
X930642D01*
X930975Y559141D01*
X931267Y558974D01*
X931517Y558724D01*
X931683Y558432D01*
X931725Y558099D01*
G01X931058Y558432D02*
X931725Y558932D01*
G01X931225Y560282D02*
X931517Y560532D01*
X931683Y560866D01*
X931725Y561241D01*
X931683Y561574D01*
X931475Y561907D01*
X931225Y562116D01*
X930975Y562157D01*
X930683Y562074D01*
X930475Y561782D01*
X930392Y561491D01*
Y561116D01*
G01Y561491D02*
X930267Y561741D01*
X930058Y561949D01*
X929808Y562032D01*
X929558Y561949D01*
X929350Y561741D01*
X929225Y561366D01*
X929267Y560991D01*
X929433Y560616D01*
G01X931725Y564216D02*
X931183Y564299D01*
X930725Y564424D01*
X930308Y564591D01*
X929850Y564799D01*
X929225Y565132D01*
Y563466D01*
G01X941765Y689750D02*
X951765D01*
G01Y682750D02*
X941765D01*
G01X946765D02*
Y689750D01*
G01X941765Y679317D02*
X951765D01*
Y675983D01*
X951265Y674650D01*
X950598Y673650D01*
X949598Y672817D01*
X948431Y672150D01*
X946765Y671983D01*
X945098Y672150D01*
X943932Y672817D01*
X942931Y673650D01*
X942265Y674650D01*
X941765Y675983D01*
Y679317D01*
G01Y668717D02*
X951765D01*
Y665383D01*
X951265Y664050D01*
X950598Y663050D01*
X949598Y662217D01*
X948431Y661550D01*
X946765Y661383D01*
X945098Y661550D01*
X943932Y662217D01*
X942931Y663050D01*
X942265Y664050D01*
X941765Y665383D01*
Y668717D01*
G01X943765Y658117D02*
X942598Y657117D01*
X941932Y655784D01*
X941765Y654283D01*
X941932Y652950D01*
X942765Y651617D01*
X943765Y650783D01*
X944765Y650617D01*
X945931Y650950D01*
X946765Y652117D01*
X947098Y653283D01*
Y654783D01*
G01Y653283D02*
X947598Y652283D01*
X948431Y651450D01*
X949432Y651117D01*
X950432Y651450D01*
X951265Y652283D01*
X951765Y653783D01*
X951598Y655283D01*
X950932Y656783D01*
G01X934167Y674038D02*
X934375Y674371D01*
X934500Y674746D01*
Y675080D01*
X934375Y675413D01*
X934167Y675663D01*
X933875Y675788D01*
X933583Y675705D01*
X933333Y675496D01*
X933167Y675121D01*
X933083Y674621D01*
X932917Y674330D01*
X932625Y674205D01*
X932333Y674288D01*
X932125Y674496D01*
X932000Y674788D01*
Y675080D01*
X932083Y675371D01*
X932292Y675621D01*
G01X934500Y677096D02*
X932000D01*
G01Y678680D02*
X933542Y677096D01*
G01X934500Y678930D02*
X932833Y677805D01*
G01X932000Y681113D02*
X934500D01*
G01X932000Y680155D02*
Y682071D01*
G01X934500Y684713D02*
X932000D01*
X933792Y683171D01*
Y685255D01*
G01X944265Y1092350D02*
X954265D01*
G01Y1085350D02*
X944265D01*
G01X949265D02*
Y1092350D01*
G01X944265Y1081917D02*
X954265D01*
Y1078583D01*
X953765Y1077250D01*
X953098Y1076250D01*
X952098Y1075417D01*
X950931Y1074750D01*
X949265Y1074583D01*
X947598Y1074750D01*
X946432Y1075417D01*
X945431Y1076250D01*
X944765Y1077250D01*
X944265Y1078583D01*
Y1081917D01*
G01Y1071317D02*
X954265D01*
Y1067983D01*
X953765Y1066650D01*
X953098Y1065650D01*
X952098Y1064817D01*
X950931Y1064150D01*
X949265Y1063983D01*
X947598Y1064150D01*
X946432Y1064817D01*
X945431Y1065650D01*
X944765Y1066650D01*
X944265Y1067983D01*
Y1071317D01*
G01X952598Y1060217D02*
X953598Y1059217D01*
X954098Y1058050D01*
X954265Y1056717D01*
X953932Y1055050D01*
X953098Y1053883D01*
X952098Y1053550D01*
X951098Y1053717D01*
X950265Y1054383D01*
X948598Y1057717D01*
X947432Y1059217D01*
X945765Y1060217D01*
X944265Y1060550D01*
Y1053550D01*
G01X934667Y1072038D02*
X934875Y1072371D01*
X935000Y1072746D01*
Y1073080D01*
X934875Y1073413D01*
X934667Y1073663D01*
X934375Y1073788D01*
X934083Y1073705D01*
X933833Y1073496D01*
X933667Y1073121D01*
X933583Y1072621D01*
X933417Y1072330D01*
X933125Y1072205D01*
X932833Y1072288D01*
X932625Y1072496D01*
X932500Y1072788D01*
Y1073080D01*
X932583Y1073371D01*
X932792Y1073621D01*
G01X935000Y1075096D02*
X932500D01*
G01Y1076680D02*
X934042Y1075096D01*
G01X935000Y1076930D02*
X933333Y1075805D01*
G01X932500Y1079113D02*
X935000D01*
G01X932500Y1078155D02*
Y1080071D01*
G01X934500Y1081296D02*
X934792Y1081546D01*
X934958Y1081880D01*
X935000Y1082255D01*
X934958Y1082588D01*
X934750Y1082921D01*
X934500Y1083130D01*
X934250Y1083171D01*
X933958Y1083088D01*
X933750Y1082796D01*
X933667Y1082505D01*
Y1082130D01*
G01Y1082505D02*
X933542Y1082755D01*
X933333Y1082963D01*
X933083Y1083046D01*
X932833Y1082963D01*
X932625Y1082755D01*
X932500Y1082380D01*
X932542Y1082005D01*
X932708Y1081630D01*
G01X932667Y1451975D02*
X932875Y1452308D01*
X933000Y1452683D01*
Y1453017D01*
X932875Y1453350D01*
X932667Y1453600D01*
X932375Y1453725D01*
X932083Y1453642D01*
X931833Y1453433D01*
X931667Y1453058D01*
X931583Y1452558D01*
X931417Y1452267D01*
X931125Y1452142D01*
X930833Y1452225D01*
X930625Y1452433D01*
X930500Y1452725D01*
Y1453017D01*
X930583Y1453308D01*
X930792Y1453558D01*
G01X933000Y1455033D02*
X930500D01*
G01Y1456617D02*
X932042Y1455033D01*
G01X933000Y1456867D02*
X931333Y1455742D01*
G01X930500Y1459050D02*
X933000D01*
G01X930500Y1458092D02*
Y1460008D01*
G01X930917Y1461358D02*
X930667Y1461608D01*
X930542Y1461900D01*
X930500Y1462233D01*
X930583Y1462650D01*
X930792Y1462942D01*
X931042Y1463025D01*
X931292Y1462983D01*
X931500Y1462817D01*
X931917Y1461983D01*
X932208Y1461608D01*
X932625Y1461358D01*
X933000Y1461275D01*
Y1463025D01*
G01X954700Y1482900D02*
X949200D01*
G01X937100D02*
Y1490900D01*
G01X942600Y1482900D02*
X937100D01*
G01X954800Y1473500D02*
X949300D01*
G01Y1481500D02*
X954800D01*
G01X937200D02*
X942700D01*
G01X937200Y1473500D02*
Y1481500D01*
G01X942700Y1473500D02*
X937200D01*
G01X937000Y1544500D02*
X947000D01*
G01Y1537500D02*
X937000D01*
G01X942000D02*
Y1544500D01*
G01X937000Y1534067D02*
X947000D01*
Y1530733D01*
X946500Y1529400D01*
X945833Y1528400D01*
X944833Y1527567D01*
X943666Y1526900D01*
X942000Y1526733D01*
X940333Y1526900D01*
X939167Y1527567D01*
X938166Y1528400D01*
X937500Y1529400D01*
X937000Y1530733D01*
Y1534067D01*
G01Y1523467D02*
X947000D01*
Y1520133D01*
X946500Y1518800D01*
X945833Y1517800D01*
X944833Y1516967D01*
X943666Y1516300D01*
X942000Y1516133D01*
X940333Y1516300D01*
X939167Y1516967D01*
X938166Y1517800D01*
X937500Y1518800D01*
X937000Y1520133D01*
Y1523467D01*
G01Y1509200D02*
X947000D01*
X945000Y1511200D01*
G01X937000D02*
Y1507200D01*
G01X949200Y1490900D02*
X954700D01*
G01X937100D02*
X942600D01*
G01X950767Y1661292D02*
X950517Y1661417D01*
X950225Y1661500D01*
X949892D01*
X949517Y1661375D01*
X949225Y1661167D01*
X949017Y1660917D01*
X948850Y1660500D01*
X948808Y1660125D01*
X948892Y1659750D01*
X949017Y1659500D01*
X949267Y1659250D01*
X949558Y1659083D01*
X949850Y1659000D01*
X950142D01*
X950433Y1659083D01*
X950683Y1659208D01*
X950892Y1659375D01*
G01X952033Y1659500D02*
X952283Y1659208D01*
X952617Y1659042D01*
X952992Y1659000D01*
X953325Y1659042D01*
X953658Y1659250D01*
X953867Y1659500D01*
X953908Y1659750D01*
X953825Y1660042D01*
X953533Y1660250D01*
X953242Y1660333D01*
X952867D01*
G01X953242D02*
X953492Y1660458D01*
X953700Y1660667D01*
X953783Y1660917D01*
X953700Y1661167D01*
X953492Y1661375D01*
X953117Y1661500D01*
X952742Y1661458D01*
X952367Y1661292D01*
G01X955133Y1659375D02*
X955383Y1659167D01*
X955675Y1659042D01*
X956050Y1659000D01*
X956425Y1659083D01*
X956717Y1659250D01*
X956925Y1659542D01*
X956967Y1659875D01*
X956883Y1660208D01*
X956675Y1660417D01*
X956383Y1660583D01*
X956092Y1660625D01*
X955800Y1660583D01*
X955425Y1660417D01*
X955550Y1661500D01*
X956675D01*
G01X958233Y1659375D02*
X958483Y1659167D01*
X958775Y1659042D01*
X959150Y1659000D01*
X959525Y1659083D01*
X959817Y1659250D01*
X960025Y1659542D01*
X960067Y1659875D01*
X959983Y1660208D01*
X959775Y1660417D01*
X959483Y1660583D01*
X959192Y1660625D01*
X958900Y1660583D01*
X958525Y1660417D01*
X958650Y1661500D01*
X959775D01*
G01X950767Y1665292D02*
X950517Y1665417D01*
X950225Y1665500D01*
X949892D01*
X949517Y1665375D01*
X949225Y1665167D01*
X949017Y1664917D01*
X948850Y1664500D01*
X948808Y1664125D01*
X948892Y1663750D01*
X949017Y1663500D01*
X949267Y1663250D01*
X949558Y1663083D01*
X949850Y1663000D01*
X950142D01*
X950433Y1663083D01*
X950683Y1663208D01*
X950892Y1663375D01*
G01X952033Y1663500D02*
X952283Y1663208D01*
X952617Y1663042D01*
X952992Y1663000D01*
X953325Y1663042D01*
X953658Y1663250D01*
X953867Y1663500D01*
X953908Y1663750D01*
X953825Y1664042D01*
X953533Y1664250D01*
X953242Y1664333D01*
X952867D01*
G01X953242D02*
X953492Y1664458D01*
X953700Y1664667D01*
X953783Y1664917D01*
X953700Y1665167D01*
X953492Y1665375D01*
X953117Y1665500D01*
X952742Y1665458D01*
X952367Y1665292D01*
G01X955133Y1663375D02*
X955383Y1663167D01*
X955675Y1663042D01*
X956050Y1663000D01*
X956425Y1663083D01*
X956717Y1663250D01*
X956925Y1663542D01*
X956967Y1663875D01*
X956883Y1664208D01*
X956675Y1664417D01*
X956383Y1664583D01*
X956092Y1664625D01*
X955800Y1664583D01*
X955425Y1664417D01*
X955550Y1665500D01*
X956675D01*
G01X958358Y1664042D02*
X958650Y1664333D01*
X958900Y1664500D01*
X959233Y1664583D01*
X959525Y1664500D01*
X959733Y1664333D01*
X959900Y1664083D01*
X959942Y1663792D01*
X959900Y1663542D01*
X959733Y1663292D01*
X959483Y1663083D01*
X959192Y1663000D01*
X958858Y1663083D01*
X958567Y1663333D01*
X958400Y1663708D01*
X958358Y1664125D01*
X958442Y1664667D01*
X958567Y1664958D01*
X958775Y1665250D01*
X959067Y1665458D01*
X959358Y1665500D01*
X959650Y1665417D01*
X959858Y1665208D01*
G01X934667Y1885038D02*
X934875Y1885371D01*
X935000Y1885746D01*
Y1886080D01*
X934875Y1886413D01*
X934667Y1886663D01*
X934375Y1886788D01*
X934083Y1886705D01*
X933833Y1886496D01*
X933667Y1886121D01*
X933583Y1885621D01*
X933417Y1885330D01*
X933125Y1885205D01*
X932833Y1885288D01*
X932625Y1885496D01*
X932500Y1885788D01*
Y1886080D01*
X932583Y1886371D01*
X932792Y1886621D01*
G01X935000Y1888096D02*
X932500D01*
G01Y1889680D02*
X934042Y1888096D01*
G01X935000Y1889930D02*
X933333Y1888805D01*
G01X932500Y1892113D02*
X935000D01*
G01X932500Y1891155D02*
Y1893071D01*
G01X935000Y1895213D02*
X932500D01*
X933000Y1894713D01*
G01X935000D02*
Y1895713D01*
G01X942431Y1951450D02*
X952431D01*
G01Y1944450D02*
X942431D01*
G01X947431D02*
Y1951450D01*
G01X942431Y1941017D02*
X952431D01*
Y1937683D01*
X951931Y1936350D01*
X951264Y1935350D01*
X950264Y1934517D01*
X949097Y1933850D01*
X947431Y1933683D01*
X945764Y1933850D01*
X944598Y1934517D01*
X943597Y1935350D01*
X942931Y1936350D01*
X942431Y1937683D01*
Y1941017D01*
G01Y1930417D02*
X952431D01*
Y1927083D01*
X951931Y1925750D01*
X951264Y1924750D01*
X950264Y1923917D01*
X949097Y1923250D01*
X947431Y1923083D01*
X945764Y1923250D01*
X944598Y1923917D01*
X943597Y1924750D01*
X942931Y1925750D01*
X942431Y1927083D01*
Y1930417D01*
G01X952431Y1916150D02*
X952098Y1917484D01*
X951264Y1918483D01*
X950264Y1919150D01*
X948931Y1919650D01*
X947431Y1919817D01*
X945931Y1919650D01*
X944598Y1919150D01*
X943597Y1918483D01*
X942764Y1917484D01*
X942431Y1916150D01*
X942764Y1914817D01*
X943597Y1913817D01*
X944598Y1913150D01*
X945931Y1912650D01*
X947431Y1912483D01*
X948931Y1912650D01*
X950264Y1913150D01*
X951264Y1913817D01*
X952098Y1914817D01*
X952431Y1916150D01*
G01X966567Y53500D02*
Y56000D01*
X967567D01*
X967900Y55875D01*
X968150Y55583D01*
X968233Y55250D01*
X968150Y54917D01*
X967942Y54667D01*
X967567Y54542D01*
X966567D01*
G01X971417Y55792D02*
X971167Y55917D01*
X970875Y56000D01*
X970542D01*
X970167Y55875D01*
X969875Y55667D01*
X969667Y55417D01*
X969500Y55000D01*
X969458Y54625D01*
X969542Y54250D01*
X969667Y54000D01*
X969917Y53750D01*
X970208Y53583D01*
X970500Y53500D01*
X970792D01*
X971083Y53583D01*
X971333Y53708D01*
X971542Y53875D01*
G01X973600Y53500D02*
Y56000D01*
X973100Y55500D01*
G01Y53500D02*
X974100D01*
G01X966567Y57500D02*
Y60000D01*
X967567D01*
X967900Y59875D01*
X968150Y59583D01*
X968233Y59250D01*
X968150Y58917D01*
X967942Y58667D01*
X967567Y58542D01*
X966567D01*
G01X971417Y59792D02*
X971167Y59917D01*
X970875Y60000D01*
X970542D01*
X970167Y59875D01*
X969875Y59667D01*
X969667Y59417D01*
X969500Y59000D01*
X969458Y58625D01*
X969542Y58250D01*
X969667Y58000D01*
X969917Y57750D01*
X970208Y57583D01*
X970500Y57500D01*
X970792D01*
X971083Y57583D01*
X971333Y57708D01*
X971542Y57875D01*
G01X972808Y59583D02*
X973058Y59833D01*
X973350Y59958D01*
X973683Y60000D01*
X974100Y59917D01*
X974392Y59708D01*
X974475Y59458D01*
X974433Y59208D01*
X974267Y59000D01*
X973433Y58583D01*
X973058Y58292D01*
X972808Y57875D01*
X972725Y57500D01*
X974475D01*
G01X966567Y61500D02*
Y64000D01*
X967567D01*
X967900Y63875D01*
X968150Y63583D01*
X968233Y63250D01*
X968150Y62917D01*
X967942Y62667D01*
X967567Y62542D01*
X966567D01*
G01X971417Y63792D02*
X971167Y63917D01*
X970875Y64000D01*
X970542D01*
X970167Y63875D01*
X969875Y63667D01*
X969667Y63417D01*
X969500Y63000D01*
X969458Y62625D01*
X969542Y62250D01*
X969667Y62000D01*
X969917Y61750D01*
X970208Y61583D01*
X970500Y61500D01*
X970792D01*
X971083Y61583D01*
X971333Y61708D01*
X971542Y61875D01*
G01X972683Y62000D02*
X972933Y61708D01*
X973267Y61542D01*
X973642Y61500D01*
X973975Y61542D01*
X974308Y61750D01*
X974517Y62000D01*
X974558Y62250D01*
X974475Y62542D01*
X974183Y62750D01*
X973892Y62833D01*
X973517D01*
G01X973892D02*
X974142Y62958D01*
X974350Y63167D01*
X974433Y63417D01*
X974350Y63667D01*
X974142Y63875D01*
X973767Y64000D01*
X973392Y63958D01*
X973017Y63792D01*
G01X966567Y65500D02*
Y68000D01*
X967567D01*
X967900Y67875D01*
X968150Y67583D01*
X968233Y67250D01*
X968150Y66917D01*
X967942Y66667D01*
X967567Y66542D01*
X966567D01*
G01X971417Y67792D02*
X971167Y67917D01*
X970875Y68000D01*
X970542D01*
X970167Y67875D01*
X969875Y67667D01*
X969667Y67417D01*
X969500Y67000D01*
X969458Y66625D01*
X969542Y66250D01*
X969667Y66000D01*
X969917Y65750D01*
X970208Y65583D01*
X970500Y65500D01*
X970792D01*
X971083Y65583D01*
X971333Y65708D01*
X971542Y65875D01*
G01X974100Y65500D02*
Y68000D01*
X972558Y66208D01*
X974642D01*
G01X966567Y69500D02*
Y72000D01*
X967567D01*
X967900Y71875D01*
X968150Y71583D01*
X968233Y71250D01*
X968150Y70917D01*
X967942Y70667D01*
X967567Y70542D01*
X966567D01*
G01X971417Y71792D02*
X971167Y71917D01*
X970875Y72000D01*
X970542D01*
X970167Y71875D01*
X969875Y71667D01*
X969667Y71417D01*
X969500Y71000D01*
X969458Y70625D01*
X969542Y70250D01*
X969667Y70000D01*
X969917Y69750D01*
X970208Y69583D01*
X970500Y69500D01*
X970792D01*
X971083Y69583D01*
X971333Y69708D01*
X971542Y69875D01*
G01X972683D02*
X972933Y69667D01*
X973225Y69542D01*
X973600Y69500D01*
X973975Y69583D01*
X974267Y69750D01*
X974475Y70042D01*
X974517Y70375D01*
X974433Y70708D01*
X974225Y70917D01*
X973933Y71083D01*
X973642Y71125D01*
X973350Y71083D01*
X972975Y70917D01*
X973100Y72000D01*
X974225D01*
G01X968089Y94290D02*
Y96790D01*
X969089D01*
X969422Y96665D01*
X969672Y96373D01*
X969755Y96040D01*
X969672Y95707D01*
X969464Y95457D01*
X969089Y95332D01*
X968089D01*
G01X972939Y96582D02*
X972689Y96707D01*
X972397Y96790D01*
X972064D01*
X971689Y96665D01*
X971397Y96457D01*
X971189Y96207D01*
X971022Y95790D01*
X970980Y95415D01*
X971064Y95040D01*
X971189Y94790D01*
X971439Y94540D01*
X971730Y94373D01*
X972022Y94290D01*
X972314D01*
X972605Y94373D01*
X972855Y94498D01*
X973064Y94665D01*
G01X975122Y94290D02*
Y96790D01*
X974622Y96290D01*
G01Y94290D02*
X975622D01*
G01X978222Y96790D02*
X977889Y96707D01*
X977639Y96498D01*
X977472Y96248D01*
X977347Y95915D01*
X977305Y95540D01*
X977347Y95165D01*
X977472Y94832D01*
X977639Y94582D01*
X977889Y94373D01*
X978222Y94290D01*
X978555Y94373D01*
X978805Y94582D01*
X978972Y94832D01*
X979097Y95165D01*
X979139Y95540D01*
X979097Y95915D01*
X978972Y96248D01*
X978805Y96498D01*
X978555Y96707D01*
X978222Y96790D01*
G01X962566Y88550D02*
Y91050D01*
X963566D01*
X963899Y90925D01*
X964149Y90633D01*
X964232Y90300D01*
X964149Y89967D01*
X963941Y89717D01*
X963566Y89592D01*
X962566D01*
G01X965666Y88550D02*
Y91050D01*
X966707D01*
X967041Y90925D01*
X967249Y90758D01*
X967332Y90425D01*
X967249Y90092D01*
X966999Y89883D01*
X966707Y89758D01*
X965666D01*
G01X966707D02*
X967332Y88550D01*
G01X969599D02*
Y91050D01*
X969099Y90550D01*
G01Y88550D02*
X970099D01*
G01X964001Y108039D02*
X961501D01*
Y109039D01*
X961626Y109372D01*
X961918Y109622D01*
X962251Y109705D01*
X962584Y109622D01*
X962834Y109414D01*
X962959Y109039D01*
Y108039D01*
G01X964001Y111139D02*
X961501D01*
Y112180D01*
X961626Y112514D01*
X961793Y112722D01*
X962126Y112805D01*
X962459Y112722D01*
X962668Y112472D01*
X962793Y112180D01*
Y111139D01*
G01Y112180D02*
X964001Y112805D01*
G01Y115072D02*
X961501D01*
X962001Y114572D01*
G01X964001D02*
Y115572D01*
G01X961501Y118172D02*
X961584Y117839D01*
X961793Y117589D01*
X962043Y117422D01*
X962376Y117297D01*
X962751Y117255D01*
X963126Y117297D01*
X963459Y117422D01*
X963709Y117589D01*
X963918Y117839D01*
X964001Y118172D01*
X963918Y118505D01*
X963709Y118755D01*
X963459Y118922D01*
X963126Y119047D01*
X962751Y119089D01*
X962376Y119047D01*
X962043Y118922D01*
X961793Y118755D01*
X961584Y118505D01*
X961501Y118172D01*
G01X950499Y106350D02*
X954499D01*
Y113750D01*
G01X960001Y108039D02*
X957501D01*
Y109039D01*
X957626Y109372D01*
X957918Y109622D01*
X958251Y109705D01*
X958584Y109622D01*
X958834Y109414D01*
X958959Y109039D01*
Y108039D01*
G01X960001Y111139D02*
X957501D01*
Y112180D01*
X957626Y112514D01*
X957793Y112722D01*
X958126Y112805D01*
X958459Y112722D01*
X958668Y112472D01*
X958793Y112180D01*
Y111139D01*
G01Y112180D02*
X960001Y112805D01*
G01Y115072D02*
X957501D01*
X958001Y114572D01*
G01X960001D02*
Y115572D01*
G01X959501Y117255D02*
X959793Y117505D01*
X959959Y117839D01*
X960001Y118214D01*
X959959Y118547D01*
X959751Y118880D01*
X959501Y119089D01*
X959251Y119130D01*
X958959Y119047D01*
X958751Y118755D01*
X958668Y118464D01*
Y118089D01*
G01Y118464D02*
X958543Y118714D01*
X958334Y118922D01*
X958084Y119005D01*
X957834Y118922D01*
X957626Y118714D01*
X957501Y118339D01*
X957543Y117964D01*
X957709Y117589D01*
G01X968001Y108089D02*
X965501D01*
Y109089D01*
X965626Y109422D01*
X965918Y109672D01*
X966251Y109755D01*
X966584Y109672D01*
X966834Y109464D01*
X966959Y109089D01*
Y108089D01*
G01X968001Y111189D02*
X965501D01*
Y112230D01*
X965626Y112564D01*
X965793Y112772D01*
X966126Y112855D01*
X966459Y112772D01*
X966668Y112522D01*
X966793Y112230D01*
Y111189D01*
G01Y112230D02*
X968001Y112855D01*
G01Y115039D02*
X967459Y115122D01*
X967001Y115247D01*
X966584Y115414D01*
X966126Y115622D01*
X965501Y115955D01*
Y114289D01*
G01X963066Y101050D02*
Y103550D01*
X964066D01*
X964399Y103425D01*
X964649Y103133D01*
X964732Y102800D01*
X964649Y102467D01*
X964441Y102217D01*
X964066Y102092D01*
X963066D01*
G01X967916Y103342D02*
X967666Y103467D01*
X967374Y103550D01*
X967041D01*
X966666Y103425D01*
X966374Y103217D01*
X966166Y102967D01*
X965999Y102550D01*
X965957Y102175D01*
X966041Y101800D01*
X966166Y101550D01*
X966416Y101300D01*
X966707Y101133D01*
X966999Y101050D01*
X967291D01*
X967582Y101133D01*
X967832Y101258D01*
X968041Y101425D01*
G01X969307Y102092D02*
X969599Y102383D01*
X969849Y102550D01*
X970182Y102633D01*
X970474Y102550D01*
X970682Y102383D01*
X970849Y102133D01*
X970891Y101842D01*
X970849Y101592D01*
X970682Y101342D01*
X970432Y101133D01*
X970141Y101050D01*
X969807Y101133D01*
X969516Y101383D01*
X969349Y101758D01*
X969307Y102175D01*
X969391Y102717D01*
X969516Y103008D01*
X969724Y103300D01*
X970016Y103508D01*
X970307Y103550D01*
X970599Y103467D01*
X970807Y103258D01*
G01X959267Y1487692D02*
X959017Y1487817D01*
X958725Y1487900D01*
X958392D01*
X958017Y1487775D01*
X957725Y1487567D01*
X957517Y1487317D01*
X957350Y1486900D01*
X957308Y1486525D01*
X957392Y1486150D01*
X957517Y1485900D01*
X957767Y1485650D01*
X958058Y1485483D01*
X958350Y1485400D01*
X958642D01*
X958933Y1485483D01*
X959183Y1485608D01*
X959392Y1485775D01*
G01X960533Y1485900D02*
X960783Y1485608D01*
X961117Y1485442D01*
X961492Y1485400D01*
X961825Y1485442D01*
X962158Y1485650D01*
X962367Y1485900D01*
X962408Y1486150D01*
X962325Y1486442D01*
X962033Y1486650D01*
X961742Y1486733D01*
X961367D01*
G01X961742D02*
X961992Y1486858D01*
X962200Y1487067D01*
X962283Y1487317D01*
X962200Y1487567D01*
X961992Y1487775D01*
X961617Y1487900D01*
X961242Y1487858D01*
X960867Y1487692D01*
G01X965050Y1485400D02*
Y1487900D01*
X963508Y1486108D01*
X965592D01*
G01X967650Y1485400D02*
X967942Y1485442D01*
X968275Y1485567D01*
X968483Y1485775D01*
X968567Y1486067D01*
X968483Y1486358D01*
X968233Y1486608D01*
X967858Y1486733D01*
X967442D01*
X967192Y1486817D01*
X966983Y1487025D01*
X966900Y1487317D01*
X967025Y1487608D01*
X967317Y1487817D01*
X967650Y1487900D01*
X967983Y1487817D01*
X968275Y1487608D01*
X968400Y1487317D01*
X968317Y1487025D01*
X968108Y1486817D01*
X967858Y1486733D01*
X967442D01*
X967067Y1486608D01*
X966817Y1486358D01*
X966733Y1486067D01*
X966817Y1485775D01*
X967025Y1485567D01*
X967358Y1485442D01*
X967650Y1485400D01*
G01X954700Y1490900D02*
Y1482900D01*
G01X959367Y1478292D02*
X959117Y1478417D01*
X958825Y1478500D01*
X958492D01*
X958117Y1478375D01*
X957825Y1478167D01*
X957617Y1477917D01*
X957450Y1477500D01*
X957408Y1477125D01*
X957492Y1476750D01*
X957617Y1476500D01*
X957867Y1476250D01*
X958158Y1476083D01*
X958450Y1476000D01*
X958742D01*
X959033Y1476083D01*
X959283Y1476208D01*
X959492Y1476375D01*
G01X960633Y1476500D02*
X960883Y1476208D01*
X961217Y1476042D01*
X961592Y1476000D01*
X961925Y1476042D01*
X962258Y1476250D01*
X962467Y1476500D01*
X962508Y1476750D01*
X962425Y1477042D01*
X962133Y1477250D01*
X961842Y1477333D01*
X961467D01*
G01X961842D02*
X962092Y1477458D01*
X962300Y1477667D01*
X962383Y1477917D01*
X962300Y1478167D01*
X962092Y1478375D01*
X961717Y1478500D01*
X961342Y1478458D01*
X960967Y1478292D01*
G01X965150Y1476000D02*
Y1478500D01*
X963608Y1476708D01*
X965692D01*
G01X967042Y1476292D02*
X967333Y1476083D01*
X967667Y1476000D01*
X968000Y1476083D01*
X968292Y1476333D01*
X968500Y1476708D01*
X968583Y1477083D01*
Y1477542D01*
X968500Y1477917D01*
X968292Y1478250D01*
X968042Y1478417D01*
X967750Y1478500D01*
X967417Y1478417D01*
X967167Y1478250D01*
X967000Y1478000D01*
X966917Y1477667D01*
X967000Y1477375D01*
X967208Y1477083D01*
X967458Y1476917D01*
X967750Y1476875D01*
X968083Y1476958D01*
X968333Y1477167D01*
X968583Y1477542D01*
G01X954800Y1481500D02*
Y1473500D01*
G01X964817Y1610792D02*
X964567Y1610917D01*
X964275Y1611000D01*
X963942D01*
X963567Y1610875D01*
X963275Y1610667D01*
X963067Y1610417D01*
X962900Y1610000D01*
X962858Y1609625D01*
X962942Y1609250D01*
X963067Y1609000D01*
X963317Y1608750D01*
X963608Y1608583D01*
X963900Y1608500D01*
X964192D01*
X964483Y1608583D01*
X964733Y1608708D01*
X964942Y1608875D01*
G01X966042Y1608500D02*
Y1611000D01*
X967958Y1608500D01*
Y1611000D01*
G01X970017Y1608500D02*
X970100Y1609042D01*
X970225Y1609500D01*
X970392Y1609917D01*
X970600Y1610375D01*
X970933Y1611000D01*
X969267D01*
G01X990118Y171593D02*
Y174093D01*
G01X991868D02*
Y171593D01*
G01Y172843D02*
X990118D01*
G01X994093Y171593D02*
Y174093D01*
X993593Y173593D01*
G01Y171593D02*
X994593D01*
G01X996401Y172635D02*
X996693Y172926D01*
X996943Y173093D01*
X997276Y173176D01*
X997568Y173093D01*
X997776Y172926D01*
X997943Y172676D01*
X997985Y172385D01*
X997943Y172135D01*
X997776Y171885D01*
X997526Y171676D01*
X997235Y171593D01*
X996901Y171676D01*
X996610Y171926D01*
X996443Y172301D01*
X996401Y172718D01*
X996485Y173260D01*
X996610Y173551D01*
X996818Y173843D01*
X997110Y174051D01*
X997401Y174093D01*
X997693Y174010D01*
X997901Y173801D01*
G01X990118Y695215D02*
Y697715D01*
G01X991868D02*
Y695215D01*
G01Y696465D02*
X990118D01*
G01X994093Y695215D02*
Y697715D01*
X993593Y697215D01*
G01Y695215D02*
X994593D01*
G01X996276Y695590D02*
X996526Y695382D01*
X996818Y695257D01*
X997193Y695215D01*
X997568Y695298D01*
X997860Y695465D01*
X998068Y695757D01*
X998110Y696090D01*
X998026Y696423D01*
X997818Y696632D01*
X997526Y696798D01*
X997235Y696840D01*
X996943Y696798D01*
X996568Y696632D01*
X996693Y697715D01*
X997818D01*
G01X985025Y1089000D02*
Y1091500D01*
G01X986775D02*
Y1089000D01*
G01Y1090250D02*
X985025D01*
G01X989000Y1089000D02*
Y1091500D01*
X988500Y1091000D01*
G01Y1089000D02*
X989500D01*
G01X992600D02*
Y1091500D01*
X991058Y1089708D01*
X993142D01*
G01X1033464Y1400276D02*
Y1424882D01*
X1029527Y1428819D01*
X1024212D01*
G02X1019291Y1433740I0J4921D01*
G01Y1610886D01*
X1018307Y1611870D01*
X989744D01*
G02Y1616082I0J2106D01*
G01X1018307D01*
X1019291Y1617066D01*
Y1676496D01*
G02X1024212Y1681417I4921J0D01*
G01X1029527D01*
X1033464Y1685354D01*
Y1709976D01*
X1003491D01*
Y1678726D01*
X990691D01*
Y1617076D01*
X986591D01*
Y1611876D01*
X976891D01*
Y1432676D01*
X1003491D01*
Y1400276D01*
X1033464D01*
G01X987635Y1909076D02*
Y1913076D01*
G01X990435D02*
Y1909076D01*
G01Y1911076D02*
X987635D01*
G01X993635Y1909076D02*
Y1913076D01*
X992835Y1912276D01*
G01Y1909076D02*
X994435D01*
G01X998235D02*
Y1913076D01*
X997435Y1912276D01*
G01Y1909076D02*
X999035D01*
G01X1038542Y1546026D02*
X1038875Y1546559D01*
X1039075Y1547159D01*
Y1547693D01*
X1038875Y1548226D01*
X1038542Y1548626D01*
X1038075Y1548826D01*
X1037608Y1548693D01*
X1037208Y1548359D01*
X1036942Y1547759D01*
X1036808Y1546959D01*
X1036542Y1546493D01*
X1036075Y1546293D01*
X1035608Y1546426D01*
X1035275Y1546759D01*
X1035075Y1547226D01*
Y1547693D01*
X1035208Y1548159D01*
X1035542Y1548559D01*
G01X1039075Y1552026D02*
X1035075D01*
G01X1036408Y1556626D02*
X1039075D01*
G01X1035342D02*
X1035275Y1556493D01*
X1035142D01*
X1035075Y1556626D01*
X1035142Y1556759D01*
X1035275D01*
X1035342Y1556626D01*
G01X1035075Y1561226D02*
X1039075D01*
G01X1036408Y1560293D02*
Y1562159D01*
G01X1106972Y471923D02*
X1107439Y472389D01*
X1107839Y472656D01*
X1108372Y472789D01*
X1108839Y472656D01*
X1109172Y472389D01*
X1109439Y471989D01*
X1109506Y471523D01*
X1109439Y471123D01*
X1109172Y470723D01*
X1108772Y470389D01*
X1108306Y470256D01*
X1107772Y470389D01*
X1107306Y470789D01*
X1107039Y471389D01*
X1106972Y472056D01*
X1107106Y472923D01*
X1107306Y473389D01*
X1107639Y473856D01*
X1108106Y474189D01*
X1108572Y474256D01*
X1109039Y474123D01*
X1109372Y473789D01*
G01X1106854Y501018D02*
X1107254Y500685D01*
X1107721Y500485D01*
X1108321Y500418D01*
X1108921Y500551D01*
X1109388Y500818D01*
X1109721Y501285D01*
X1109788Y501818D01*
X1109654Y502351D01*
X1109321Y502685D01*
X1108854Y502951D01*
X1108388Y503018D01*
X1107921Y502951D01*
X1107321Y502685D01*
X1107521Y504418D01*
X1109321D01*
G01X1109566Y532365D02*
Y536365D01*
X1107099Y533498D01*
X1110433D01*
G01X1107062Y564683D02*
X1107462Y564216D01*
X1107996Y563950D01*
X1108596Y563883D01*
X1109129Y563950D01*
X1109662Y564283D01*
X1109996Y564683D01*
X1110062Y565083D01*
X1109929Y565550D01*
X1109462Y565883D01*
X1108996Y566016D01*
X1108396D01*
G01X1108996D02*
X1109396Y566216D01*
X1109729Y566550D01*
X1109862Y566950D01*
X1109729Y567350D01*
X1109396Y567683D01*
X1108796Y567883D01*
X1108196Y567816D01*
X1107596Y567550D01*
G01X1107512Y598945D02*
X1107912Y599345D01*
X1108379Y599545D01*
X1108912Y599612D01*
X1109579Y599479D01*
X1110046Y599145D01*
X1110179Y598745D01*
X1110112Y598345D01*
X1109846Y598012D01*
X1108512Y597345D01*
X1107912Y596879D01*
X1107512Y596212D01*
X1107379Y595612D01*
X1110179D01*
G01X1108141Y627159D02*
Y631159D01*
X1107341Y630359D01*
G01Y627159D02*
X1108941D01*
M02*
